(kicad_pcb
	(version 20260206)
	(generator "pcbnew")
	(generator_version "10.0")
	(general
		(thickness 1.6)
		(legacy_teardrops no)
	)
	(paper "A4")
	(layers
		(0 "F.Cu" signal "TOP")
		(4 "In1.Cu" signal "GND")
		(6 "In2.Cu" signal "IN1")
		(8 "In3.Cu" signal "VCC")
		(10 "In4.Cu" signal "VCC1")
		(12 "In5.Cu" signal "IN2")
		(14 "In6.Cu" signal "GND1")
		(2 "B.Cu" signal "BOTTOM")
		(9 "F.Adhes" user "F.Adhesive")
		(11 "B.Adhes" user "B.Adhesive")
		(13 "F.Paste" user "Package Geometry/Pastemask Top")
		(15 "B.Paste" user "Package Geometry/Pastemask Bottom")
		(5 "F.SilkS" user "Ref Des/Silkscreen Top")
		(7 "B.SilkS" user "Ref Des/Silkscreen Bottom")
		(1 "F.Mask" user "Board Geometry/Soldermask Top")
		(3 "B.Mask" user "Board Geometry/Soldermask Bottom")
		(17 "Dwgs.User" user "User.Drawings")
		(19 "Cmts.User" user "User.Comments")
		(21 "Eco1.User" user "User.Eco1")
		(23 "Eco2.User" user "User.Eco2")
		(25 "Edge.Cuts" user "Board Geometry/Outline")
		(27 "Margin" user)
		(31 "F.CrtYd" user "Package Geometry/Place Bound Top")
		(29 "B.CrtYd" user "Package Geometry/Place Bound Bottom")
		(35 "F.Fab" user "Ref Des/Assembly Top")
		(33 "B.Fab" user "Ref Des/Assembly Bottom")
	)
	(setup
		(pad_to_mask_clearance 0)
		(allow_soldermask_bridges_in_footprints no)
		(tenting
			(front yes)
			(back yes)
		)
		(covering
			(front no)
			(back no)
		)
		(plugging
			(front no)
			(back no)
		)
		(capping no)
		(filling no)
		(pcbplotparams
			(layerselection 0x00000000_00000000_55555555_5755f5ff)
			(plot_on_all_layers_selection 0x00000000_00000000_00000000_00000000)
			(disableapertmacros no)
			(usegerberextensions no)
			(usegerberattributes yes)
			(usegerberadvancedattributes yes)
			(creategerberjobfile yes)
			(dashed_line_dash_ratio 12)
			(dashed_line_gap_ratio 3)
			(svgprecision 4)
			(plotframeref no)
			(mode 1)
			(useauxorigin no)
			(pdf_front_fp_property_popups yes)
			(pdf_back_fp_property_popups yes)
			(pdf_metadata yes)
			(pdf_single_document no)
			(dxfpolygonmode yes)
			(dxfimperialunits yes)
			(dxfusepcbnewfont yes)
			(psnegative no)
			(psa4output no)
			(plot_black_and_white yes)
			(sketchpadsonfab no)
			(plotpadnumbers no)
			(hidednponfab no)
			(sketchdnponfab yes)
			(crossoutdnponfab yes)
			(subtractmaskfromsilk no)
			(outputformat 1)
			(mirror no)
			(drillshape 1)
			(scaleselection 1)
			(outputdirectory "")
		)
	)
	(footprint ""
		(layer "F.Cu")
		(at 16.599916 -384.79984)
		(property "Reference" "H6"
			(at -6.4516 -7.127748 0)
			(unlocked yes)
			(layer "F.SilkS")
			(effects
				(font
					(size 0.7874 0.5842)
					(thickness 0.1524)
				)
				(justify left)
			)
		)
		(property "Value" ""
			(at 0 0 0)
			(layer "F.Fab")
			(effects
				(font
					(size 1.27 1.27)
				)
			)
		)
		(duplicate_pad_numbers_are_jumpers no)
		(fp_circle
			(center 0 0)
			(end 7.999984 0)
			(stroke
				(width 0.1524)
				(type default)
			)
			(fill no)
			(layer "F.SilkS")
		)
		(fp_circle
			(center 0 0)
			(end 14.7066 0)
			(stroke
				(width 0.1524)
				(type default)
			)
			(fill no)
			(layer "B.SilkS")
		)
		(fp_poly
			(pts
				(arc
					(start 0 5.0038)
					(mid 0 -5.0038)
					(end 0 5.0038)
				)
			)
			(stroke
				(width 0)
				(type default)
			)
			(fill no)
			(layer "F.CrtYd")
		)
		(pad "" np_thru_hole circle
			(at 0 0)
			(size 4.0132 4.0132)
			(drill 4.0132)
			(layers "*.Cu" "*.Mask")
			(clearance 0.381)
			(thermal_gap 0.381)
		)
		(pad "2" thru_hole circle
			(at 0 -3.50012)
			(size 0.762 0.762)
			(drill 0.5588)
			(layers "*.Cu" "*.Mask")
			(remove_unused_layers no)
			(net "GND")
			(clearance 0.1524)
			(thermal_gap 0.1524)
		)
		(pad "3" thru_hole circle
			(at -2.500122 -2.500122)
			(size 0.762 0.762)
			(drill 0.5588)
			(layers "*.Cu" "*.Mask")
			(remove_unused_layers no)
			(net "GND")
			(clearance 0.1524)
			(thermal_gap 0.1524)
		)
		(pad "4" thru_hole circle
			(at -3.50012 0)
			(size 0.762 0.762)
			(drill 0.5588)
			(layers "*.Cu" "*.Mask")
			(remove_unused_layers no)
			(net "GND")
			(clearance 0.1524)
			(thermal_gap 0.1524)
		)
		(pad "5" thru_hole circle
			(at -2.500122 2.500122)
			(size 0.762 0.762)
			(drill 0.5588)
			(layers "*.Cu" "*.Mask")
			(remove_unused_layers no)
			(net "GND")
			(clearance 0.1524)
			(thermal_gap 0.1524)
		)
		(pad "6" thru_hole circle
			(at 0 3.50012)
			(size 0.762 0.762)
			(drill 0.5588)
			(layers "*.Cu" "*.Mask")
			(remove_unused_layers no)
			(net "GND")
			(clearance 0.1524)
			(thermal_gap 0.1524)
		)
		(pad "7" thru_hole circle
			(at 2.500122 2.500122)
			(size 0.762 0.762)
			(drill 0.5588)
			(layers "*.Cu" "*.Mask")
			(remove_unused_layers no)
			(net "GND")
			(clearance 0.1524)
			(thermal_gap 0.1524)
		)
		(pad "8" thru_hole circle
			(at 3.50012 0)
			(size 0.762 0.762)
			(drill 0.5588)
			(layers "*.Cu" "*.Mask")
			(remove_unused_layers no)
			(net "GND")
			(clearance 0.1524)
			(thermal_gap 0.1524)
		)
		(pad "9" thru_hole circle
			(at 2.500122 -2.500122)
			(size 0.762 0.762)
			(drill 0.5588)
			(layers "*.Cu" "*.Mask")
			(remove_unused_layers no)
			(net "GND")
			(clearance 0.1524)
			(thermal_gap 0.1524)
		)
		(zone
			(layer "F.Cu")
			(hatch none 0.5)
			(connect_pads
				(clearance 0)
			)
			(min_thickness 0.25)
			(keepout
				(tracks not_allowed)
				(vias allowed)
				(pads allowed)
				(copperpour not_allowed)
				(footprints allowed)
			)
			(placement
				(enabled no)
				(sheetname "")
			)
			(fill
				(thermal_gap 0.5)
				(thermal_bridge_width 0.5)
				(island_removal_mode 0)
			)
			(polygon
				(pts
					(arc
						(start 16.599916 -392.80084)
						(mid 8.598916 -384.79984)
						(end 16.599916 -376.79884)
					)
					(arc
						(start 16.599916 -376.79884)
						(mid 18.035016 -378.23394)
						(end 16.599916 -379.66904)
					)
					(arc
						(start 16.599916 -379.66904)
						(mid 11.469116 -384.79984)
						(end 16.599916 -389.93064)
					)
					(arc
						(start 16.599916 -389.93064)
						(mid 18.035016 -391.36574)
						(end 16.599916 -392.80084)
					)
				)
			)
		)
		(zone
			(layer "F.Cu")
			(hatch none 0.5)
			(connect_pads
				(clearance 0)
			)
			(min_thickness 0.25)
			(keepout
				(tracks not_allowed)
				(vias allowed)
				(pads allowed)
				(copperpour not_allowed)
				(footprints allowed)
			)
			(placement
				(enabled no)
				(sheetname "")
			)
			(fill
				(thermal_gap 0.5)
				(thermal_bridge_width 0.5)
				(island_removal_mode 0)
			)
			(polygon
				(pts
					(arc
						(start 16.599916 -392.80084)
						(mid 24.600916 -384.79984)
						(end 16.599916 -376.79884)
					)
					(arc
						(start 16.599916 -376.79884)
						(mid 15.164816 -378.23394)
						(end 16.599916 -379.66904)
					)
					(arc
						(start 16.599916 -379.66904)
						(mid 21.730716 -384.79984)
						(end 16.599916 -389.93064)
					)
					(arc
						(start 16.599916 -389.93064)
						(mid 15.164816 -391.36574)
						(end 16.599916 -392.80084)
					)
				)
			)
		)
		(zone
			(layers "F.Cu" "B.Cu" "In1.Cu" "In2.Cu" "In3.Cu" "In4.Cu" "In5.Cu" "In6.Cu")
			(hatch none 0.5)
			(connect_pads
				(clearance 0)
			)
			(min_thickness 0.25)
			(keepout
				(tracks not_allowed)
				(vias allowed)
				(pads allowed)
				(copperpour not_allowed)
				(footprints allowed)
			)
			(placement
				(enabled no)
				(sheetname "")
			)
			(fill
				(thermal_gap 0.5)
				(thermal_bridge_width 0.5)
				(island_removal_mode 0)
			)
			(polygon
				(pts
					(arc
						(start 16.599916 -382.28778)
						(mid 16.599916 -387.3119)
						(end 16.599916 -382.28778)
					)
				)
			)
		)
	)
	(footprint ""
		(layer "F.Cu")
		(at 66.74104 -206.29118 180)
		(property "Reference" "R120"
			(at -0.150876 -1.42875 0)
			(unlocked yes)
			(layer "F.SilkS")
			(effects
				(font
					(size 0.7874 0.5842)
					(thickness 0.1524)
				)
				(justify left)
			)
		)
		(property "Value" ""
			(at 0 0 180)
			(layer "F.Fab")
			(effects
				(font
					(size 1.27 1.27)
				)
			)
		)
		(duplicate_pad_numbers_are_jumpers no)
		(fp_line
			(start 0.7874 0.4064)
			(end -0.7874 0.4064)
			(stroke
				(width 0.1524)
				(type default)
			)
			(layer "F.SilkS")
		)
		(fp_line
			(start 0.7874 -0.4064)
			(end 0.7874 0.4064)
			(stroke
				(width 0.1524)
				(type default)
			)
			(layer "F.SilkS")
		)
		(fp_line
			(start -0.7874 0.4064)
			(end -0.7874 -0.4064)
			(stroke
				(width 0.1524)
				(type default)
			)
			(layer "F.SilkS")
		)
		(fp_line
			(start -0.7874 -0.4064)
			(end 0.7874 -0.4064)
			(stroke
				(width 0.1524)
				(type default)
			)
			(layer "F.SilkS")
		)
		(fp_poly
			(pts
				(xy -0.508 0.2794) (xy -0.508 0.2286) (xy -0.635 0.2286) (xy -0.635 -0.254) (xy -0.5334 -0.254)
				(xy -0.5334 -0.2794) (xy 0.5334 -0.2794) (xy 0.5334 -0.254) (xy 0.635 -0.254) (xy 0.635 0.254) (xy 0.5334 0.254)
				(xy 0.5334 0.2794)
			)
			(stroke
				(width 0)
				(type default)
			)
			(fill no)
			(layer "F.CrtYd")
		)
		(pad "1" smd rect
			(at 0.40005 0 180)
			(size 0.4572 0.508)
			(layers "F.Cu" "F.Mask" "F.Paste")
			(net "PSU3_REMOTE_R2_N")
		)
		(pad "2" smd rect
			(at -0.40005 0 180)
			(size 0.4572 0.508)
			(layers "F.Cu" "F.Mask" "F.Paste")
			(net "GND")
		)
	)
	(footprint ""
		(layer "F.Cu")
		(at 71.903844 -42.631106 90)
		(property "Reference" "C14"
			(at -1.201928 4.801108 90)
			(unlocked yes)
			(layer "F.SilkS")
			(effects
				(font
					(size 0.7874 0.5842)
					(thickness 0.1524)
				)
				(justify left)
			)
		)
		(property "Value" ""
			(at 0 0 90)
			(layer "F.Fab")
			(effects
				(font
					(size 1.27 1.27)
				)
			)
		)
		(duplicate_pad_numbers_are_jumpers no)
		(fp_line
			(start 0.7874 -0.4064)
			(end 0.7874 0.4064)
			(stroke
				(width 0.1524)
				(type default)
			)
			(layer "F.SilkS")
		)
		(fp_line
			(start -0.7874 -0.4064)
			(end 0.7874 -0.4064)
			(stroke
				(width 0.1524)
				(type default)
			)
			(layer "F.SilkS")
		)
		(fp_line
			(start 0 0.381)
			(end 0 -0.381)
			(stroke
				(width 0.1524)
				(type default)
			)
			(layer "F.SilkS")
		)
		(fp_line
			(start 0.7874 0.4064)
			(end -0.7874 0.4064)
			(stroke
				(width 0.1524)
				(type default)
			)
			(layer "F.SilkS")
		)
		(fp_line
			(start -0.7874 0.4064)
			(end -0.7874 -0.4064)
			(stroke
				(width 0.1524)
				(type default)
			)
			(layer "F.SilkS")
		)
		(fp_poly
			(pts
				(xy -0.5334 0.254) (xy -0.635 0.254) (xy -0.635 0.2286) (xy -0.635 -0.254) (xy -0.5334 -0.254) (xy -0.5334 -0.2794)
				(xy 0.5334 -0.2794) (xy 0.5334 -0.254) (xy 0.635 -0.254) (xy 0.635 0.254) (xy 0.5334 0.254) (xy 0.5334 0.2794)
				(xy -0.508 0.2794) (xy -0.5334 0.2794)
			)
			(stroke
				(width 0)
				(type default)
			)
			(fill no)
			(layer "F.CrtYd")
		)
		(pad "1" smd rect
			(at 0.40005 0 90)
			(size 0.4572 0.508)
			(layers "F.Cu" "F.Mask" "F.Paste")
			(net "P12V")
		)
		(pad "2" smd rect
			(at -0.40005 0 90)
			(size 0.4572 0.508)
			(layers "F.Cu" "F.Mask" "F.Paste")
			(net "GND")
		)
	)
	(footprint ""
		(layer "F.Cu")
		(at 74.0537 -459.732634 -90)
		(property "Reference" "C73"
			(at -2.962656 -0.345948 90)
			(unlocked yes)
			(layer "F.SilkS")
			(effects
				(font
					(size 0.7874 0.5842)
					(thickness 0.1524)
				)
				(justify left)
			)
		)
		(property "Value" ""
			(at 0 0 270)
			(layer "F.Fab")
			(effects
				(font
					(size 1.27 1.27)
				)
			)
		)
		(duplicate_pad_numbers_are_jumpers no)
		(fp_line
			(start -0.7874 0.4064)
			(end -0.7874 -0.4064)
			(stroke
				(width 0.1524)
				(type default)
			)
			(layer "F.SilkS")
		)
		(fp_line
			(start 0.7874 0.4064)
			(end -0.7874 0.4064)
			(stroke
				(width 0.1524)
				(type default)
			)
			(layer "F.SilkS")
		)
		(fp_line
			(start 0 0.381)
			(end 0 -0.381)
			(stroke
				(width 0.1524)
				(type default)
			)
			(layer "F.SilkS")
		)
		(fp_line
			(start -0.7874 -0.4064)
			(end 0.7874 -0.4064)
			(stroke
				(width 0.1524)
				(type default)
			)
			(layer "F.SilkS")
		)
		(fp_line
			(start 0.7874 -0.4064)
			(end 0.7874 0.4064)
			(stroke
				(width 0.1524)
				(type default)
			)
			(layer "F.SilkS")
		)
		(fp_poly
			(pts
				(xy -0.5334 0.254) (xy -0.635 0.254) (xy -0.635 0.2286) (xy -0.635 -0.254) (xy -0.5334 -0.254) (xy -0.5334 -0.2794)
				(xy 0.5334 -0.2794) (xy 0.5334 -0.254) (xy 0.635 -0.254) (xy 0.635 0.254) (xy 0.5334 0.254) (xy 0.5334 0.2794)
				(xy -0.508 0.2794) (xy -0.5334 0.2794)
			)
			(stroke
				(width 0)
				(type default)
			)
			(fill no)
			(layer "F.CrtYd")
		)
		(pad "1" smd rect
			(at 0.40005 0 270)
			(size 0.4572 0.508)
			(layers "F.Cu" "F.Mask" "F.Paste")
			(net "P12V")
		)
		(pad "2" smd rect
			(at -0.40005 0 270)
			(size 0.4572 0.508)
			(layers "F.Cu" "F.Mask" "F.Paste")
			(net "GND")
		)
	)
	(footprint ""
		(layer "F.Cu")
		(at 66.7004 -209.195416 180)
		(property "Reference" "R119"
			(at 0.958596 0.97282 0)
			(unlocked yes)
			(layer "F.SilkS")
			(effects
				(font
					(size 0.7874 0.5842)
					(thickness 0.1524)
				)
				(justify left)
			)
		)
		(property "Value" ""
			(at 0 0 180)
			(layer "F.Fab")
			(effects
				(font
					(size 1.27 1.27)
				)
			)
		)
		(duplicate_pad_numbers_are_jumpers no)
		(fp_line
			(start 0.7874 0.4064)
			(end -0.7874 0.4064)
			(stroke
				(width 0.1524)
				(type default)
			)
			(layer "F.SilkS")
		)
		(fp_line
			(start 0.7874 -0.4064)
			(end 0.7874 0.4064)
			(stroke
				(width 0.1524)
				(type default)
			)
			(layer "F.SilkS")
		)
		(fp_line
			(start -0.7874 0.4064)
			(end -0.7874 -0.4064)
			(stroke
				(width 0.1524)
				(type default)
			)
			(layer "F.SilkS")
		)
		(fp_line
			(start -0.7874 -0.4064)
			(end 0.7874 -0.4064)
			(stroke
				(width 0.1524)
				(type default)
			)
			(layer "F.SilkS")
		)
		(fp_poly
			(pts
				(xy -0.508 0.2794) (xy -0.508 0.2286) (xy -0.635 0.2286) (xy -0.635 -0.254) (xy -0.5334 -0.254)
				(xy -0.5334 -0.2794) (xy 0.5334 -0.2794) (xy 0.5334 -0.254) (xy 0.635 -0.254) (xy 0.635 0.254) (xy 0.5334 0.254)
				(xy 0.5334 0.2794)
			)
			(stroke
				(width 0)
				(type default)
			)
			(fill no)
			(layer "F.CrtYd")
		)
		(pad "1" smd rect
			(at 0.40005 0 180)
			(size 0.4572 0.508)
			(layers "F.Cu" "F.Mask" "F.Paste")
			(net "PSU3_REMOTE_R2_P")
		)
		(pad "2" smd rect
			(at -0.40005 0 180)
			(size 0.4572 0.508)
			(layers "F.Cu" "F.Mask" "F.Paste")
			(net "P12V")
		)
	)
	(footprint ""
		(layer "F.Cu")
		(at 27.639264 -285.429452 -90)
		(property "Reference" "R109"
			(at -1.498854 1.234948 90)
			(unlocked yes)
			(layer "F.SilkS")
			(effects
				(font
					(size 0.7874 0.5842)
					(thickness 0.1524)
				)
				(justify left)
			)
		)
		(property "Value" ""
			(at 0 0 270)
			(layer "F.Fab")
			(effects
				(font
					(size 1.27 1.27)
				)
			)
		)
		(duplicate_pad_numbers_are_jumpers no)
		(fp_line
			(start -0.7874 0.4064)
			(end -0.7874 -0.4064)
			(stroke
				(width 0.1524)
				(type default)
			)
			(layer "F.SilkS")
		)
		(fp_line
			(start 0.7874 0.4064)
			(end -0.7874 0.4064)
			(stroke
				(width 0.1524)
				(type default)
			)
			(layer "F.SilkS")
		)
		(fp_line
			(start -0.7874 -0.4064)
			(end 0.7874 -0.4064)
			(stroke
				(width 0.1524)
				(type default)
			)
			(layer "F.SilkS")
		)
		(fp_line
			(start 0.7874 -0.4064)
			(end 0.7874 0.4064)
			(stroke
				(width 0.1524)
				(type default)
			)
			(layer "F.SilkS")
		)
		(fp_poly
			(pts
				(xy -0.508 0.2794) (xy -0.508 0.2286) (xy -0.635 0.2286) (xy -0.635 -0.254) (xy -0.5334 -0.254)
				(xy -0.5334 -0.2794) (xy 0.5334 -0.2794) (xy 0.5334 -0.254) (xy 0.635 -0.254) (xy 0.635 0.254) (xy 0.5334 0.254)
				(xy 0.5334 0.2794)
			)
			(stroke
				(width 0)
				(type default)
			)
			(fill no)
			(layer "F.CrtYd")
		)
		(pad "1" smd rect
			(at 0.40005 0 270)
			(size 0.4572 0.508)
			(layers "F.Cu" "F.Mask" "F.Paste")
			(net "PSU4_REMOTE_N")
		)
		(pad "2" smd rect
			(at -0.40005 0 270)
			(size 0.4572 0.508)
			(layers "F.Cu" "F.Mask" "F.Paste")
			(net "PSU4_REMOTE_R_N")
		)
	)
	(footprint ""
		(layer "F.Cu")
		(at 79.524606 -14.939772 -90)
		(property "Reference" "C5"
			(at -1.75133 0.0254 90)
			(unlocked yes)
			(layer "F.SilkS")
			(effects
				(font
					(size 0.7874 0.5842)
					(thickness 0.1524)
				)
				(justify left)
			)
		)
		(property "Value" ""
			(at 0 0 270)
			(layer "F.Fab")
			(effects
				(font
					(size 1.27 1.27)
				)
			)
		)
		(duplicate_pad_numbers_are_jumpers no)
		(fp_line
			(start -0.7874 0.4064)
			(end -0.7874 -0.4064)
			(stroke
				(width 0.1524)
				(type default)
			)
			(layer "F.SilkS")
		)
		(fp_line
			(start 0.7874 0.4064)
			(end -0.7874 0.4064)
			(stroke
				(width 0.1524)
				(type default)
			)
			(layer "F.SilkS")
		)
		(fp_line
			(start 0 0.381)
			(end 0 -0.381)
			(stroke
				(width 0.1524)
				(type default)
			)
			(layer "F.SilkS")
		)
		(fp_line
			(start -0.7874 -0.4064)
			(end 0.7874 -0.4064)
			(stroke
				(width 0.1524)
				(type default)
			)
			(layer "F.SilkS")
		)
		(fp_line
			(start 0.7874 -0.4064)
			(end 0.7874 0.4064)
			(stroke
				(width 0.1524)
				(type default)
			)
			(layer "F.SilkS")
		)
		(fp_poly
			(pts
				(xy -0.5334 0.254) (xy -0.635 0.254) (xy -0.635 0.2286) (xy -0.635 -0.254) (xy -0.5334 -0.254) (xy -0.5334 -0.2794)
				(xy 0.5334 -0.2794) (xy 0.5334 -0.254) (xy 0.635 -0.254) (xy 0.635 0.254) (xy 0.5334 0.254) (xy 0.5334 0.2794)
				(xy -0.508 0.2794) (xy -0.5334 0.2794)
			)
			(stroke
				(width 0)
				(type default)
			)
			(fill no)
			(layer "F.CrtYd")
		)
		(pad "1" smd rect
			(at 0.40005 0 270)
			(size 0.4572 0.508)
			(layers "F.Cu" "F.Mask" "F.Paste")
			(net "P12V")
		)
		(pad "2" smd rect
			(at -0.40005 0 270)
			(size 0.4572 0.508)
			(layers "F.Cu" "F.Mask" "F.Paste")
			(net "GND")
		)
	)
	(footprint ""
		(layer "F.Cu")
		(at 91.399868 -20.01012)
		(property "Reference" "H25"
			(at -5.1308 -5.23113 0)
			(unlocked yes)
			(layer "F.SilkS")
			(effects
				(font
					(size 0.7874 0.5842)
					(thickness 0.1524)
				)
				(justify left)
			)
		)
		(property "Value" ""
			(at 0 0 0)
			(layer "F.Fab")
			(effects
				(font
					(size 1.27 1.27)
				)
			)
		)
		(duplicate_pad_numbers_are_jumpers no)
		(fp_circle
			(center 0 0)
			(end 4.826 0)
			(stroke
				(width 0.1524)
				(type default)
			)
			(fill no)
			(layer "F.SilkS")
		)
		(fp_circle
			(center 0 0)
			(end 4.826 0)
			(stroke
				(width 0.1524)
				(type default)
			)
			(fill no)
			(layer "B.SilkS")
		)
		(fp_poly
			(pts
				(arc
					(start 0 4.0132)
					(mid 0 -4.0132)
					(end 0 4.0132)
				)
			)
			(stroke
				(width 0)
				(type default)
			)
			(fill no)
			(layer "F.CrtYd")
		)
		(pad "" np_thru_hole circle
			(at 0 0)
			(size 8.001 8.001)
			(drill 8.001)
			(layers "*.Cu" "*.Mask")
			(clearance 0.381)
			(thermal_gap 0.381)
		)
		(zone
			(layers "F.Cu" "B.Cu" "In1.Cu" "In2.Cu" "In3.Cu" "In4.Cu" "In5.Cu" "In6.Cu")
			(hatch none 0.5)
			(connect_pads
				(clearance 0)
			)
			(min_thickness 0.25)
			(keepout
				(tracks not_allowed)
				(vias allowed)
				(pads allowed)
				(copperpour not_allowed)
				(footprints allowed)
			)
			(placement
				(enabled no)
				(sheetname "")
			)
			(fill
				(thermal_gap 0.5)
				(thermal_bridge_width 0.5)
				(island_removal_mode 0)
			)
			(polygon
				(pts
					(arc
						(start 91.399868 -15.48892)
						(mid 91.399868 -24.53132)
						(end 91.399868 -15.48892)
					)
				)
			)
		)
	)
	(footprint ""
		(layer "F.Cu")
		(at 77.999844 -121.19991)
		(property "Reference" "H9"
			(at -9.877298 -3.685032 0)
			(unlocked yes)
			(layer "F.SilkS")
			(effects
				(font
					(size 0.7874 0.5842)
					(thickness 0.1524)
				)
				(justify left)
			)
		)
		(property "Value" ""
			(at 0 0 0)
			(layer "F.Fab")
			(effects
				(font
					(size 1.27 1.27)
				)
			)
		)
		(duplicate_pad_numbers_are_jumpers no)
		(fp_circle
			(center 0 0)
			(end 7.999984 0)
			(stroke
				(width 0.1524)
				(type default)
			)
			(fill no)
			(layer "F.SilkS")
		)
		(fp_arc
			(start 10.063734 10.724134)
			(mid -13.496547 -5.843072)
			(end 14.7066 0)
			(stroke
				(width 0.1524)
				(type default)
			)
			(layer "B.SilkS")
		)
		(fp_arc
			(start 14.7066 0)
			(mid 13.809901 5.056557)
			(end 11.22934 9.496552)
			(stroke
				(width 0.1524)
				(type default)
			)
			(layer "B.SilkS")
		)
		(fp_poly
			(pts
				(arc
					(start 5.0038 0)
					(mid -5.0038 0)
					(end 5.0038 0)
				)
			)
			(stroke
				(width 0)
				(type default)
			)
			(fill no)
			(layer "F.CrtYd")
		)
		(pad "" np_thru_hole circle
			(at 0 0)
			(size 4.0132 4.0132)
			(drill 4.0132)
			(layers "*.Cu" "*.Mask")
			(clearance 0.381)
			(thermal_gap 0.381)
		)
		(pad "2" thru_hole circle
			(at 0 -3.50012)
			(size 0.762 0.762)
			(drill 0.5588)
			(layers "*.Cu" "*.Mask")
			(remove_unused_layers no)
			(net "GND")
			(clearance 0.1524)
			(thermal_gap 0.1524)
		)
		(pad "3" thru_hole circle
			(at -2.500122 -2.500122)
			(size 0.762 0.762)
			(drill 0.5588)
			(layers "*.Cu" "*.Mask")
			(remove_unused_layers no)
			(net "GND")
			(clearance 0.1524)
			(thermal_gap 0.1524)
		)
		(pad "4" thru_hole circle
			(at -3.50012 0)
			(size 0.762 0.762)
			(drill 0.5588)
			(layers "*.Cu" "*.Mask")
			(remove_unused_layers no)
			(net "GND")
			(clearance 0.1524)
			(thermal_gap 0.1524)
		)
		(pad "5" thru_hole circle
			(at -2.500122 2.500122)
			(size 0.762 0.762)
			(drill 0.5588)
			(layers "*.Cu" "*.Mask")
			(remove_unused_layers no)
			(net "GND")
			(clearance 0.1524)
			(thermal_gap 0.1524)
		)
		(pad "6" thru_hole circle
			(at 0 3.50012)
			(size 0.762 0.762)
			(drill 0.5588)
			(layers "*.Cu" "*.Mask")
			(remove_unused_layers no)
			(net "GND")
			(clearance 0.1524)
			(thermal_gap 0.1524)
		)
		(pad "7" thru_hole circle
			(at 2.500122 2.500122)
			(size 0.762 0.762)
			(drill 0.5588)
			(layers "*.Cu" "*.Mask")
			(remove_unused_layers no)
			(net "GND")
			(clearance 0.1524)
			(thermal_gap 0.1524)
		)
		(pad "8" thru_hole circle
			(at 3.50012 0)
			(size 0.762 0.762)
			(drill 0.5588)
			(layers "*.Cu" "*.Mask")
			(remove_unused_layers no)
			(net "GND")
			(clearance 0.1524)
			(thermal_gap 0.1524)
		)
		(pad "9" thru_hole circle
			(at 2.500122 -2.500122)
			(size 0.762 0.762)
			(drill 0.5588)
			(layers "*.Cu" "*.Mask")
			(remove_unused_layers no)
			(net "GND")
			(clearance 0.1524)
			(thermal_gap 0.1524)
		)
		(zone
			(layer "F.Cu")
			(hatch none 0.5)
			(connect_pads
				(clearance 0)
			)
			(min_thickness 0.25)
			(keepout
				(tracks not_allowed)
				(vias allowed)
				(pads allowed)
				(copperpour not_allowed)
				(footprints allowed)
			)
			(placement
				(enabled no)
				(sheetname "")
			)
			(fill
				(thermal_gap 0.5)
				(thermal_bridge_width 0.5)
				(island_removal_mode 0)
			)
			(polygon
				(pts
					(arc
						(start 77.999844 -129.20091)
						(mid 69.998844 -121.19991)
						(end 77.999844 -113.19891)
					)
					(arc
						(start 77.999844 -113.19891)
						(mid 79.434944 -114.63401)
						(end 77.999844 -116.06911)
					)
					(arc
						(start 77.999844 -116.06911)
						(mid 72.869044 -121.19991)
						(end 77.999844 -126.33071)
					)
					(arc
						(start 77.999844 -126.33071)
						(mid 79.434944 -127.76581)
						(end 77.999844 -129.20091)
					)
				)
			)
		)
		(zone
			(layer "F.Cu")
			(hatch none 0.5)
			(connect_pads
				(clearance 0)
			)
			(min_thickness 0.25)
			(keepout
				(tracks not_allowed)
				(vias allowed)
				(pads allowed)
				(copperpour not_allowed)
				(footprints allowed)
			)
			(placement
				(enabled no)
				(sheetname "")
			)
			(fill
				(thermal_gap 0.5)
				(thermal_bridge_width 0.5)
				(island_removal_mode 0)
			)
			(polygon
				(pts
					(arc
						(start 77.999844 -129.20091)
						(mid 86.000844 -121.19991)
						(end 77.999844 -113.19891)
					)
					(arc
						(start 77.999844 -113.19891)
						(mid 76.564744 -114.63401)
						(end 77.999844 -116.06911)
					)
					(arc
						(start 77.999844 -116.06911)
						(mid 83.130644 -121.19991)
						(end 77.999844 -126.33071)
					)
					(arc
						(start 77.999844 -126.33071)
						(mid 76.564744 -127.76581)
						(end 77.999844 -129.20091)
					)
				)
			)
		)
		(zone
			(layers "F.Cu" "B.Cu" "In1.Cu" "In2.Cu" "In3.Cu" "In4.Cu" "In5.Cu" "In6.Cu")
			(hatch none 0.5)
			(connect_pads
				(clearance 0)
			)
			(min_thickness 0.25)
			(keepout
				(tracks not_allowed)
				(vias allowed)
				(pads allowed)
				(copperpour not_allowed)
				(footprints allowed)
			)
			(placement
				(enabled no)
				(sheetname "")
			)
			(fill
				(thermal_gap 0.5)
				(thermal_bridge_width 0.5)
				(island_removal_mode 0)
			)
			(polygon
				(pts
					(arc
						(start 80.511904 -121.19991)
						(mid 75.487784 -121.19991)
						(end 80.511904 -121.19991)
					)
				)
			)
		)
	)
	(footprint ""
		(layer "F.Cu")
		(at 4.50469 -494.611914)
		(property "Reference" "J22"
			(at 2.474976 -5.752846 0)
			(unlocked yes)
			(layer "F.SilkS")
			(effects
				(font
					(size 0.7874 0.5842)
					(thickness 0.1524)
				)
				(justify left)
			)
		)
		(property "Value" ""
			(at 0 0 0)
			(layer "F.Fab")
			(effects
				(font
					(size 1.27 1.27)
				)
			)
		)
		(duplicate_pad_numbers_are_jumpers no)
		(fp_line
			(start -3.370072 -3.81)
			(end 12.260072 -3.81)
			(stroke
				(width 0.1524)
				(type default)
			)
			(layer "F.SilkS")
		)
		(fp_line
			(start -3.370072 12.830048)
			(end -3.370072 -3.81)
			(stroke
				(width 0.1524)
				(type default)
			)
			(layer "F.SilkS")
		)
		(fp_line
			(start 12.260072 -3.81)
			(end 12.260072 12.830048)
			(stroke
				(width 0.1524)
				(type default)
			)
			(layer "F.SilkS")
		)
		(fp_line
			(start 12.260072 12.830048)
			(end -3.370072 12.830048)
			(stroke
				(width 0.1524)
				(type default)
			)
			(layer "F.SilkS")
		)
		(fp_poly
			(pts
				(xy -3.451606 -0.016764) (xy -4.255262 0.385064) (xy -4.255262 -0.418592)
			)
			(stroke
				(width 0)
				(type default)
			)
			(fill yes)
			(layer "F.SilkS")
		)
		(fp_poly
			(pts
				(xy -0.762 0.762) (xy 8.382 0.762) (xy 8.382 -1.8034) (xy 9.652 -1.8034) (xy 9.652 -3.302) (xy 0.508 -3.302)
				(xy 0.508 -0.762) (xy -0.762 -0.762)
			)
			(stroke
				(width 0)
				(type default)
			)
			(fill no)
			(layer "B.CrtYd")
		)
		(fp_poly
			(pts
				(arc
					(start 0.6604 6.35)
					(mid -3.2004 6.35)
					(end 0.6604 6.35)
				)
			)
			(stroke
				(width 0)
				(type default)
			)
			(fill no)
			(layer "B.CrtYd")
		)
		(fp_poly
			(pts
				(arc
					(start 12.0904 6.35)
					(mid 8.2296 6.35)
					(end 12.0904 6.35)
				)
			)
			(stroke
				(width 0)
				(type default)
			)
			(fill no)
			(layer "B.CrtYd")
		)
		(fp_poly
			(pts
				(xy -3.370072 12.830048) (xy 12.260072 12.830048) (xy 12.260072 -3.81) (xy -3.370072 -3.81)
			)
			(stroke
				(width 0)
				(type default)
			)
			(fill no)
			(layer "F.CrtYd")
		)
		(fp_line
			(start -3.370072 -3.81)
			(end 12.260072 -3.81)
			(stroke
				(width 0.1)
				(type default)
			)
			(layer "F.Fab")
		)
		(fp_line
			(start -3.370072 12.830048)
			(end -3.370072 -3.81)
			(stroke
				(width 0.1)
				(type default)
			)
			(layer "F.Fab")
		)
		(fp_line
			(start 12.260072 -3.81)
			(end 12.260072 12.830048)
			(stroke
				(width 0.1)
				(type default)
			)
			(layer "F.Fab")
		)
		(fp_line
			(start 12.260072 12.830048)
			(end -3.370072 12.830048)
			(stroke
				(width 0.1)
				(type default)
			)
			(layer "F.Fab")
		)
		(fp_poly
			(pts
				(xy -3.576828 0) (xy -5.0038 0.713486) (xy -5.0038 -0.713486)
			)
			(stroke
				(width 0)
				(type default)
			)
			(fill yes)
			(layer "F.Fab")
		)
		(fp_text user "2"
			(at -3.828796 -3.314446 0)
			(unlocked yes)
			(layer "F.SilkS")
			(effects
				(font
					(size 0.7874 0.5842)
					(thickness 0.1524)
				)
			)
		)
		(fp_text user "1"
			(at -3.777996 -1.815846 0)
			(unlocked yes)
			(layer "F.SilkS")
			(effects
				(font
					(size 0.7874 0.5842)
					(thickness 0.1524)
				)
			)
		)
		(fp_text user "8"
			(at 12.7762 -2.555748 0)
			(unlocked yes)
			(layer "F.SilkS")
			(effects
				(font
					(size 0.7874 0.5842)
					(thickness 0.1524)
				)
			)
		)
		(fp_text user "7"
			(at 12.7762 -0.091948 0)
			(unlocked yes)
			(layer "F.SilkS")
			(effects
				(font
					(size 0.7874 0.5842)
					(thickness 0.1524)
				)
			)
		)
		(fp_text user "1"
			(at -1.2954 0.085852 0)
			(unlocked yes)
			(layer "B.SilkS")
			(effects
				(font
					(size 0.7874 0.5842)
					(thickness 0.1524)
				)
				(justify mirror)
			)
		)
		(fp_text user "2"
			(at 0 -2.581148 0)
			(unlocked yes)
			(layer "B.SilkS")
			(effects
				(font
					(size 0.7874 0.5842)
					(thickness 0.1524)
				)
				(justify mirror)
			)
		)
		(fp_text user "7"
			(at 8.8138 0.238252 0)
			(unlocked yes)
			(layer "B.SilkS")
			(effects
				(font
					(size 0.7874 0.5842)
					(thickness 0.1524)
				)
				(justify mirror)
			)
		)
		(fp_text user "8"
			(at 10.0838 -2.403348 0)
			(unlocked yes)
			(layer "B.SilkS")
			(effects
				(font
					(size 0.7874 0.5842)
					(thickness 0.1524)
				)
				(justify mirror)
			)
		)
		(fp_text user "1"
			(at -1.2954 0.085852 0)
			(unlocked yes)
			(layer "B.Fab")
			(effects
				(font
					(size 0.7874 0.5842)
					(thickness 0.000001)
				)
				(justify mirror)
			)
		)
		(fp_text user "2"
			(at 0 -2.581148 0)
			(unlocked yes)
			(layer "B.Fab")
			(effects
				(font
					(size 0.7874 0.5842)
					(thickness 0.000001)
				)
				(justify mirror)
			)
		)
		(fp_text user "7"
			(at 8.8138 0.238252 0)
			(unlocked yes)
			(layer "B.Fab")
			(effects
				(font
					(size 0.7874 0.5842)
					(thickness 0.000001)
				)
				(justify mirror)
			)
		)
		(fp_text user "8"
			(at 10.0838 -2.403348 0)
			(unlocked yes)
			(layer "B.Fab")
			(effects
				(font
					(size 0.7874 0.5842)
					(thickness 0.000001)
				)
				(justify mirror)
			)
		)
		(fp_text user "2"
			(at -3.9624 -2.428748 0)
			(unlocked yes)
			(layer "F.Fab")
			(effects
				(font
					(size 0.7874 0.5842)
					(thickness 0.000001)
				)
			)
		)
		(fp_text user "1"
			(at -3.9116 -0.930148 0)
			(unlocked yes)
			(layer "F.Fab")
			(effects
				(font
					(size 0.7874 0.5842)
					(thickness 0.000001)
				)
			)
		)
		(fp_text user "8"
			(at 12.7762 -2.555748 0)
			(unlocked yes)
			(layer "F.Fab")
			(effects
				(font
					(size 0.7874 0.5842)
					(thickness 0.000001)
				)
			)
		)
		(fp_text user "7"
			(at 12.7762 -0.091948 0)
			(unlocked yes)
			(layer "F.Fab")
			(effects
				(font
					(size 0.7874 0.5842)
					(thickness 0.000001)
				)
			)
		)
		(pad "" np_thru_hole circle
			(at -1.27 6.35)
			(size 3.3528 3.3528)
			(drill 3.3528)
			(layers "*.Cu" "*.Mask")
			(clearance 0.381)
			(thermal_gap 0.381)
		)
		(pad "" np_thru_hole circle
			(at 10.16 6.35)
			(size 3.3528 3.3528)
			(drill 3.3528)
			(layers "*.Cu" "*.Mask")
			(clearance 0.381)
			(thermal_gap 0.381)
		)
		(pad "1" thru_hole rect
			(at 0 0)
			(size 1.397 1.397)
			(drill 0.9906)
			(layers "*.Cu" "*.Mask")
			(remove_unused_layers no)
			(net "UART_RTS_RP5_L_N")
			(clearance 0.0508)
			(thermal_gap 0.0508)
			(padstack
				(mode front_inner_back)
				(layer "Inner"
					(shape circle)
					(size 1.397 1.397)
					(clearance 0.0508)
				)
				(layer "B.Cu"
					(shape rect)
					(size 1.397 1.397)
					(clearance 0.0508)
				)
			)
		)
		(pad "2" thru_hole circle
			(at 1.27 -2.54)
			(size 1.397 1.397)
			(drill 0.9906)
			(layers "*.Cu" "*.Mask")
			(remove_unused_layers no)
			(net "UART_DSR_RP5_L")
			(clearance 0.0508)
			(thermal_gap 0.0508)
		)
		(pad "3" thru_hole circle
			(at 2.54 0)
			(size 1.397 1.397)
			(drill 0.9906)
			(layers "*.Cu" "*.Mask")
			(remove_unused_layers no)
			(net "UART_RX_RP5_L")
			(clearance 0.0508)
			(thermal_gap 0.0508)
		)
		(pad "4" thru_hole circle
			(at 3.81 -2.54)
			(size 1.397 1.397)
			(drill 0.9906)
			(layers "*.Cu" "*.Mask")
			(remove_unused_layers no)
			(net "UART_RI_RP5_L_N")
			(clearance 0.0508)
			(thermal_gap 0.0508)
		)
		(pad "5" thru_hole circle
			(at 5.08 0)
			(size 1.397 1.397)
			(drill 0.9906)
			(layers "*.Cu" "*.Mask")
			(remove_unused_layers no)
			(net "GND")
			(clearance 0.0508)
			(thermal_gap 0.0508)
		)
		(pad "6" thru_hole circle
			(at 6.35 -2.54)
			(size 1.397 1.397)
			(drill 0.9906)
			(layers "*.Cu" "*.Mask")
			(remove_unused_layers no)
			(net "UART_TX_RP5_L")
			(clearance 0.0508)
			(thermal_gap 0.0508)
		)
		(pad "7" thru_hole circle
			(at 7.62 0)
			(size 1.397 1.397)
			(drill 0.9906)
			(layers "*.Cu" "*.Mask")
			(remove_unused_layers no)
			(net "UART_DTR_RP5_L_N")
			(clearance 0.0508)
			(thermal_gap 0.0508)
		)
		(pad "8" thru_hole circle
			(at 8.89 -2.54)
			(size 1.397 1.397)
			(drill 0.9906)
			(layers "*.Cu" "*.Mask")
			(remove_unused_layers no)
			(net "UART_CTS_RP5_L_N")
			(clearance 0.0508)
			(thermal_gap 0.0508)
		)
		(zone
			(layers "F.Cu" "B.Cu" "In1.Cu" "In2.Cu" "In3.Cu" "In4.Cu" "In5.Cu" "In6.Cu")
			(hatch none 0.5)
			(connect_pads
				(clearance 0)
			)
			(min_thickness 0.25)
			(keepout
				(tracks not_allowed)
				(vias allowed)
				(pads allowed)
				(copperpour not_allowed)
				(footprints allowed)
			)
			(placement
				(enabled no)
				(sheetname "")
			)
			(fill
				(thermal_gap 0.5)
				(thermal_bridge_width 0.5)
				(island_removal_mode 0)
			)
			(polygon
				(pts
					(arc
						(start 5.31749 -488.261914)
						(mid 1.15189 -488.261914)
						(end 5.31749 -488.261914)
					)
				)
			)
		)
		(zone
			(layers "F.Cu" "B.Cu" "In1.Cu" "In2.Cu" "In3.Cu" "In4.Cu" "In5.Cu" "In6.Cu")
			(hatch none 0.5)
			(connect_pads
				(clearance 0)
			)
			(min_thickness 0.25)
			(keepout
				(tracks not_allowed)
				(vias allowed)
				(pads allowed)
				(copperpour not_allowed)
				(footprints allowed)
			)
			(placement
				(enabled no)
				(sheetname "")
			)
			(fill
				(thermal_gap 0.5)
				(thermal_bridge_width 0.5)
				(island_removal_mode 0)
			)
			(polygon
				(pts
					(arc
						(start 16.74749 -488.261914)
						(mid 12.58189 -488.261914)
						(end 16.74749 -488.261914)
					)
				)
			)
		)
	)
	(footprint ""
		(layer "F.Cu")
		(at 69.982334 -370.601748 -90)
		(property "Reference" "C58"
			(at -2.675128 0.148844 90)
			(unlocked yes)
			(layer "F.SilkS")
			(effects
				(font
					(size 0.7874 0.5842)
					(thickness 0.1524)
				)
				(justify left)
			)
		)
		(property "Value" ""
			(at 0 0 270)
			(layer "F.Fab")
			(effects
				(font
					(size 1.27 1.27)
				)
			)
		)
		(duplicate_pad_numbers_are_jumpers no)
		(fp_line
			(start -0.7874 0.4064)
			(end -0.7874 -0.4064)
			(stroke
				(width 0.1524)
				(type default)
			)
			(layer "F.SilkS")
		)
		(fp_line
			(start 0.7874 0.4064)
			(end -0.7874 0.4064)
			(stroke
				(width 0.1524)
				(type default)
			)
			(layer "F.SilkS")
		)
		(fp_line
			(start 0 0.381)
			(end 0 -0.381)
			(stroke
				(width 0.1524)
				(type default)
			)
			(layer "F.SilkS")
		)
		(fp_line
			(start -0.7874 -0.4064)
			(end 0.7874 -0.4064)
			(stroke
				(width 0.1524)
				(type default)
			)
			(layer "F.SilkS")
		)
		(fp_line
			(start 0.7874 -0.4064)
			(end 0.7874 0.4064)
			(stroke
				(width 0.1524)
				(type default)
			)
			(layer "F.SilkS")
		)
		(fp_poly
			(pts
				(xy -0.5334 0.254) (xy -0.635 0.254) (xy -0.635 0.2286) (xy -0.635 -0.254) (xy -0.5334 -0.254) (xy -0.5334 -0.2794)
				(xy 0.5334 -0.2794) (xy 0.5334 -0.254) (xy 0.635 -0.254) (xy 0.635 0.254) (xy 0.5334 0.254) (xy 0.5334 0.2794)
				(xy -0.508 0.2794) (xy -0.5334 0.2794)
			)
			(stroke
				(width 0)
				(type default)
			)
			(fill no)
			(layer "F.CrtYd")
		)
		(pad "1" smd rect
			(at 0.40005 0 270)
			(size 0.4572 0.508)
			(layers "F.Cu" "F.Mask" "F.Paste")
			(net "P12V")
		)
		(pad "2" smd rect
			(at -0.40005 0 270)
			(size 0.4572 0.508)
			(layers "F.Cu" "F.Mask" "F.Paste")
			(net "GND")
		)
	)
	(footprint ""
		(layer "F.Cu")
		(at 39.849552 -17.30502 180)
		(property "Reference" "R12"
			(at -1.74498 -0.093472 0)
			(unlocked yes)
			(layer "F.SilkS")
			(effects
				(font
					(size 0.7874 0.5842)
					(thickness 0.1524)
				)
				(justify left)
			)
		)
		(property "Value" ""
			(at 0 0 180)
			(layer "F.Fab")
			(effects
				(font
					(size 1.27 1.27)
				)
			)
		)
		(duplicate_pad_numbers_are_jumpers no)
		(fp_line
			(start 0.7874 0.4064)
			(end -0.7874 0.4064)
			(stroke
				(width 0.1524)
				(type default)
			)
			(layer "F.SilkS")
		)
		(fp_line
			(start 0.7874 -0.4064)
			(end 0.7874 0.4064)
			(stroke
				(width 0.1524)
				(type default)
			)
			(layer "F.SilkS")
		)
		(fp_line
			(start -0.7874 0.4064)
			(end -0.7874 -0.4064)
			(stroke
				(width 0.1524)
				(type default)
			)
			(layer "F.SilkS")
		)
		(fp_line
			(start -0.7874 -0.4064)
			(end 0.7874 -0.4064)
			(stroke
				(width 0.1524)
				(type default)
			)
			(layer "F.SilkS")
		)
		(fp_poly
			(pts
				(xy -0.508 0.2794) (xy -0.508 0.2286) (xy -0.635 0.2286) (xy -0.635 -0.254) (xy -0.5334 -0.254)
				(xy -0.5334 -0.2794) (xy 0.5334 -0.2794) (xy 0.5334 -0.254) (xy 0.635 -0.254) (xy 0.635 0.254) (xy 0.5334 0.254)
				(xy 0.5334 0.2794)
			)
			(stroke
				(width 0)
				(type default)
			)
			(fill no)
			(layer "F.CrtYd")
		)
		(pad "1" smd rect
			(at 0.40005 0 180)
			(size 0.4572 0.508)
			(layers "F.Cu" "F.Mask" "F.Paste")
			(net "PSU1_AD0")
		)
		(pad "2" smd rect
			(at -0.40005 0 180)
			(size 0.4572 0.508)
			(layers "F.Cu" "F.Mask" "F.Paste")
			(net "GND")
		)
	)
	(footprint ""
		(layer "F.Cu")
		(at 27.05481 -11.75639 180)
		(property "Reference" "R49"
			(at 3.972306 0.169926 0)
			(unlocked yes)
			(layer "F.SilkS")
			(effects
				(font
					(size 0.7874 0.5842)
					(thickness 0.1524)
				)
				(justify left)
			)
		)
		(property "Value" ""
			(at 0 0 180)
			(layer "F.Fab")
			(effects
				(font
					(size 1.27 1.27)
				)
			)
		)
		(duplicate_pad_numbers_are_jumpers no)
		(fp_line
			(start 0.7874 0.4064)
			(end -0.7874 0.4064)
			(stroke
				(width 0.1524)
				(type default)
			)
			(layer "F.SilkS")
		)
		(fp_line
			(start 0.7874 -0.4064)
			(end 0.7874 0.4064)
			(stroke
				(width 0.1524)
				(type default)
			)
			(layer "F.SilkS")
		)
		(fp_line
			(start -0.7874 0.4064)
			(end -0.7874 -0.4064)
			(stroke
				(width 0.1524)
				(type default)
			)
			(layer "F.SilkS")
		)
		(fp_line
			(start -0.7874 -0.4064)
			(end 0.7874 -0.4064)
			(stroke
				(width 0.1524)
				(type default)
			)
			(layer "F.SilkS")
		)
		(fp_poly
			(pts
				(xy -0.508 0.2794) (xy -0.508 0.2286) (xy -0.635 0.2286) (xy -0.635 -0.254) (xy -0.5334 -0.254)
				(xy -0.5334 -0.2794) (xy 0.5334 -0.2794) (xy 0.5334 -0.254) (xy 0.635 -0.254) (xy 0.635 0.254) (xy 0.5334 0.254)
				(xy 0.5334 0.2794)
			)
			(stroke
				(width 0)
				(type default)
			)
			(fill no)
			(layer "F.CrtYd")
		)
		(pad "1" smd rect
			(at 0.40005 0 180)
			(size 0.4572 0.508)
			(layers "F.Cu" "F.Mask" "F.Paste")
			(net "GND")
		)
		(pad "2" smd rect
			(at -0.40005 0 180)
			(size 0.4572 0.508)
			(layers "F.Cu" "F.Mask" "F.Paste")
			(net "PSU1_PS_ON_N")
		)
	)
	(footprint ""
		(layer "F.Cu")
		(at 71.518526 -105.26776 -90)
		(property "Reference" "C15"
			(at -3.25374 -0.008128 90)
			(unlocked yes)
			(layer "F.SilkS")
			(effects
				(font
					(size 0.7874 0.5842)
					(thickness 0.1524)
				)
			)
		)
		(property "Value" ""
			(at 0 0 270)
			(layer "F.Fab")
			(effects
				(font
					(size 1.27 1.27)
				)
			)
		)
		(duplicate_pad_numbers_are_jumpers no)
		(fp_line
			(start -1.2954 0.5842)
			(end -1.2954 -0.5842)
			(stroke
				(width 0.1524)
				(type default)
			)
			(layer "F.SilkS")
		)
		(fp_line
			(start 1.2954 0.5842)
			(end -1.2954 0.5842)
			(stroke
				(width 0.1524)
				(type default)
			)
			(layer "F.SilkS")
		)
		(fp_line
			(start -1.2954 -0.5842)
			(end 1.2954 -0.5842)
			(stroke
				(width 0.1524)
				(type default)
			)
			(layer "F.SilkS")
		)
		(fp_line
			(start 0 -0.5842)
			(end 0 0.5842)
			(stroke
				(width 0.1524)
				(type default)
			)
			(layer "F.SilkS")
		)
		(fp_line
			(start 1.2954 -0.5842)
			(end 1.2954 0.5842)
			(stroke
				(width 0.1524)
				(type default)
			)
			(layer "F.SilkS")
		)
		(fp_poly
			(pts
				(xy 0.8636 -0.4572) (xy 0.8636 -0.3556) (xy 1.143 -0.3556) (xy 1.143 0.3556) (xy 0.8636 0.3556)
				(xy 0.8636 0.4572) (xy -0.8636 0.4572) (xy -0.8636 0.3556) (xy -1.143 0.3556) (xy -1.143 -0.3556)
				(xy -0.8636 -0.3556) (xy -0.8636 -0.4572)
			)
			(stroke
				(width 0)
				(type default)
			)
			(fill no)
			(layer "F.CrtYd")
		)
		(fp_line
			(start -0.884936 0.504952)
			(end -0.884936 -0.504952)
			(stroke
				(width 0.1)
				(type default)
			)
			(layer "F.Fab")
		)
		(fp_line
			(start 0.884936 0.504952)
			(end -0.884936 0.504952)
			(stroke
				(width 0.1)
				(type default)
			)
			(layer "F.Fab")
		)
		(fp_line
			(start -0.884936 -0.504952)
			(end 0.884936 -0.504952)
			(stroke
				(width 0.1)
				(type default)
			)
			(layer "F.Fab")
		)
		(fp_line
			(start 0.884936 -0.504952)
			(end 0.884936 0.504952)
			(stroke
				(width 0.1)
				(type default)
			)
			(layer "F.Fab")
		)
		(pad "1" smd rect
			(at 0.7366 0)
			(size 0.7112 0.8128)
			(layers "F.Cu" "F.Mask" "F.Paste")
			(net "P12V")
		)
		(pad "2" smd rect
			(at -0.7366 0)
			(size 0.7112 0.8128)
			(layers "F.Cu" "F.Mask" "F.Paste")
			(net "GND")
		)
	)
	(footprint ""
		(layer "F.Cu")
		(at 26.18613 -190.368174)
		(property "Reference" "R136"
			(at -4.256532 0.268224 0)
			(unlocked yes)
			(layer "F.SilkS")
			(effects
				(font
					(size 0.7874 0.5842)
					(thickness 0.1524)
				)
				(justify left)
			)
		)
		(property "Value" ""
			(at 0 0 0)
			(layer "F.Fab")
			(effects
				(font
					(size 1.27 1.27)
				)
			)
		)
		(duplicate_pad_numbers_are_jumpers no)
		(fp_line
			(start -0.7874 -0.4064)
			(end 0.7874 -0.4064)
			(stroke
				(width 0.1524)
				(type default)
			)
			(layer "F.SilkS")
		)
		(fp_line
			(start -0.7874 0.4064)
			(end -0.7874 -0.4064)
			(stroke
				(width 0.1524)
				(type default)
			)
			(layer "F.SilkS")
		)
		(fp_line
			(start 0.7874 -0.4064)
			(end 0.7874 0.4064)
			(stroke
				(width 0.1524)
				(type default)
			)
			(layer "F.SilkS")
		)
		(fp_line
			(start 0.7874 0.4064)
			(end -0.7874 0.4064)
			(stroke
				(width 0.1524)
				(type default)
			)
			(layer "F.SilkS")
		)
		(fp_poly
			(pts
				(xy -0.508 0.2794) (xy -0.508 0.2286) (xy -0.635 0.2286) (xy -0.635 -0.254) (xy -0.5334 -0.254)
				(xy -0.5334 -0.2794) (xy 0.5334 -0.2794) (xy 0.5334 -0.254) (xy 0.635 -0.254) (xy 0.635 0.254) (xy 0.5334 0.254)
				(xy 0.5334 0.2794)
			)
			(stroke
				(width 0)
				(type default)
			)
			(fill no)
			(layer "F.CrtYd")
		)
		(pad "1" smd rect
			(at 0.40005 0)
			(size 0.4572 0.508)
			(layers "F.Cu" "F.Mask" "F.Paste")
			(net "PSU3_CSAHRE")
		)
		(pad "2" smd rect
			(at -0.40005 0)
			(size 0.4572 0.508)
			(layers "F.Cu" "F.Mask" "F.Paste")
			(net "PSU_CSAHRE")
		)
	)
	(footprint ""
		(layer "F.Cu")
		(at 16.599916 -206.99984)
		(property "Reference" "H2"
			(at -3.038856 -9.000998 0)
			(unlocked yes)
			(layer "F.SilkS")
			(effects
				(font
					(size 0.7874 0.5842)
					(thickness 0.1524)
				)
				(justify left)
			)
		)
		(property "Value" ""
			(at 0 0 0)
			(layer "F.Fab")
			(effects
				(font
					(size 1.27 1.27)
				)
			)
		)
		(duplicate_pad_numbers_are_jumpers no)
		(fp_circle
			(center 0 0)
			(end 7.999984 0)
			(stroke
				(width 0.1524)
				(type default)
			)
			(fill no)
			(layer "F.SilkS")
		)
		(fp_circle
			(center 0 0)
			(end 14.7066 0)
			(stroke
				(width 0.1524)
				(type default)
			)
			(fill no)
			(layer "B.SilkS")
		)
		(fp_poly
			(pts
				(arc
					(start 0 5.0038)
					(mid 0 -5.0038)
					(end 0 5.0038)
				)
			)
			(stroke
				(width 0)
				(type default)
			)
			(fill no)
			(layer "F.CrtYd")
		)
		(pad "" np_thru_hole circle
			(at 0 0)
			(size 4.0132 4.0132)
			(drill 4.0132)
			(layers "*.Cu" "*.Mask")
			(clearance 0.381)
			(thermal_gap 0.381)
		)
		(pad "2" thru_hole circle
			(at 0 -3.50012)
			(size 0.762 0.762)
			(drill 0.5588)
			(layers "*.Cu" "*.Mask")
			(remove_unused_layers no)
			(net "GND")
			(clearance 0.1524)
			(thermal_gap 0.1524)
		)
		(pad "3" thru_hole circle
			(at -2.500122 -2.500122)
			(size 0.762 0.762)
			(drill 0.5588)
			(layers "*.Cu" "*.Mask")
			(remove_unused_layers no)
			(net "GND")
			(clearance 0.1524)
			(thermal_gap 0.1524)
		)
		(pad "4" thru_hole circle
			(at -3.50012 0)
			(size 0.762 0.762)
			(drill 0.5588)
			(layers "*.Cu" "*.Mask")
			(remove_unused_layers no)
			(net "GND")
			(clearance 0.1524)
			(thermal_gap 0.1524)
		)
		(pad "5" thru_hole circle
			(at -2.500122 2.500122)
			(size 0.762 0.762)
			(drill 0.5588)
			(layers "*.Cu" "*.Mask")
			(remove_unused_layers no)
			(net "GND")
			(clearance 0.1524)
			(thermal_gap 0.1524)
		)
		(pad "6" thru_hole circle
			(at 0 3.50012)
			(size 0.762 0.762)
			(drill 0.5588)
			(layers "*.Cu" "*.Mask")
			(remove_unused_layers no)
			(net "GND")
			(clearance 0.1524)
			(thermal_gap 0.1524)
		)
		(pad "7" thru_hole circle
			(at 2.500122 2.500122)
			(size 0.762 0.762)
			(drill 0.5588)
			(layers "*.Cu" "*.Mask")
			(remove_unused_layers no)
			(net "GND")
			(clearance 0.1524)
			(thermal_gap 0.1524)
		)
		(pad "8" thru_hole circle
			(at 3.50012 0)
			(size 0.762 0.762)
			(drill 0.5588)
			(layers "*.Cu" "*.Mask")
			(remove_unused_layers no)
			(net "GND")
			(clearance 0.1524)
			(thermal_gap 0.1524)
		)
		(pad "9" thru_hole circle
			(at 2.500122 -2.500122)
			(size 0.762 0.762)
			(drill 0.5588)
			(layers "*.Cu" "*.Mask")
			(remove_unused_layers no)
			(net "GND")
			(clearance 0.1524)
			(thermal_gap 0.1524)
		)
		(zone
			(layer "F.Cu")
			(hatch none 0.5)
			(connect_pads
				(clearance 0)
			)
			(min_thickness 0.25)
			(keepout
				(tracks not_allowed)
				(vias allowed)
				(pads allowed)
				(copperpour not_allowed)
				(footprints allowed)
			)
			(placement
				(enabled no)
				(sheetname "")
			)
			(fill
				(thermal_gap 0.5)
				(thermal_bridge_width 0.5)
				(island_removal_mode 0)
			)
			(polygon
				(pts
					(arc
						(start 16.599916 -215.00084)
						(mid 8.598916 -206.99984)
						(end 16.599916 -198.99884)
					)
					(arc
						(start 16.599916 -198.99884)
						(mid 18.035016 -200.43394)
						(end 16.599916 -201.86904)
					)
					(arc
						(start 16.599916 -201.86904)
						(mid 11.469116 -206.99984)
						(end 16.599916 -212.13064)
					)
					(arc
						(start 16.599916 -212.13064)
						(mid 18.035016 -213.56574)
						(end 16.599916 -215.00084)
					)
				)
			)
		)
		(zone
			(layer "F.Cu")
			(hatch none 0.5)
			(connect_pads
				(clearance 0)
			)
			(min_thickness 0.25)
			(keepout
				(tracks not_allowed)
				(vias allowed)
				(pads allowed)
				(copperpour not_allowed)
				(footprints allowed)
			)
			(placement
				(enabled no)
				(sheetname "")
			)
			(fill
				(thermal_gap 0.5)
				(thermal_bridge_width 0.5)
				(island_removal_mode 0)
			)
			(polygon
				(pts
					(arc
						(start 16.599916 -215.00084)
						(mid 24.600916 -206.99984)
						(end 16.599916 -198.99884)
					)
					(arc
						(start 16.599916 -198.99884)
						(mid 15.164816 -200.43394)
						(end 16.599916 -201.86904)
					)
					(arc
						(start 16.599916 -201.86904)
						(mid 21.730716 -206.99984)
						(end 16.599916 -212.13064)
					)
					(arc
						(start 16.599916 -212.13064)
						(mid 15.164816 -213.56574)
						(end 16.599916 -215.00084)
					)
				)
			)
		)
		(zone
			(layers "F.Cu" "B.Cu" "In1.Cu" "In2.Cu" "In3.Cu" "In4.Cu" "In5.Cu" "In6.Cu")
			(hatch none 0.5)
			(connect_pads
				(clearance 0)
			)
			(min_thickness 0.25)
			(keepout
				(tracks not_allowed)
				(vias allowed)
				(pads allowed)
				(copperpour not_allowed)
				(footprints allowed)
			)
			(placement
				(enabled no)
				(sheetname "")
			)
			(fill
				(thermal_gap 0.5)
				(thermal_bridge_width 0.5)
				(island_removal_mode 0)
			)
			(polygon
				(pts
					(arc
						(start 16.599916 -204.48778)
						(mid 16.599916 -209.5119)
						(end 16.599916 -204.48778)
					)
				)
			)
		)
	)
	(footprint ""
		(layer "F.Cu")
		(at 51.613054 -240.589308 180)
		(property "Reference" "CE12"
			(at -5.020056 0.183388 0)
			(unlocked yes)
			(layer "F.SilkS")
			(effects
				(font
					(size 0.7874 0.5842)
					(thickness 0.1524)
				)
				(justify left)
			)
		)
		(property "Value" ""
			(at 0 0 180)
			(layer "F.Fab")
			(effects
				(font
					(size 1.27 1.27)
				)
			)
		)
		(duplicate_pad_numbers_are_jumpers no)
		(fp_line
			(start 0 -4.2672)
			(end 0 4.2672)
			(stroke
				(width 0.1524)
				(type default)
			)
			(layer "F.SilkS")
		)
		(fp_circle
			(center 0 0)
			(end -4.2672 0)
			(stroke
				(width 0.1524)
				(type default)
			)
			(fill no)
			(layer "F.SilkS")
		)
		(fp_poly
			(pts
				(arc
					(start 0 -4.2672)
					(mid 4.2672 0)
					(end 0 4.2672)
				)
			)
			(stroke
				(width 0)
				(type default)
			)
			(fill yes)
			(layer "F.SilkS")
		)
		(fp_poly
			(pts
				(xy -2.5146 -0.762) (xy -0.9906 -0.762) (xy -0.9906 0.762) (xy -2.5146 0.762)
			)
			(stroke
				(width 0)
				(type default)
			)
			(fill no)
			(layer "B.CrtYd")
		)
		(fp_poly
			(pts
				(arc
					(start 1.7526 0.762)
					(mid 2.291415 -0.538815)
					(end 0.9906 0)
				)
				(arc
					(start 0.9906 0.0254)
					(mid 1.206345 0.546255)
					(end 1.7272 0.762)
				)
			)
			(stroke
				(width 0)
				(type default)
			)
			(fill no)
			(layer "B.CrtYd")
		)
		(fp_poly
			(pts
				(arc
					(start -4.2672 0)
					(mid 4.2672 0)
					(end -4.2672 0)
				)
			)
			(stroke
				(width 0)
				(type default)
			)
			(fill no)
			(layer "F.CrtYd")
		)
		(fp_circle
			(center 0 0)
			(end -4.2672 0)
			(stroke
				(width 0.1)
				(type default)
			)
			(fill no)
			(layer "F.Fab")
		)
		(fp_text user "+"
			(at -6.029198 -1.306322 180)
			(unlocked yes)
			(layer "F.SilkS")
			(effects
				(font
					(size 0.7874 0.5842)
					(thickness 0.1524)
				)
				(justify left)
			)
		)
		(fp_text user "+"
			(at -5.6642 -0.34925 180)
			(unlocked yes)
			(layer "F.Fab")
			(effects
				(font
					(size 1.905 1.4224)
					(thickness 0.000001)
				)
				(justify left)
			)
		)
		(pad "1" thru_hole rect
			(at -1.75006 0 180)
			(size 1.397 1.397)
			(drill 0.9144)
			(layers "*.Cu" "*.Mask")
			(remove_unused_layers no)
			(net "P12V")
			(clearance 0.0127)
			(thermal_gap 0.0127)
			(padstack
				(mode front_inner_back)
				(layer "Inner"
					(shape circle)
					(size 1.397 1.397)
					(clearance 0.0127)
				)
				(layer "B.Cu"
					(shape rect)
					(size 1.397 1.397)
					(clearance 0.0127)
				)
			)
		)
		(pad "2" thru_hole circle
			(at 1.75006 0 180)
			(size 1.397 1.397)
			(drill 0.9144)
			(layers "*.Cu" "*.Mask")
			(remove_unused_layers no)
			(net "GND")
			(clearance 0.0127)
			(thermal_gap 0.0127)
		)
	)
	(footprint ""
		(layer "F.Cu")
		(at 70.71487 -131.443476 90)
		(property "Reference" "C26"
			(at -3.829812 0.066294 90)
			(unlocked yes)
			(layer "F.SilkS")
			(effects
				(font
					(size 0.7874 0.5842)
					(thickness 0.1524)
				)
				(justify left)
			)
		)
		(property "Value" ""
			(at 0 0 90)
			(layer "F.Fab")
			(effects
				(font
					(size 1.27 1.27)
				)
			)
		)
		(duplicate_pad_numbers_are_jumpers no)
		(fp_line
			(start 0.7874 -0.4064)
			(end 0.7874 0.4064)
			(stroke
				(width 0.1524)
				(type default)
			)
			(layer "F.SilkS")
		)
		(fp_line
			(start -0.7874 -0.4064)
			(end 0.7874 -0.4064)
			(stroke
				(width 0.1524)
				(type default)
			)
			(layer "F.SilkS")
		)
		(fp_line
			(start 0 0.381)
			(end 0 -0.381)
			(stroke
				(width 0.1524)
				(type default)
			)
			(layer "F.SilkS")
		)
		(fp_line
			(start 0.7874 0.4064)
			(end -0.7874 0.4064)
			(stroke
				(width 0.1524)
				(type default)
			)
			(layer "F.SilkS")
		)
		(fp_line
			(start -0.7874 0.4064)
			(end -0.7874 -0.4064)
			(stroke
				(width 0.1524)
				(type default)
			)
			(layer "F.SilkS")
		)
		(fp_poly
			(pts
				(xy -0.5334 0.254) (xy -0.635 0.254) (xy -0.635 0.2286) (xy -0.635 -0.254) (xy -0.5334 -0.254) (xy -0.5334 -0.2794)
				(xy 0.5334 -0.2794) (xy 0.5334 -0.254) (xy 0.635 -0.254) (xy 0.635 0.254) (xy 0.5334 0.254) (xy 0.5334 0.2794)
				(xy -0.508 0.2794) (xy -0.5334 0.2794)
			)
			(stroke
				(width 0)
				(type default)
			)
			(fill no)
			(layer "F.CrtYd")
		)
		(pad "1" smd rect
			(at 0.40005 0 90)
			(size 0.4572 0.508)
			(layers "F.Cu" "F.Mask" "F.Paste")
			(net "P12V")
		)
		(pad "2" smd rect
			(at -0.40005 0 90)
			(size 0.4572 0.508)
			(layers "F.Cu" "F.Mask" "F.Paste")
			(net "GND")
		)
	)
	(footprint ""
		(layer "F.Cu")
		(at 16.599916 -29.19984)
		(property "Reference" "H11"
			(at 6.04139 -6.838696 0)
			(unlocked yes)
			(layer "F.SilkS")
			(effects
				(font
					(size 0.7874 0.5842)
					(thickness 0.1524)
				)
				(justify left)
			)
		)
		(property "Value" ""
			(at 0 0 0)
			(layer "F.Fab")
			(effects
				(font
					(size 1.27 1.27)
				)
			)
		)
		(duplicate_pad_numbers_are_jumpers no)
		(fp_circle
			(center 0 0)
			(end 7.999984 0)
			(stroke
				(width 0.1524)
				(type default)
			)
			(fill no)
			(layer "F.SilkS")
		)
		(fp_circle
			(center 0 0)
			(end 14.7066 0)
			(stroke
				(width 0.1524)
				(type default)
			)
			(fill no)
			(layer "B.SilkS")
		)
		(fp_poly
			(pts
				(arc
					(start 0 5.0038)
					(mid 0 -5.0038)
					(end 0 5.0038)
				)
			)
			(stroke
				(width 0)
				(type default)
			)
			(fill no)
			(layer "F.CrtYd")
		)
		(pad "" np_thru_hole circle
			(at 0 0)
			(size 4.0132 4.0132)
			(drill 4.0132)
			(layers "*.Cu" "*.Mask")
			(clearance 0.381)
			(thermal_gap 0.381)
		)
		(pad "2" thru_hole circle
			(at 0 -3.50012)
			(size 0.762 0.762)
			(drill 0.5588)
			(layers "*.Cu" "*.Mask")
			(remove_unused_layers no)
			(net "GND")
			(clearance 0.1524)
			(thermal_gap 0.1524)
		)
		(pad "3" thru_hole circle
			(at -2.500122 -2.500122)
			(size 0.762 0.762)
			(drill 0.5588)
			(layers "*.Cu" "*.Mask")
			(remove_unused_layers no)
			(net "GND")
			(clearance 0.1524)
			(thermal_gap 0.1524)
		)
		(pad "4" thru_hole circle
			(at -3.50012 0)
			(size 0.762 0.762)
			(drill 0.5588)
			(layers "*.Cu" "*.Mask")
			(remove_unused_layers no)
			(net "GND")
			(clearance 0.1524)
			(thermal_gap 0.1524)
		)
		(pad "5" thru_hole circle
			(at -2.500122 2.500122)
			(size 0.762 0.762)
			(drill 0.5588)
			(layers "*.Cu" "*.Mask")
			(remove_unused_layers no)
			(net "GND")
			(clearance 0.1524)
			(thermal_gap 0.1524)
		)
		(pad "6" thru_hole circle
			(at 0 3.50012)
			(size 0.762 0.762)
			(drill 0.5588)
			(layers "*.Cu" "*.Mask")
			(remove_unused_layers no)
			(net "GND")
			(clearance 0.1524)
			(thermal_gap 0.1524)
		)
		(pad "7" thru_hole circle
			(at 2.500122 2.500122)
			(size 0.762 0.762)
			(drill 0.5588)
			(layers "*.Cu" "*.Mask")
			(remove_unused_layers no)
			(net "GND")
			(clearance 0.1524)
			(thermal_gap 0.1524)
		)
		(pad "8" thru_hole circle
			(at 3.50012 0)
			(size 0.762 0.762)
			(drill 0.5588)
			(layers "*.Cu" "*.Mask")
			(remove_unused_layers no)
			(net "GND")
			(clearance 0.1524)
			(thermal_gap 0.1524)
		)
		(pad "9" thru_hole circle
			(at 2.500122 -2.500122)
			(size 0.762 0.762)
			(drill 0.5588)
			(layers "*.Cu" "*.Mask")
			(remove_unused_layers no)
			(net "GND")
			(clearance 0.1524)
			(thermal_gap 0.1524)
		)
		(zone
			(layer "F.Cu")
			(hatch none 0.5)
			(connect_pads
				(clearance 0)
			)
			(min_thickness 0.25)
			(keepout
				(tracks not_allowed)
				(vias allowed)
				(pads allowed)
				(copperpour not_allowed)
				(footprints allowed)
			)
			(placement
				(enabled no)
				(sheetname "")
			)
			(fill
				(thermal_gap 0.5)
				(thermal_bridge_width 0.5)
				(island_removal_mode 0)
			)
			(polygon
				(pts
					(arc
						(start 16.599916 -37.20084)
						(mid 8.598916 -29.19984)
						(end 16.599916 -21.19884)
					)
					(arc
						(start 16.599916 -21.19884)
						(mid 18.035016 -22.63394)
						(end 16.599916 -24.06904)
					)
					(arc
						(start 16.599916 -24.06904)
						(mid 11.469116 -29.19984)
						(end 16.599916 -34.33064)
					)
					(arc
						(start 16.599916 -34.33064)
						(mid 18.035016 -35.76574)
						(end 16.599916 -37.20084)
					)
				)
			)
		)
		(zone
			(layer "F.Cu")
			(hatch none 0.5)
			(connect_pads
				(clearance 0)
			)
			(min_thickness 0.25)
			(keepout
				(tracks not_allowed)
				(vias allowed)
				(pads allowed)
				(copperpour not_allowed)
				(footprints allowed)
			)
			(placement
				(enabled no)
				(sheetname "")
			)
			(fill
				(thermal_gap 0.5)
				(thermal_bridge_width 0.5)
				(island_removal_mode 0)
			)
			(polygon
				(pts
					(arc
						(start 16.599916 -37.20084)
						(mid 24.600916 -29.19984)
						(end 16.599916 -21.19884)
					)
					(arc
						(start 16.599916 -21.19884)
						(mid 15.164816 -22.63394)
						(end 16.599916 -24.06904)
					)
					(arc
						(start 16.599916 -24.06904)
						(mid 21.730716 -29.19984)
						(end 16.599916 -34.33064)
					)
					(arc
						(start 16.599916 -34.33064)
						(mid 15.164816 -35.76574)
						(end 16.599916 -37.20084)
					)
				)
			)
		)
		(zone
			(layers "F.Cu" "B.Cu" "In1.Cu" "In2.Cu" "In3.Cu" "In4.Cu" "In5.Cu" "In6.Cu")
			(hatch none 0.5)
			(connect_pads
				(clearance 0)
			)
			(min_thickness 0.25)
			(keepout
				(tracks not_allowed)
				(vias allowed)
				(pads allowed)
				(copperpour not_allowed)
				(footprints allowed)
			)
			(placement
				(enabled no)
				(sheetname "")
			)
			(fill
				(thermal_gap 0.5)
				(thermal_bridge_width 0.5)
				(island_removal_mode 0)
			)
			(polygon
				(pts
					(arc
						(start 16.599916 -26.68778)
						(mid 16.599916 -31.7119)
						(end 16.599916 -26.68778)
					)
				)
			)
		)
	)
	(footprint ""
		(layer "F.Cu")
		(at 39.46398 -22.785324 -90)
		(property "Reference" "R86"
			(at -1.022858 -0.025146 90)
			(unlocked yes)
			(layer "F.SilkS")
			(effects
				(font
					(size 0.7874 0.5842)
					(thickness 0.1524)
				)
				(justify left)
			)
		)
		(property "Value" ""
			(at 0 0 270)
			(layer "F.Fab")
			(effects
				(font
					(size 1.27 1.27)
				)
			)
		)
		(duplicate_pad_numbers_are_jumpers no)
		(fp_line
			(start -0.7874 0.4064)
			(end -0.7874 -0.4064)
			(stroke
				(width 0.1524)
				(type default)
			)
			(layer "F.SilkS")
		)
		(fp_line
			(start 0.7874 0.4064)
			(end -0.7874 0.4064)
			(stroke
				(width 0.1524)
				(type default)
			)
			(layer "F.SilkS")
		)
		(fp_line
			(start -0.7874 -0.4064)
			(end 0.7874 -0.4064)
			(stroke
				(width 0.1524)
				(type default)
			)
			(layer "F.SilkS")
		)
		(fp_line
			(start 0.7874 -0.4064)
			(end 0.7874 0.4064)
			(stroke
				(width 0.1524)
				(type default)
			)
			(layer "F.SilkS")
		)
		(fp_poly
			(pts
				(xy -0.508 0.2794) (xy -0.508 0.2286) (xy -0.635 0.2286) (xy -0.635 -0.254) (xy -0.5334 -0.254)
				(xy -0.5334 -0.2794) (xy 0.5334 -0.2794) (xy 0.5334 -0.254) (xy 0.635 -0.254) (xy 0.635 0.254) (xy 0.5334 0.254)
				(xy 0.5334 0.2794)
			)
			(stroke
				(width 0)
				(type default)
			)
			(fill no)
			(layer "F.CrtYd")
		)
		(pad "1" smd rect
			(at 0.40005 0 270)
			(size 0.4572 0.508)
			(layers "F.Cu" "F.Mask" "F.Paste")
			(net "PSU1_REMOTE_P")
		)
		(pad "2" smd rect
			(at -0.40005 0 270)
			(size 0.4572 0.508)
			(layers "F.Cu" "F.Mask" "F.Paste")
			(net "PSU1_REMOTE_R_P")
		)
	)
	(footprint ""
		(layer "F.Cu")
		(at 72.81291 -104.75976 -90)
		(property "Reference" "C16"
			(at -2.68224 0.11684 90)
			(unlocked yes)
			(layer "F.SilkS")
			(effects
				(font
					(size 0.7874 0.5842)
					(thickness 0.1524)
				)
				(justify left)
			)
		)
		(property "Value" ""
			(at 0 0 270)
			(layer "F.Fab")
			(effects
				(font
					(size 1.27 1.27)
				)
			)
		)
		(duplicate_pad_numbers_are_jumpers no)
		(fp_line
			(start -0.7874 0.4064)
			(end -0.7874 -0.4064)
			(stroke
				(width 0.1524)
				(type default)
			)
			(layer "F.SilkS")
		)
		(fp_line
			(start 0.7874 0.4064)
			(end -0.7874 0.4064)
			(stroke
				(width 0.1524)
				(type default)
			)
			(layer "F.SilkS")
		)
		(fp_line
			(start 0 0.381)
			(end 0 -0.381)
			(stroke
				(width 0.1524)
				(type default)
			)
			(layer "F.SilkS")
		)
		(fp_line
			(start -0.7874 -0.4064)
			(end 0.7874 -0.4064)
			(stroke
				(width 0.1524)
				(type default)
			)
			(layer "F.SilkS")
		)
		(fp_line
			(start 0.7874 -0.4064)
			(end 0.7874 0.4064)
			(stroke
				(width 0.1524)
				(type default)
			)
			(layer "F.SilkS")
		)
		(fp_poly
			(pts
				(xy -0.5334 0.254) (xy -0.635 0.254) (xy -0.635 0.2286) (xy -0.635 -0.254) (xy -0.5334 -0.254) (xy -0.5334 -0.2794)
				(xy 0.5334 -0.2794) (xy 0.5334 -0.254) (xy 0.635 -0.254) (xy 0.635 0.254) (xy 0.5334 0.254) (xy 0.5334 0.2794)
				(xy -0.508 0.2794) (xy -0.5334 0.2794)
			)
			(stroke
				(width 0)
				(type default)
			)
			(fill no)
			(layer "F.CrtYd")
		)
		(pad "1" smd rect
			(at 0.40005 0 270)
			(size 0.4572 0.508)
			(layers "F.Cu" "F.Mask" "F.Paste")
			(net "P12V")
		)
		(pad "2" smd rect
			(at -0.40005 0 270)
			(size 0.4572 0.508)
			(layers "F.Cu" "F.Mask" "F.Paste")
			(net "GND")
		)
	)
	(footprint ""
		(layer "F.Cu")
		(at 13.386308 -319.438782 180)
		(property "Reference" "R141"
			(at -1.21285 -0.090678 0)
			(unlocked yes)
			(layer "F.SilkS")
			(effects
				(font
					(size 0.7874 0.5842)
					(thickness 0.1524)
				)
				(justify left)
			)
		)
		(property "Value" ""
			(at 0 0 180)
			(layer "F.Fab")
			(effects
				(font
					(size 1.27 1.27)
				)
			)
		)
		(duplicate_pad_numbers_are_jumpers no)
		(fp_line
			(start 0.7874 0.4064)
			(end -0.7874 0.4064)
			(stroke
				(width 0.1524)
				(type default)
			)
			(layer "F.SilkS")
		)
		(fp_line
			(start 0.7874 -0.4064)
			(end 0.7874 0.4064)
			(stroke
				(width 0.1524)
				(type default)
			)
			(layer "F.SilkS")
		)
		(fp_line
			(start -0.7874 0.4064)
			(end -0.7874 -0.4064)
			(stroke
				(width 0.1524)
				(type default)
			)
			(layer "F.SilkS")
		)
		(fp_line
			(start -0.7874 -0.4064)
			(end 0.7874 -0.4064)
			(stroke
				(width 0.1524)
				(type default)
			)
			(layer "F.SilkS")
		)
		(fp_poly
			(pts
				(xy -0.508 0.2794) (xy -0.508 0.2286) (xy -0.635 0.2286) (xy -0.635 -0.254) (xy -0.5334 -0.254)
				(xy -0.5334 -0.2794) (xy 0.5334 -0.2794) (xy 0.5334 -0.254) (xy 0.635 -0.254) (xy 0.635 0.254) (xy 0.5334 0.254)
				(xy 0.5334 0.2794)
			)
			(stroke
				(width 0)
				(type default)
			)
			(fill no)
			(layer "F.CrtYd")
		)
		(pad "1" smd rect
			(at 0.40005 0 180)
			(size 0.4572 0.508)
			(layers "F.Cu" "F.Mask" "F.Paste")
			(net "FAN_PWM")
		)
		(pad "2" smd rect
			(at -0.40005 0 180)
			(size 0.4572 0.508)
			(layers "F.Cu" "F.Mask" "F.Paste")
			(net "P12V")
		)
	)
	(footprint ""
		(layer "F.Cu")
		(at 46.408086 -239.669066 180)
		(property "Reference" "R89"
			(at 4.341114 0.123698 0)
			(unlocked yes)
			(layer "F.SilkS")
			(effects
				(font
					(size 0.7874 0.5842)
					(thickness 0.1524)
				)
				(justify left)
			)
		)
		(property "Value" ""
			(at 0 0 180)
			(layer "F.Fab")
			(effects
				(font
					(size 1.27 1.27)
				)
			)
		)
		(duplicate_pad_numbers_are_jumpers no)
		(fp_line
			(start 0.7874 0.4064)
			(end -0.7874 0.4064)
			(stroke
				(width 0.1524)
				(type default)
			)
			(layer "F.SilkS")
		)
		(fp_line
			(start 0.7874 -0.4064)
			(end 0.7874 0.4064)
			(stroke
				(width 0.1524)
				(type default)
			)
			(layer "F.SilkS")
		)
		(fp_line
			(start -0.7874 0.4064)
			(end -0.7874 -0.4064)
			(stroke
				(width 0.1524)
				(type default)
			)
			(layer "F.SilkS")
		)
		(fp_line
			(start -0.7874 -0.4064)
			(end 0.7874 -0.4064)
			(stroke
				(width 0.1524)
				(type default)
			)
			(layer "F.SilkS")
		)
		(fp_poly
			(pts
				(xy -0.508 0.2794) (xy -0.508 0.2286) (xy -0.635 0.2286) (xy -0.635 -0.254) (xy -0.5334 -0.254)
				(xy -0.5334 -0.2794) (xy 0.5334 -0.2794) (xy 0.5334 -0.254) (xy 0.635 -0.254) (xy 0.635 0.254) (xy 0.5334 0.254)
				(xy 0.5334 0.2794)
			)
			(stroke
				(width 0)
				(type default)
			)
			(fill no)
			(layer "F.CrtYd")
		)
		(pad "1" smd rect
			(at 0.40005 0 180)
			(size 0.4572 0.508)
			(layers "F.Cu" "F.Mask" "F.Paste")
			(net "PSU1_REMOTE_R_N")
		)
		(pad "2" smd rect
			(at -0.40005 0 180)
			(size 0.4572 0.508)
			(layers "F.Cu" "F.Mask" "F.Paste")
			(net "GND")
		)
	)
	(footprint ""
		(layer "F.Cu")
		(at 39.436802 -287.17748 90)
		(property "Reference" "R122"
			(at -3.06705 1.662938 90)
			(unlocked yes)
			(layer "F.SilkS")
			(effects
				(font
					(size 0.7874 0.5842)
					(thickness 0.1524)
				)
				(justify left)
			)
		)
		(property "Value" ""
			(at 0 0 90)
			(layer "F.Fab")
			(effects
				(font
					(size 1.27 1.27)
				)
			)
		)
		(duplicate_pad_numbers_are_jumpers no)
		(fp_line
			(start 0.7874 -0.4064)
			(end 0.7874 0.4064)
			(stroke
				(width 0.1524)
				(type default)
			)
			(layer "F.SilkS")
		)
		(fp_line
			(start -0.7874 -0.4064)
			(end 0.7874 -0.4064)
			(stroke
				(width 0.1524)
				(type default)
			)
			(layer "F.SilkS")
		)
		(fp_line
			(start 0.7874 0.4064)
			(end -0.7874 0.4064)
			(stroke
				(width 0.1524)
				(type default)
			)
			(layer "F.SilkS")
		)
		(fp_line
			(start -0.7874 0.4064)
			(end -0.7874 -0.4064)
			(stroke
				(width 0.1524)
				(type default)
			)
			(layer "F.SilkS")
		)
		(fp_poly
			(pts
				(xy -0.508 0.2794) (xy -0.508 0.2286) (xy -0.635 0.2286) (xy -0.635 -0.254) (xy -0.5334 -0.254)
				(xy -0.5334 -0.2794) (xy 0.5334 -0.2794) (xy 0.5334 -0.254) (xy 0.635 -0.254) (xy 0.635 0.254) (xy 0.5334 0.254)
				(xy 0.5334 0.2794)
			)
			(stroke
				(width 0)
				(type default)
			)
			(fill no)
			(layer "F.CrtYd")
		)
		(pad "1" smd rect
			(at 0.40005 0 90)
			(size 0.4572 0.508)
			(layers "F.Cu" "F.Mask" "F.Paste")
			(net "PSU4_REMOTE_P")
		)
		(pad "2" smd rect
			(at -0.40005 0 90)
			(size 0.4572 0.508)
			(layers "F.Cu" "F.Mask" "F.Paste")
			(net "PSU4_REMOTE_R2_P")
		)
	)
	(footprint ""
		(layer "F.Cu")
		(at 50.150522 -128.655318 180)
		(property "Reference" "CE6"
			(at 0.794004 -5.521452 0)
			(unlocked yes)
			(layer "F.SilkS")
			(effects
				(font
					(size 0.7874 0.5842)
					(thickness 0.1524)
				)
				(justify left)
			)
		)
		(property "Value" ""
			(at 0 0 180)
			(layer "F.Fab")
			(effects
				(font
					(size 1.27 1.27)
				)
			)
		)
		(duplicate_pad_numbers_are_jumpers no)
		(fp_line
			(start 0 -4.2672)
			(end 0 4.2672)
			(stroke
				(width 0.1524)
				(type default)
			)
			(layer "F.SilkS")
		)
		(fp_circle
			(center 0 0)
			(end -4.2672 0)
			(stroke
				(width 0.1524)
				(type default)
			)
			(fill no)
			(layer "F.SilkS")
		)
		(fp_poly
			(pts
				(arc
					(start 0 -4.2672)
					(mid 4.2672 0)
					(end 0 4.2672)
				)
			)
			(stroke
				(width 0)
				(type default)
			)
			(fill yes)
			(layer "F.SilkS")
		)
		(fp_poly
			(pts
				(xy -2.5146 -0.762) (xy -0.9906 -0.762) (xy -0.9906 0.762) (xy -2.5146 0.762)
			)
			(stroke
				(width 0)
				(type default)
			)
			(fill no)
			(layer "B.CrtYd")
		)
		(fp_poly
			(pts
				(arc
					(start 1.7526 0.762)
					(mid 2.291415 -0.538815)
					(end 0.9906 0)
				)
				(arc
					(start 0.9906 0.0254)
					(mid 1.206345 0.546255)
					(end 1.7272 0.762)
				)
			)
			(stroke
				(width 0)
				(type default)
			)
			(fill no)
			(layer "B.CrtYd")
		)
		(fp_poly
			(pts
				(arc
					(start -4.2672 0)
					(mid 4.2672 0)
					(end -4.2672 0)
				)
			)
			(stroke
				(width 0)
				(type default)
			)
			(fill no)
			(layer "F.CrtYd")
		)
		(fp_circle
			(center 0 0)
			(end -4.2672 0)
			(stroke
				(width 0.1)
				(type default)
			)
			(fill no)
			(layer "F.Fab")
		)
		(fp_text user "+"
			(at -4.720082 -1.919224 180)
			(unlocked yes)
			(layer "F.SilkS")
			(effects
				(font
					(size 0.7874 0.5842)
					(thickness 0.1524)
				)
				(justify left)
			)
		)
		(fp_text user "+"
			(at -5.6642 -0.34925 180)
			(unlocked yes)
			(layer "F.Fab")
			(effects
				(font
					(size 1.905 1.4224)
					(thickness 0.000001)
				)
				(justify left)
			)
		)
		(pad "1" thru_hole rect
			(at -1.75006 0 180)
			(size 1.397 1.397)
			(drill 0.9144)
			(layers "*.Cu" "*.Mask")
			(remove_unused_layers no)
			(net "P12V")
			(clearance 0.0127)
			(thermal_gap 0.0127)
			(padstack
				(mode front_inner_back)
				(layer "Inner"
					(shape circle)
					(size 1.397 1.397)
					(clearance 0.0127)
				)
				(layer "B.Cu"
					(shape rect)
					(size 1.397 1.397)
					(clearance 0.0127)
				)
			)
		)
		(pad "2" thru_hole circle
			(at 1.75006 0 180)
			(size 1.397 1.397)
			(drill 0.9144)
			(layers "*.Cu" "*.Mask")
			(remove_unused_layers no)
			(net "GND")
			(clearance 0.0127)
			(thermal_gap 0.0127)
		)
	)
	(footprint ""
		(layer "F.Cu")
		(at 27.243786 -285.030164)
		(property "Reference" "R20"
			(at -3.418332 0.009144 0)
			(unlocked yes)
			(layer "F.SilkS")
			(effects
				(font
					(size 0.7874 0.5842)
					(thickness 0.1524)
				)
				(justify left)
			)
		)
		(property "Value" ""
			(at 0 0 0)
			(layer "F.Fab")
			(effects
				(font
					(size 1.27 1.27)
				)
			)
		)
		(duplicate_pad_numbers_are_jumpers no)
		(fp_line
			(start -0.7874 -0.4064)
			(end 0.7874 -0.4064)
			(stroke
				(width 0.1524)
				(type default)
			)
			(layer "F.SilkS")
		)
		(fp_line
			(start -0.7874 0.4064)
			(end -0.7874 -0.4064)
			(stroke
				(width 0.1524)
				(type default)
			)
			(layer "F.SilkS")
		)
		(fp_line
			(start 0.7874 -0.4064)
			(end 0.7874 0.4064)
			(stroke
				(width 0.1524)
				(type default)
			)
			(layer "F.SilkS")
		)
		(fp_line
			(start 0.7874 0.4064)
			(end -0.7874 0.4064)
			(stroke
				(width 0.1524)
				(type default)
			)
			(layer "F.SilkS")
		)
		(fp_poly
			(pts
				(xy -0.508 0.2794) (xy -0.508 0.2286) (xy -0.635 0.2286) (xy -0.635 -0.254) (xy -0.5334 -0.254)
				(xy -0.5334 -0.2794) (xy 0.5334 -0.2794) (xy 0.5334 -0.254) (xy 0.635 -0.254) (xy 0.635 0.254) (xy 0.5334 0.254)
				(xy 0.5334 0.2794)
			)
			(stroke
				(width 0)
				(type default)
			)
			(fill no)
			(layer "F.CrtYd")
		)
		(pad "1" smd rect
			(at 0.40005 0)
			(size 0.4572 0.508)
			(layers "F.Cu" "F.Mask" "F.Paste")
			(net "PSU4_REMOTE_N")
		)
		(pad "2" smd rect
			(at -0.40005 0)
			(size 0.4572 0.508)
			(layers "F.Cu" "F.Mask" "F.Paste")
			(net "GND")
		)
	)
	(footprint ""
		(layer "F.Cu")
		(at 73.57745 -397.262604 90)
		(property "Reference" "C69"
			(at -1.662176 -4.920742 90)
			(unlocked yes)
			(layer "F.SilkS")
			(effects
				(font
					(size 0.7874 0.5842)
					(thickness 0.1524)
				)
				(justify left)
			)
		)
		(property "Value" ""
			(at 0 0 90)
			(layer "F.Fab")
			(effects
				(font
					(size 1.27 1.27)
				)
			)
		)
		(duplicate_pad_numbers_are_jumpers no)
		(fp_line
			(start 0.7874 -0.4064)
			(end 0.7874 0.4064)
			(stroke
				(width 0.1524)
				(type default)
			)
			(layer "F.SilkS")
		)
		(fp_line
			(start -0.7874 -0.4064)
			(end 0.7874 -0.4064)
			(stroke
				(width 0.1524)
				(type default)
			)
			(layer "F.SilkS")
		)
		(fp_line
			(start 0 0.381)
			(end 0 -0.381)
			(stroke
				(width 0.1524)
				(type default)
			)
			(layer "F.SilkS")
		)
		(fp_line
			(start 0.7874 0.4064)
			(end -0.7874 0.4064)
			(stroke
				(width 0.1524)
				(type default)
			)
			(layer "F.SilkS")
		)
		(fp_line
			(start -0.7874 0.4064)
			(end -0.7874 -0.4064)
			(stroke
				(width 0.1524)
				(type default)
			)
			(layer "F.SilkS")
		)
		(fp_poly
			(pts
				(xy -0.5334 0.254) (xy -0.635 0.254) (xy -0.635 0.2286) (xy -0.635 -0.254) (xy -0.5334 -0.254) (xy -0.5334 -0.2794)
				(xy 0.5334 -0.2794) (xy 0.5334 -0.254) (xy 0.635 -0.254) (xy 0.635 0.254) (xy 0.5334 0.254) (xy 0.5334 0.2794)
				(xy -0.508 0.2794) (xy -0.5334 0.2794)
			)
			(stroke
				(width 0)
				(type default)
			)
			(fill no)
			(layer "F.CrtYd")
		)
		(pad "1" smd rect
			(at 0.40005 0 90)
			(size 0.4572 0.508)
			(layers "F.Cu" "F.Mask" "F.Paste")
			(net "P12V")
		)
		(pad "2" smd rect
			(at -0.40005 0 90)
			(size 0.4572 0.508)
			(layers "F.Cu" "F.Mask" "F.Paste")
			(net "GND")
		)
	)
	(footprint ""
		(layer "F.Cu")
		(at 46.425612 -253.125732 180)
		(property "Reference" "R99"
			(at 2.224278 1.16205 0)
			(unlocked yes)
			(layer "F.SilkS")
			(effects
				(font
					(size 0.7874 0.5842)
					(thickness 0.1524)
				)
				(justify left)
			)
		)
		(property "Value" ""
			(at 0 0 180)
			(layer "F.Fab")
			(effects
				(font
					(size 1.27 1.27)
				)
			)
		)
		(duplicate_pad_numbers_are_jumpers no)
		(fp_line
			(start 0.7874 0.4064)
			(end -0.7874 0.4064)
			(stroke
				(width 0.1524)
				(type default)
			)
			(layer "F.SilkS")
		)
		(fp_line
			(start 0.7874 -0.4064)
			(end 0.7874 0.4064)
			(stroke
				(width 0.1524)
				(type default)
			)
			(layer "F.SilkS")
		)
		(fp_line
			(start -0.7874 0.4064)
			(end -0.7874 -0.4064)
			(stroke
				(width 0.1524)
				(type default)
			)
			(layer "F.SilkS")
		)
		(fp_line
			(start -0.7874 -0.4064)
			(end 0.7874 -0.4064)
			(stroke
				(width 0.1524)
				(type default)
			)
			(layer "F.SilkS")
		)
		(fp_poly
			(pts
				(xy -0.508 0.2794) (xy -0.508 0.2286) (xy -0.635 0.2286) (xy -0.635 -0.254) (xy -0.5334 -0.254)
				(xy -0.5334 -0.2794) (xy 0.5334 -0.2794) (xy 0.5334 -0.254) (xy 0.635 -0.254) (xy 0.635 0.254) (xy 0.5334 0.254)
				(xy 0.5334 0.2794)
			)
			(stroke
				(width 0)
				(type default)
			)
			(fill no)
			(layer "F.CrtYd")
		)
		(pad "1" smd rect
			(at 0.40005 0 180)
			(size 0.4572 0.508)
			(layers "F.Cu" "F.Mask" "F.Paste")
			(net "PSU6_REMOTE_R_N")
		)
		(pad "2" smd rect
			(at -0.40005 0 180)
			(size 0.4572 0.508)
			(layers "F.Cu" "F.Mask" "F.Paste")
			(net "GND")
		)
	)
	(footprint ""
		(layer "F.Cu")
		(at 40.056562 -281.140662 180)
		(property "Reference" "R25"
			(at -1.619504 -0.058166 0)
			(unlocked yes)
			(layer "F.SilkS")
			(effects
				(font
					(size 0.7874 0.5842)
					(thickness 0.1524)
				)
				(justify left)
			)
		)
		(property "Value" ""
			(at 0 0 180)
			(layer "F.Fab")
			(effects
				(font
					(size 1.27 1.27)
				)
			)
		)
		(duplicate_pad_numbers_are_jumpers no)
		(fp_line
			(start 0.7874 0.4064)
			(end -0.7874 0.4064)
			(stroke
				(width 0.1524)
				(type default)
			)
			(layer "F.SilkS")
		)
		(fp_line
			(start 0.7874 -0.4064)
			(end 0.7874 0.4064)
			(stroke
				(width 0.1524)
				(type default)
			)
			(layer "F.SilkS")
		)
		(fp_line
			(start -0.7874 0.4064)
			(end -0.7874 -0.4064)
			(stroke
				(width 0.1524)
				(type default)
			)
			(layer "F.SilkS")
		)
		(fp_line
			(start -0.7874 -0.4064)
			(end 0.7874 -0.4064)
			(stroke
				(width 0.1524)
				(type default)
			)
			(layer "F.SilkS")
		)
		(fp_poly
			(pts
				(xy -0.508 0.2794) (xy -0.508 0.2286) (xy -0.635 0.2286) (xy -0.635 -0.254) (xy -0.5334 -0.254)
				(xy -0.5334 -0.2794) (xy 0.5334 -0.2794) (xy 0.5334 -0.254) (xy 0.635 -0.254) (xy 0.635 0.254) (xy 0.5334 0.254)
				(xy 0.5334 0.2794)
			)
			(stroke
				(width 0)
				(type default)
			)
			(fill no)
			(layer "F.CrtYd")
		)
		(pad "1" smd rect
			(at 0.40005 0 180)
			(size 0.4572 0.508)
			(layers "F.Cu" "F.Mask" "F.Paste")
			(net "PSU4_RETURN")
		)
		(pad "2" smd rect
			(at -0.40005 0 180)
			(size 0.4572 0.508)
			(layers "F.Cu" "F.Mask" "F.Paste")
			(net "GND")
		)
	)
	(footprint ""
		(layer "F.Cu")
		(at 91.399868 -64.46012)
		(property "Reference" "H16"
			(at -5.1308 -5.23113 0)
			(unlocked yes)
			(layer "F.SilkS")
			(effects
				(font
					(size 0.7874 0.5842)
					(thickness 0.1524)
				)
				(justify left)
			)
		)
		(property "Value" ""
			(at 0 0 0)
			(layer "F.Fab")
			(effects
				(font
					(size 1.27 1.27)
				)
			)
		)
		(duplicate_pad_numbers_are_jumpers no)
		(fp_circle
			(center 0 0)
			(end 4.826 0)
			(stroke
				(width 0.1524)
				(type default)
			)
			(fill no)
			(layer "F.SilkS")
		)
		(fp_circle
			(center 0 0)
			(end 4.826 0)
			(stroke
				(width 0.1524)
				(type default)
			)
			(fill no)
			(layer "B.SilkS")
		)
		(fp_poly
			(pts
				(arc
					(start 0 4.0132)
					(mid 0 -4.0132)
					(end 0 4.0132)
				)
			)
			(stroke
				(width 0)
				(type default)
			)
			(fill no)
			(layer "F.CrtYd")
		)
		(pad "" np_thru_hole circle
			(at 0 0)
			(size 8.001 8.001)
			(drill 8.001)
			(layers "*.Cu" "*.Mask")
			(clearance 0.381)
			(thermal_gap 0.381)
		)
		(zone
			(layers "F.Cu" "B.Cu" "In1.Cu" "In2.Cu" "In3.Cu" "In4.Cu" "In5.Cu" "In6.Cu")
			(hatch none 0.5)
			(connect_pads
				(clearance 0)
			)
			(min_thickness 0.25)
			(keepout
				(tracks not_allowed)
				(vias allowed)
				(pads allowed)
				(copperpour not_allowed)
				(footprints allowed)
			)
			(placement
				(enabled no)
				(sheetname "")
			)
			(fill
				(thermal_gap 0.5)
				(thermal_bridge_width 0.5)
				(island_removal_mode 0)
			)
			(polygon
				(pts
					(arc
						(start 91.399868 -59.93892)
						(mid 91.399868 -68.98132)
						(end 91.399868 -59.93892)
					)
				)
			)
		)
	)
	(footprint ""
		(layer "F.Cu")
		(at 26.102056 -271.14881)
		(property "Reference" "R77"
			(at -4.037838 -0.005334 0)
			(unlocked yes)
			(layer "F.SilkS")
			(effects
				(font
					(size 0.7874 0.5842)
					(thickness 0.1524)
				)
				(justify left)
			)
		)
		(property "Value" ""
			(at 0 0 0)
			(layer "F.Fab")
			(effects
				(font
					(size 1.27 1.27)
				)
			)
		)
		(duplicate_pad_numbers_are_jumpers no)
		(fp_line
			(start -0.7874 -0.4064)
			(end 0.7874 -0.4064)
			(stroke
				(width 0.1524)
				(type default)
			)
			(layer "F.SilkS")
		)
		(fp_line
			(start -0.7874 0.4064)
			(end -0.7874 -0.4064)
			(stroke
				(width 0.1524)
				(type default)
			)
			(layer "F.SilkS")
		)
		(fp_line
			(start 0.7874 -0.4064)
			(end 0.7874 0.4064)
			(stroke
				(width 0.1524)
				(type default)
			)
			(layer "F.SilkS")
		)
		(fp_line
			(start 0.7874 0.4064)
			(end -0.7874 0.4064)
			(stroke
				(width 0.1524)
				(type default)
			)
			(layer "F.SilkS")
		)
		(fp_poly
			(pts
				(xy -0.508 0.2794) (xy -0.508 0.2286) (xy -0.635 0.2286) (xy -0.635 -0.254) (xy -0.5334 -0.254)
				(xy -0.5334 -0.2794) (xy 0.5334 -0.2794) (xy 0.5334 -0.254) (xy 0.635 -0.254) (xy 0.635 0.254) (xy 0.5334 0.254)
				(xy 0.5334 0.2794)
			)
			(stroke
				(width 0)
				(type default)
			)
			(fill no)
			(layer "F.CrtYd")
		)
		(pad "1" smd rect
			(at 0.40005 0)
			(size 0.4572 0.508)
			(layers "F.Cu" "F.Mask" "F.Paste")
			(net "PSU4_RESET")
		)
		(pad "2" smd rect
			(at -0.40005 0)
			(size 0.4572 0.508)
			(layers "F.Cu" "F.Mask" "F.Paste")
			(net "GND")
		)
	)
	(footprint ""
		(layer "F.Cu")
		(at 50.554382 -418.636958 180)
		(property "Reference" "CE19"
			(at 6.458458 3.641344 0)
			(unlocked yes)
			(layer "F.SilkS")
			(effects
				(font
					(size 0.7874 0.5842)
					(thickness 0.1524)
				)
				(justify left)
			)
		)
		(property "Value" ""
			(at 0 0 180)
			(layer "F.Fab")
			(effects
				(font
					(size 1.27 1.27)
				)
			)
		)
		(duplicate_pad_numbers_are_jumpers no)
		(fp_line
			(start 0 -4.2672)
			(end 0 4.2672)
			(stroke
				(width 0.1524)
				(type default)
			)
			(layer "F.SilkS")
		)
		(fp_circle
			(center 0 0)
			(end -4.2672 0)
			(stroke
				(width 0.1524)
				(type default)
			)
			(fill no)
			(layer "F.SilkS")
		)
		(fp_poly
			(pts
				(arc
					(start 0 -4.2672)
					(mid 4.2672 0)
					(end 0 4.2672)
				)
			)
			(stroke
				(width 0)
				(type default)
			)
			(fill yes)
			(layer "F.SilkS")
		)
		(fp_poly
			(pts
				(xy -2.5146 -0.762) (xy -0.9906 -0.762) (xy -0.9906 0.762) (xy -2.5146 0.762)
			)
			(stroke
				(width 0)
				(type default)
			)
			(fill no)
			(layer "B.CrtYd")
		)
		(fp_poly
			(pts
				(arc
					(start 1.7526 0.762)
					(mid 2.291415 -0.538815)
					(end 0.9906 0)
				)
				(arc
					(start 0.9906 0.0254)
					(mid 1.206345 0.546255)
					(end 1.7272 0.762)
				)
			)
			(stroke
				(width 0)
				(type default)
			)
			(fill no)
			(layer "B.CrtYd")
		)
		(fp_poly
			(pts
				(arc
					(start -4.2672 0)
					(mid 4.2672 0)
					(end -4.2672 0)
				)
			)
			(stroke
				(width 0)
				(type default)
			)
			(fill no)
			(layer "F.CrtYd")
		)
		(fp_circle
			(center 0 0)
			(end -4.2672 0)
			(stroke
				(width 0.1)
				(type default)
			)
			(fill no)
			(layer "F.Fab")
		)
		(fp_text user "+"
			(at -5.103114 1.718056 180)
			(unlocked yes)
			(layer "F.SilkS")
			(effects
				(font
					(size 0.7874 0.5842)
					(thickness 0.1524)
				)
				(justify left)
			)
		)
		(fp_text user "+"
			(at -5.6642 -0.34925 180)
			(unlocked yes)
			(layer "F.Fab")
			(effects
				(font
					(size 1.905 1.4224)
					(thickness 0.000001)
				)
				(justify left)
			)
		)
		(pad "1" thru_hole rect
			(at -1.75006 0 180)
			(size 1.397 1.397)
			(drill 0.9144)
			(layers "*.Cu" "*.Mask")
			(remove_unused_layers no)
			(net "P12V")
			(clearance 0.0127)
			(thermal_gap 0.0127)
			(padstack
				(mode front_inner_back)
				(layer "Inner"
					(shape circle)
					(size 1.397 1.397)
					(clearance 0.0127)
				)
				(layer "B.Cu"
					(shape rect)
					(size 1.397 1.397)
					(clearance 0.0127)
				)
			)
		)
		(pad "2" thru_hole circle
			(at 1.75006 0 180)
			(size 1.397 1.397)
			(drill 0.9144)
			(layers "*.Cu" "*.Mask")
			(remove_unused_layers no)
			(net "GND")
			(clearance 0.0127)
			(thermal_gap 0.0127)
		)
	)
	(footprint ""
		(layer "F.Cu")
		(at 26.226008 -447.250058)
		(property "Reference" "R61"
			(at -3.597402 -0.121666 0)
			(unlocked yes)
			(layer "F.SilkS")
			(effects
				(font
					(size 0.7874 0.5842)
					(thickness 0.1524)
				)
				(justify left)
			)
		)
		(property "Value" ""
			(at 0 0 0)
			(layer "F.Fab")
			(effects
				(font
					(size 1.27 1.27)
				)
			)
		)
		(duplicate_pad_numbers_are_jumpers no)
		(fp_line
			(start -0.7874 -0.4064)
			(end 0.7874 -0.4064)
			(stroke
				(width 0.1524)
				(type default)
			)
			(layer "F.SilkS")
		)
		(fp_line
			(start -0.7874 0.4064)
			(end -0.7874 -0.4064)
			(stroke
				(width 0.1524)
				(type default)
			)
			(layer "F.SilkS")
		)
		(fp_line
			(start 0.7874 -0.4064)
			(end 0.7874 0.4064)
			(stroke
				(width 0.1524)
				(type default)
			)
			(layer "F.SilkS")
		)
		(fp_line
			(start 0.7874 0.4064)
			(end -0.7874 0.4064)
			(stroke
				(width 0.1524)
				(type default)
			)
			(layer "F.SilkS")
		)
		(fp_poly
			(pts
				(xy -0.508 0.2794) (xy -0.508 0.2286) (xy -0.635 0.2286) (xy -0.635 -0.254) (xy -0.5334 -0.254)
				(xy -0.5334 -0.2794) (xy 0.5334 -0.2794) (xy 0.5334 -0.254) (xy 0.635 -0.254) (xy 0.635 0.254) (xy 0.5334 0.254)
				(xy 0.5334 0.2794)
			)
			(stroke
				(width 0)
				(type default)
			)
			(fill no)
			(layer "F.CrtYd")
		)
		(pad "1" smd rect
			(at 0.40005 0)
			(size 0.4572 0.508)
			(layers "F.Cu" "F.Mask" "F.Paste")
			(net "PSU6_RESET")
		)
		(pad "2" smd rect
			(at -0.40005 0)
			(size 0.4572 0.508)
			(layers "F.Cu" "F.Mask" "F.Paste")
			(net "GND")
		)
	)
	(footprint ""
		(layer "F.Cu")
		(at 77.999844 -430.150016)
		(property "Reference" "H3"
			(at -6.4516 -7.127748 0)
			(unlocked yes)
			(layer "F.SilkS")
			(effects
				(font
					(size 0.7874 0.5842)
					(thickness 0.1524)
				)
				(justify left)
			)
		)
		(property "Value" ""
			(at 0 0 0)
			(layer "F.Fab")
			(effects
				(font
					(size 1.27 1.27)
				)
			)
		)
		(duplicate_pad_numbers_are_jumpers no)
		(fp_circle
			(center 0 0)
			(end 7.999984 0)
			(stroke
				(width 0.1524)
				(type default)
			)
			(fill no)
			(layer "F.SilkS")
		)
		(fp_arc
			(start -4.620006 -13.962126)
			(mid 8.612183 -11.921174)
			(end 14.7066 0)
			(stroke
				(width 0.1524)
				(type default)
			)
			(layer "B.SilkS")
		)
		(fp_arc
			(start 14.7066 0)
			(mid -8.042606 12.311424)
			(end -5.908802 -13.467334)
			(stroke
				(width 0.1524)
				(type default)
			)
			(layer "B.SilkS")
		)
		(fp_poly
			(pts
				(arc
					(start 5.0038 0)
					(mid -5.0038 0)
					(end 5.0038 0)
				)
			)
			(stroke
				(width 0)
				(type default)
			)
			(fill no)
			(layer "F.CrtYd")
		)
		(pad "" np_thru_hole circle
			(at 0 0)
			(size 4.0132 4.0132)
			(drill 4.0132)
			(layers "*.Cu" "*.Mask")
			(clearance 0.381)
			(thermal_gap 0.381)
		)
		(pad "2" thru_hole circle
			(at 0 -3.50012)
			(size 0.762 0.762)
			(drill 0.5588)
			(layers "*.Cu" "*.Mask")
			(remove_unused_layers no)
			(net "GND")
			(clearance 0.1524)
			(thermal_gap 0.1524)
		)
		(pad "3" thru_hole circle
			(at -2.500122 -2.500122)
			(size 0.762 0.762)
			(drill 0.5588)
			(layers "*.Cu" "*.Mask")
			(remove_unused_layers no)
			(net "GND")
			(clearance 0.1524)
			(thermal_gap 0.1524)
		)
		(pad "4" thru_hole circle
			(at -3.50012 0)
			(size 0.762 0.762)
			(drill 0.5588)
			(layers "*.Cu" "*.Mask")
			(remove_unused_layers no)
			(net "GND")
			(clearance 0.1524)
			(thermal_gap 0.1524)
		)
		(pad "5" thru_hole circle
			(at -2.500122 2.500122)
			(size 0.762 0.762)
			(drill 0.5588)
			(layers "*.Cu" "*.Mask")
			(remove_unused_layers no)
			(net "GND")
			(clearance 0.1524)
			(thermal_gap 0.1524)
		)
		(pad "6" thru_hole circle
			(at 0 3.50012)
			(size 0.762 0.762)
			(drill 0.5588)
			(layers "*.Cu" "*.Mask")
			(remove_unused_layers no)
			(net "GND")
			(clearance 0.1524)
			(thermal_gap 0.1524)
		)
		(pad "7" thru_hole circle
			(at 2.500122 2.500122)
			(size 0.762 0.762)
			(drill 0.5588)
			(layers "*.Cu" "*.Mask")
			(remove_unused_layers no)
			(net "GND")
			(clearance 0.1524)
			(thermal_gap 0.1524)
		)
		(pad "8" thru_hole circle
			(at 3.50012 0)
			(size 0.762 0.762)
			(drill 0.5588)
			(layers "*.Cu" "*.Mask")
			(remove_unused_layers no)
			(net "GND")
			(clearance 0.1524)
			(thermal_gap 0.1524)
		)
		(pad "9" thru_hole circle
			(at 2.500122 -2.500122)
			(size 0.762 0.762)
			(drill 0.5588)
			(layers "*.Cu" "*.Mask")
			(remove_unused_layers no)
			(net "GND")
			(clearance 0.1524)
			(thermal_gap 0.1524)
		)
		(zone
			(layer "F.Cu")
			(hatch none 0.5)
			(connect_pads
				(clearance 0)
			)
			(min_thickness 0.25)
			(keepout
				(tracks not_allowed)
				(vias allowed)
				(pads allowed)
				(copperpour not_allowed)
				(footprints allowed)
			)
			(placement
				(enabled no)
				(sheetname "")
			)
			(fill
				(thermal_gap 0.5)
				(thermal_bridge_width 0.5)
				(island_removal_mode 0)
			)
			(polygon
				(pts
					(arc
						(start 77.999844 -438.151016)
						(mid 69.998844 -430.150016)
						(end 77.999844 -422.149016)
					)
					(arc
						(start 77.999844 -422.149016)
						(mid 79.434944 -423.584116)
						(end 77.999844 -425.019216)
					)
					(arc
						(start 77.999844 -425.019216)
						(mid 72.869044 -430.150016)
						(end 77.999844 -435.280816)
					)
					(arc
						(start 77.999844 -435.280816)
						(mid 79.434944 -436.715916)
						(end 77.999844 -438.151016)
					)
				)
			)
		)
		(zone
			(layer "F.Cu")
			(hatch none 0.5)
			(connect_pads
				(clearance 0)
			)
			(min_thickness 0.25)
			(keepout
				(tracks not_allowed)
				(vias allowed)
				(pads allowed)
				(copperpour not_allowed)
				(footprints allowed)
			)
			(placement
				(enabled no)
				(sheetname "")
			)
			(fill
				(thermal_gap 0.5)
				(thermal_bridge_width 0.5)
				(island_removal_mode 0)
			)
			(polygon
				(pts
					(arc
						(start 77.999844 -438.151016)
						(mid 86.000844 -430.150016)
						(end 77.999844 -422.149016)
					)
					(arc
						(start 77.999844 -422.149016)
						(mid 76.564744 -423.584116)
						(end 77.999844 -425.019216)
					)
					(arc
						(start 77.999844 -425.019216)
						(mid 83.130644 -430.150016)
						(end 77.999844 -435.280816)
					)
					(arc
						(start 77.999844 -435.280816)
						(mid 76.564744 -436.715916)
						(end 77.999844 -438.151016)
					)
				)
			)
		)
		(zone
			(layers "F.Cu" "B.Cu" "In1.Cu" "In2.Cu" "In3.Cu" "In4.Cu" "In5.Cu" "In6.Cu")
			(hatch none 0.5)
			(connect_pads
				(clearance 0)
			)
			(min_thickness 0.25)
			(keepout
				(tracks not_allowed)
				(vias allowed)
				(pads allowed)
				(copperpour not_allowed)
				(footprints allowed)
			)
			(placement
				(enabled no)
				(sheetname "")
			)
			(fill
				(thermal_gap 0.5)
				(thermal_bridge_width 0.5)
				(island_removal_mode 0)
			)
			(polygon
				(pts
					(arc
						(start 80.511904 -430.150016)
						(mid 75.487784 -430.150016)
						(end 80.511904 -430.150016)
					)
				)
			)
		)
	)
	(footprint ""
		(layer "F.Cu")
		(at 46.365922 -257.889502 180)
		(property "Reference" "R107"
			(at -1.032002 -0.406908 0)
			(unlocked yes)
			(layer "F.SilkS")
			(effects
				(font
					(size 0.7874 0.5842)
					(thickness 0.1524)
				)
				(justify left)
			)
		)
		(property "Value" ""
			(at 0 0 180)
			(layer "F.Fab")
			(effects
				(font
					(size 1.27 1.27)
				)
			)
		)
		(duplicate_pad_numbers_are_jumpers no)
		(fp_line
			(start 0.7874 0.4064)
			(end -0.7874 0.4064)
			(stroke
				(width 0.1524)
				(type default)
			)
			(layer "F.SilkS")
		)
		(fp_line
			(start 0.7874 -0.4064)
			(end 0.7874 0.4064)
			(stroke
				(width 0.1524)
				(type default)
			)
			(layer "F.SilkS")
		)
		(fp_line
			(start -0.7874 0.4064)
			(end -0.7874 -0.4064)
			(stroke
				(width 0.1524)
				(type default)
			)
			(layer "F.SilkS")
		)
		(fp_line
			(start -0.7874 -0.4064)
			(end 0.7874 -0.4064)
			(stroke
				(width 0.1524)
				(type default)
			)
			(layer "F.SilkS")
		)
		(fp_poly
			(pts
				(xy -0.508 0.2794) (xy -0.508 0.2286) (xy -0.635 0.2286) (xy -0.635 -0.254) (xy -0.5334 -0.254)
				(xy -0.5334 -0.2794) (xy 0.5334 -0.2794) (xy 0.5334 -0.254) (xy 0.635 -0.254) (xy 0.635 0.254) (xy 0.5334 0.254)
				(xy 0.5334 0.2794)
			)
			(stroke
				(width 0)
				(type default)
			)
			(fill no)
			(layer "F.CrtYd")
		)
		(pad "1" smd rect
			(at 0.40005 0 180)
			(size 0.4572 0.508)
			(layers "F.Cu" "F.Mask" "F.Paste")
			(net "PSU4_REMOTE_R_N")
		)
		(pad "2" smd rect
			(at -0.40005 0 180)
			(size 0.4572 0.508)
			(layers "F.Cu" "F.Mask" "F.Paste")
			(net "GND")
		)
	)
	(footprint ""
		(layer "F.Cu")
		(at 75.059286 -149.113748 -90)
		(property "Reference" "C24"
			(at -2.638552 0.03937 90)
			(unlocked yes)
			(layer "F.SilkS")
			(effects
				(font
					(size 0.7874 0.5842)
					(thickness 0.1524)
				)
				(justify left)
			)
		)
		(property "Value" ""
			(at 0 0 270)
			(layer "F.Fab")
			(effects
				(font
					(size 1.27 1.27)
				)
			)
		)
		(duplicate_pad_numbers_are_jumpers no)
		(fp_line
			(start -0.7874 0.4064)
			(end -0.7874 -0.4064)
			(stroke
				(width 0.1524)
				(type default)
			)
			(layer "F.SilkS")
		)
		(fp_line
			(start 0.7874 0.4064)
			(end -0.7874 0.4064)
			(stroke
				(width 0.1524)
				(type default)
			)
			(layer "F.SilkS")
		)
		(fp_line
			(start 0 0.381)
			(end 0 -0.381)
			(stroke
				(width 0.1524)
				(type default)
			)
			(layer "F.SilkS")
		)
		(fp_line
			(start -0.7874 -0.4064)
			(end 0.7874 -0.4064)
			(stroke
				(width 0.1524)
				(type default)
			)
			(layer "F.SilkS")
		)
		(fp_line
			(start 0.7874 -0.4064)
			(end 0.7874 0.4064)
			(stroke
				(width 0.1524)
				(type default)
			)
			(layer "F.SilkS")
		)
		(fp_poly
			(pts
				(xy -0.5334 0.254) (xy -0.635 0.254) (xy -0.635 0.2286) (xy -0.635 -0.254) (xy -0.5334 -0.254) (xy -0.5334 -0.2794)
				(xy 0.5334 -0.2794) (xy 0.5334 -0.254) (xy 0.635 -0.254) (xy 0.635 0.254) (xy 0.5334 0.254) (xy 0.5334 0.2794)
				(xy -0.508 0.2794) (xy -0.5334 0.2794)
			)
			(stroke
				(width 0)
				(type default)
			)
			(fill no)
			(layer "F.CrtYd")
		)
		(pad "1" smd rect
			(at 0.40005 0 270)
			(size 0.4572 0.508)
			(layers "F.Cu" "F.Mask" "F.Paste")
			(net "P12V")
		)
		(pad "2" smd rect
			(at -0.40005 0 270)
			(size 0.4572 0.508)
			(layers "F.Cu" "F.Mask" "F.Paste")
			(net "GND")
		)
	)
	(footprint ""
		(layer "F.Cu")
		(at 26.068274 -185.521092)
		(property "Reference" "R70"
			(at -3.997198 0.128524 0)
			(unlocked yes)
			(layer "F.SilkS")
			(effects
				(font
					(size 0.7874 0.5842)
					(thickness 0.1524)
				)
				(justify left)
			)
		)
		(property "Value" ""
			(at 0 0 0)
			(layer "F.Fab")
			(effects
				(font
					(size 1.27 1.27)
				)
			)
		)
		(duplicate_pad_numbers_are_jumpers no)
		(fp_line
			(start -0.7874 -0.4064)
			(end 0.7874 -0.4064)
			(stroke
				(width 0.1524)
				(type default)
			)
			(layer "F.SilkS")
		)
		(fp_line
			(start -0.7874 0.4064)
			(end -0.7874 -0.4064)
			(stroke
				(width 0.1524)
				(type default)
			)
			(layer "F.SilkS")
		)
		(fp_line
			(start 0.7874 -0.4064)
			(end 0.7874 0.4064)
			(stroke
				(width 0.1524)
				(type default)
			)
			(layer "F.SilkS")
		)
		(fp_line
			(start 0.7874 0.4064)
			(end -0.7874 0.4064)
			(stroke
				(width 0.1524)
				(type default)
			)
			(layer "F.SilkS")
		)
		(fp_poly
			(pts
				(xy -0.508 0.2794) (xy -0.508 0.2286) (xy -0.635 0.2286) (xy -0.635 -0.254) (xy -0.5334 -0.254)
				(xy -0.5334 -0.2794) (xy 0.5334 -0.2794) (xy 0.5334 -0.254) (xy 0.635 -0.254) (xy 0.635 0.254) (xy 0.5334 0.254)
				(xy 0.5334 0.2794)
			)
			(stroke
				(width 0)
				(type default)
			)
			(fill no)
			(layer "F.CrtYd")
		)
		(pad "1" smd rect
			(at 0.40005 0)
			(size 0.4572 0.508)
			(layers "F.Cu" "F.Mask" "F.Paste")
			(net "PSU3_PS_KILL")
		)
		(pad "2" smd rect
			(at -0.40005 0)
			(size 0.4572 0.508)
			(layers "F.Cu" "F.Mask" "F.Paste")
			(net "P12V_STBY")
		)
	)
	(footprint ""
		(layer "F.Cu")
		(at 74.804524 -87.145368 90)
		(property "Reference" "C18"
			(at -4.421124 0.19177 90)
			(unlocked yes)
			(layer "F.SilkS")
			(effects
				(font
					(size 0.7874 0.5842)
					(thickness 0.1524)
				)
				(justify left)
			)
		)
		(property "Value" ""
			(at 0 0 90)
			(layer "F.Fab")
			(effects
				(font
					(size 1.27 1.27)
				)
			)
		)
		(duplicate_pad_numbers_are_jumpers no)
		(fp_line
			(start 0.7874 -0.4064)
			(end 0.7874 0.4064)
			(stroke
				(width 0.1524)
				(type default)
			)
			(layer "F.SilkS")
		)
		(fp_line
			(start -0.7874 -0.4064)
			(end 0.7874 -0.4064)
			(stroke
				(width 0.1524)
				(type default)
			)
			(layer "F.SilkS")
		)
		(fp_line
			(start 0 0.381)
			(end 0 -0.381)
			(stroke
				(width 0.1524)
				(type default)
			)
			(layer "F.SilkS")
		)
		(fp_line
			(start 0.7874 0.4064)
			(end -0.7874 0.4064)
			(stroke
				(width 0.1524)
				(type default)
			)
			(layer "F.SilkS")
		)
		(fp_line
			(start -0.7874 0.4064)
			(end -0.7874 -0.4064)
			(stroke
				(width 0.1524)
				(type default)
			)
			(layer "F.SilkS")
		)
		(fp_poly
			(pts
				(xy -0.5334 0.254) (xy -0.635 0.254) (xy -0.635 0.2286) (xy -0.635 -0.254) (xy -0.5334 -0.254) (xy -0.5334 -0.2794)
				(xy 0.5334 -0.2794) (xy 0.5334 -0.254) (xy 0.635 -0.254) (xy 0.635 0.254) (xy 0.5334 0.254) (xy 0.5334 0.2794)
				(xy -0.508 0.2794) (xy -0.5334 0.2794)
			)
			(stroke
				(width 0)
				(type default)
			)
			(fill no)
			(layer "F.CrtYd")
		)
		(pad "1" smd rect
			(at 0.40005 0 90)
			(size 0.4572 0.508)
			(layers "F.Cu" "F.Mask" "F.Paste")
			(net "P12V")
		)
		(pad "2" smd rect
			(at -0.40005 0 90)
			(size 0.4572 0.508)
			(layers "F.Cu" "F.Mask" "F.Paste")
			(net "GND")
		)
	)
	(footprint ""
		(layer "F.Cu")
		(at 40.86098 -283.09824 -90)
		(property "Reference" "R21"
			(at 0.946912 -2.85623 90)
			(unlocked yes)
			(layer "F.SilkS")
			(effects
				(font
					(size 0.7874 0.5842)
					(thickness 0.1524)
				)
				(justify left)
			)
		)
		(property "Value" ""
			(at 0 0 270)
			(layer "F.Fab")
			(effects
				(font
					(size 1.27 1.27)
				)
			)
		)
		(duplicate_pad_numbers_are_jumpers no)
		(fp_line
			(start -0.7874 0.4064)
			(end -0.7874 -0.4064)
			(stroke
				(width 0.1524)
				(type default)
			)
			(layer "F.SilkS")
		)
		(fp_line
			(start 0.7874 0.4064)
			(end -0.7874 0.4064)
			(stroke
				(width 0.1524)
				(type default)
			)
			(layer "F.SilkS")
		)
		(fp_line
			(start -0.7874 -0.4064)
			(end 0.7874 -0.4064)
			(stroke
				(width 0.1524)
				(type default)
			)
			(layer "F.SilkS")
		)
		(fp_line
			(start 0.7874 -0.4064)
			(end 0.7874 0.4064)
			(stroke
				(width 0.1524)
				(type default)
			)
			(layer "F.SilkS")
		)
		(fp_poly
			(pts
				(xy -0.508 0.2794) (xy -0.508 0.2286) (xy -0.635 0.2286) (xy -0.635 -0.254) (xy -0.5334 -0.254)
				(xy -0.5334 -0.2794) (xy 0.5334 -0.2794) (xy 0.5334 -0.254) (xy 0.635 -0.254) (xy 0.635 0.254) (xy 0.5334 0.254)
				(xy 0.5334 0.2794)
			)
			(stroke
				(width 0)
				(type default)
			)
			(fill no)
			(layer "F.CrtYd")
		)
		(pad "1" smd rect
			(at 0.40005 0 270)
			(size 0.4572 0.508)
			(layers "F.Cu" "F.Mask" "F.Paste")
			(net "PSU4_AD0")
		)
		(pad "2" smd rect
			(at -0.40005 0 270)
			(size 0.4572 0.508)
			(layers "F.Cu" "F.Mask" "F.Paste")
			(net "GND")
		)
	)
	(footprint ""
		(layer "F.Cu")
		(at 15.16507 -396.021052 180)
		(property "Reference" "R153"
			(at -1.305814 -0.218694 0)
			(unlocked yes)
			(layer "F.SilkS")
			(effects
				(font
					(size 0.7874 0.5842)
					(thickness 0.1524)
				)
				(justify left)
			)
		)
		(property "Value" ""
			(at 0 0 180)
			(layer "F.Fab")
			(effects
				(font
					(size 1.27 1.27)
				)
			)
		)
		(duplicate_pad_numbers_are_jumpers no)
		(fp_line
			(start 0.7874 0.4064)
			(end -0.7874 0.4064)
			(stroke
				(width 0.1524)
				(type default)
			)
			(layer "F.SilkS")
		)
		(fp_line
			(start 0.7874 -0.4064)
			(end 0.7874 0.4064)
			(stroke
				(width 0.1524)
				(type default)
			)
			(layer "F.SilkS")
		)
		(fp_line
			(start -0.7874 0.4064)
			(end -0.7874 -0.4064)
			(stroke
				(width 0.1524)
				(type default)
			)
			(layer "F.SilkS")
		)
		(fp_line
			(start -0.7874 -0.4064)
			(end 0.7874 -0.4064)
			(stroke
				(width 0.1524)
				(type default)
			)
			(layer "F.SilkS")
		)
		(fp_poly
			(pts
				(xy -0.508 0.2794) (xy -0.508 0.2286) (xy -0.635 0.2286) (xy -0.635 -0.254) (xy -0.5334 -0.254)
				(xy -0.5334 -0.2794) (xy 0.5334 -0.2794) (xy 0.5334 -0.254) (xy 0.635 -0.254) (xy 0.635 0.254) (xy 0.5334 0.254)
				(xy 0.5334 0.2794)
			)
			(stroke
				(width 0)
				(type default)
			)
			(fill no)
			(layer "F.CrtYd")
		)
		(pad "1" smd rect
			(at 0.40005 0 180)
			(size 0.4572 0.508)
			(layers "F.Cu" "F.Mask" "F.Paste")
			(net "GND")
		)
		(pad "2" smd rect
			(at -0.40005 0 180)
			(size 0.4572 0.508)
			(layers "F.Cu" "F.Mask" "F.Paste")
			(net "N42132358")
		)
	)
	(footprint ""
		(layer "F.Cu")
		(at 13.451332 -339.764624 -90)
		(property "Reference" "R41"
			(at -1.347724 -0.199136 90)
			(unlocked yes)
			(layer "F.SilkS")
			(effects
				(font
					(size 0.7874 0.5842)
					(thickness 0.1524)
				)
				(justify left)
			)
		)
		(property "Value" ""
			(at 0 0 270)
			(layer "F.Fab")
			(effects
				(font
					(size 1.27 1.27)
				)
			)
		)
		(duplicate_pad_numbers_are_jumpers no)
		(fp_line
			(start -0.7874 0.4064)
			(end -0.7874 -0.4064)
			(stroke
				(width 0.1524)
				(type default)
			)
			(layer "F.SilkS")
		)
		(fp_line
			(start 0.7874 0.4064)
			(end -0.7874 0.4064)
			(stroke
				(width 0.1524)
				(type default)
			)
			(layer "F.SilkS")
		)
		(fp_line
			(start -0.7874 -0.4064)
			(end 0.7874 -0.4064)
			(stroke
				(width 0.1524)
				(type default)
			)
			(layer "F.SilkS")
		)
		(fp_line
			(start 0.7874 -0.4064)
			(end 0.7874 0.4064)
			(stroke
				(width 0.1524)
				(type default)
			)
			(layer "F.SilkS")
		)
		(fp_poly
			(pts
				(xy -0.508 0.2794) (xy -0.508 0.2286) (xy -0.635 0.2286) (xy -0.635 -0.254) (xy -0.5334 -0.254)
				(xy -0.5334 -0.2794) (xy 0.5334 -0.2794) (xy 0.5334 -0.254) (xy 0.635 -0.254) (xy 0.635 0.254) (xy 0.5334 0.254)
				(xy 0.5334 0.2794)
			)
			(stroke
				(width 0)
				(type default)
			)
			(fill no)
			(layer "F.CrtYd")
		)
		(pad "1" smd rect
			(at 0.40005 0 270)
			(size 0.4572 0.508)
			(layers "F.Cu" "F.Mask" "F.Paste")
			(net "P3V3")
		)
		(pad "2" smd rect
			(at -0.40005 0 270)
			(size 0.4572 0.508)
			(layers "F.Cu" "F.Mask" "F.Paste")
			(net "FRU_WP")
		)
	)
	(footprint ""
		(layer "F.Cu")
		(at 72.611996 -237.708694 -90)
		(property "Reference" "C38"
			(at 0.73406 -3.85445 90)
			(unlocked yes)
			(layer "F.SilkS")
			(effects
				(font
					(size 0.7874 0.5842)
					(thickness 0.1524)
				)
				(justify left)
			)
		)
		(property "Value" ""
			(at 0 0 270)
			(layer "F.Fab")
			(effects
				(font
					(size 1.27 1.27)
				)
			)
		)
		(duplicate_pad_numbers_are_jumpers no)
		(fp_line
			(start -0.7874 0.4064)
			(end -0.7874 -0.4064)
			(stroke
				(width 0.1524)
				(type default)
			)
			(layer "F.SilkS")
		)
		(fp_line
			(start 0.7874 0.4064)
			(end -0.7874 0.4064)
			(stroke
				(width 0.1524)
				(type default)
			)
			(layer "F.SilkS")
		)
		(fp_line
			(start 0 0.381)
			(end 0 -0.381)
			(stroke
				(width 0.1524)
				(type default)
			)
			(layer "F.SilkS")
		)
		(fp_line
			(start -0.7874 -0.4064)
			(end 0.7874 -0.4064)
			(stroke
				(width 0.1524)
				(type default)
			)
			(layer "F.SilkS")
		)
		(fp_line
			(start 0.7874 -0.4064)
			(end 0.7874 0.4064)
			(stroke
				(width 0.1524)
				(type default)
			)
			(layer "F.SilkS")
		)
		(fp_poly
			(pts
				(xy -0.5334 0.254) (xy -0.635 0.254) (xy -0.635 0.2286) (xy -0.635 -0.254) (xy -0.5334 -0.254) (xy -0.5334 -0.2794)
				(xy 0.5334 -0.2794) (xy 0.5334 -0.254) (xy 0.635 -0.254) (xy 0.635 0.254) (xy 0.5334 0.254) (xy 0.5334 0.2794)
				(xy -0.508 0.2794) (xy -0.5334 0.2794)
			)
			(stroke
				(width 0)
				(type default)
			)
			(fill no)
			(layer "F.CrtYd")
		)
		(pad "1" smd rect
			(at 0.40005 0 270)
			(size 0.4572 0.508)
			(layers "F.Cu" "F.Mask" "F.Paste")
			(net "P12V")
		)
		(pad "2" smd rect
			(at -0.40005 0 270)
			(size 0.4572 0.508)
			(layers "F.Cu" "F.Mask" "F.Paste")
			(net "GND")
		)
	)
	(footprint ""
		(layer "F.Cu")
		(at 73.63333 -87.145368 90)
		(property "Reference" "C19"
			(at -4.367022 0.092202 90)
			(unlocked yes)
			(layer "F.SilkS")
			(effects
				(font
					(size 0.7874 0.5842)
					(thickness 0.1524)
				)
				(justify left)
			)
		)
		(property "Value" ""
			(at 0 0 90)
			(layer "F.Fab")
			(effects
				(font
					(size 1.27 1.27)
				)
			)
		)
		(duplicate_pad_numbers_are_jumpers no)
		(fp_line
			(start 0.7874 -0.4064)
			(end 0.7874 0.4064)
			(stroke
				(width 0.1524)
				(type default)
			)
			(layer "F.SilkS")
		)
		(fp_line
			(start -0.7874 -0.4064)
			(end 0.7874 -0.4064)
			(stroke
				(width 0.1524)
				(type default)
			)
			(layer "F.SilkS")
		)
		(fp_line
			(start 0 0.381)
			(end 0 -0.381)
			(stroke
				(width 0.1524)
				(type default)
			)
			(layer "F.SilkS")
		)
		(fp_line
			(start 0.7874 0.4064)
			(end -0.7874 0.4064)
			(stroke
				(width 0.1524)
				(type default)
			)
			(layer "F.SilkS")
		)
		(fp_line
			(start -0.7874 0.4064)
			(end -0.7874 -0.4064)
			(stroke
				(width 0.1524)
				(type default)
			)
			(layer "F.SilkS")
		)
		(fp_poly
			(pts
				(xy -0.5334 0.254) (xy -0.635 0.254) (xy -0.635 0.2286) (xy -0.635 -0.254) (xy -0.5334 -0.254) (xy -0.5334 -0.2794)
				(xy 0.5334 -0.2794) (xy 0.5334 -0.254) (xy 0.635 -0.254) (xy 0.635 0.254) (xy 0.5334 0.254) (xy 0.5334 0.2794)
				(xy -0.508 0.2794) (xy -0.5334 0.2794)
			)
			(stroke
				(width 0)
				(type default)
			)
			(fill no)
			(layer "F.CrtYd")
		)
		(pad "1" smd rect
			(at 0.40005 0 90)
			(size 0.4572 0.508)
			(layers "F.Cu" "F.Mask" "F.Paste")
			(net "P12V")
		)
		(pad "2" smd rect
			(at -0.40005 0 90)
			(size 0.4572 0.508)
			(layers "F.Cu" "F.Mask" "F.Paste")
			(net "GND")
		)
	)
	(footprint ""
		(layer "F.Cu")
		(at 72.802242 -459.732634 -90)
		(property "Reference" "C72"
			(at -2.962656 -0.27813 90)
			(unlocked yes)
			(layer "F.SilkS")
			(effects
				(font
					(size 0.7874 0.5842)
					(thickness 0.1524)
				)
				(justify left)
			)
		)
		(property "Value" ""
			(at 0 0 270)
			(layer "F.Fab")
			(effects
				(font
					(size 1.27 1.27)
				)
			)
		)
		(duplicate_pad_numbers_are_jumpers no)
		(fp_line
			(start -0.7874 0.4064)
			(end -0.7874 -0.4064)
			(stroke
				(width 0.1524)
				(type default)
			)
			(layer "F.SilkS")
		)
		(fp_line
			(start 0.7874 0.4064)
			(end -0.7874 0.4064)
			(stroke
				(width 0.1524)
				(type default)
			)
			(layer "F.SilkS")
		)
		(fp_line
			(start 0 0.381)
			(end 0 -0.381)
			(stroke
				(width 0.1524)
				(type default)
			)
			(layer "F.SilkS")
		)
		(fp_line
			(start -0.7874 -0.4064)
			(end 0.7874 -0.4064)
			(stroke
				(width 0.1524)
				(type default)
			)
			(layer "F.SilkS")
		)
		(fp_line
			(start 0.7874 -0.4064)
			(end 0.7874 0.4064)
			(stroke
				(width 0.1524)
				(type default)
			)
			(layer "F.SilkS")
		)
		(fp_poly
			(pts
				(xy -0.5334 0.254) (xy -0.635 0.254) (xy -0.635 0.2286) (xy -0.635 -0.254) (xy -0.5334 -0.254) (xy -0.5334 -0.2794)
				(xy 0.5334 -0.2794) (xy 0.5334 -0.254) (xy 0.635 -0.254) (xy 0.635 0.254) (xy 0.5334 0.254) (xy 0.5334 0.2794)
				(xy -0.508 0.2794) (xy -0.5334 0.2794)
			)
			(stroke
				(width 0)
				(type default)
			)
			(fill no)
			(layer "F.CrtYd")
		)
		(pad "1" smd rect
			(at 0.40005 0 270)
			(size 0.4572 0.508)
			(layers "F.Cu" "F.Mask" "F.Paste")
			(net "P12V")
		)
		(pad "2" smd rect
			(at -0.40005 0 270)
			(size 0.4572 0.508)
			(layers "F.Cu" "F.Mask" "F.Paste")
			(net "GND")
		)
	)
	(footprint ""
		(layer "F.Cu")
		(at 25.997662 -8.344662)
		(property "Reference" "R43"
			(at -3.764788 0.113792 0)
			(unlocked yes)
			(layer "F.SilkS")
			(effects
				(font
					(size 0.7874 0.5842)
					(thickness 0.1524)
				)
				(justify left)
			)
		)
		(property "Value" ""
			(at 0 0 0)
			(layer "F.Fab")
			(effects
				(font
					(size 1.27 1.27)
				)
			)
		)
		(duplicate_pad_numbers_are_jumpers no)
		(fp_line
			(start -0.7874 -0.4064)
			(end 0.7874 -0.4064)
			(stroke
				(width 0.1524)
				(type default)
			)
			(layer "F.SilkS")
		)
		(fp_line
			(start -0.7874 0.4064)
			(end -0.7874 -0.4064)
			(stroke
				(width 0.1524)
				(type default)
			)
			(layer "F.SilkS")
		)
		(fp_line
			(start 0.7874 -0.4064)
			(end 0.7874 0.4064)
			(stroke
				(width 0.1524)
				(type default)
			)
			(layer "F.SilkS")
		)
		(fp_line
			(start 0.7874 0.4064)
			(end -0.7874 0.4064)
			(stroke
				(width 0.1524)
				(type default)
			)
			(layer "F.SilkS")
		)
		(fp_poly
			(pts
				(xy -0.508 0.2794) (xy -0.508 0.2286) (xy -0.635 0.2286) (xy -0.635 -0.254) (xy -0.5334 -0.254)
				(xy -0.5334 -0.2794) (xy 0.5334 -0.2794) (xy 0.5334 -0.254) (xy 0.635 -0.254) (xy 0.635 0.254) (xy 0.5334 0.254)
				(xy 0.5334 0.2794)
			)
			(stroke
				(width 0)
				(type default)
			)
			(fill no)
			(layer "F.CrtYd")
		)
		(pad "1" smd rect
			(at 0.40005 0)
			(size 0.4572 0.508)
			(layers "F.Cu" "F.Mask" "F.Paste")
			(net "PSU1_PS_KILL")
		)
		(pad "2" smd rect
			(at -0.40005 0)
			(size 0.4572 0.508)
			(layers "F.Cu" "F.Mask" "F.Paste")
			(net "GND")
		)
	)
	(footprint ""
		(layer "F.Cu")
		(at 91.399868 -420.06012)
		(property "Reference" "H15"
			(at -5.1308 -5.23113 0)
			(unlocked yes)
			(layer "F.SilkS")
			(effects
				(font
					(size 0.7874 0.5842)
					(thickness 0.1524)
				)
				(justify left)
			)
		)
		(property "Value" ""
			(at 0 0 0)
			(layer "F.Fab")
			(effects
				(font
					(size 1.27 1.27)
				)
			)
		)
		(duplicate_pad_numbers_are_jumpers no)
		(fp_circle
			(center 0 0)
			(end 4.826 0)
			(stroke
				(width 0.1524)
				(type default)
			)
			(fill no)
			(layer "F.SilkS")
		)
		(fp_circle
			(center 0 0)
			(end 4.826 0)
			(stroke
				(width 0.1524)
				(type default)
			)
			(fill no)
			(layer "B.SilkS")
		)
		(fp_poly
			(pts
				(arc
					(start 0 4.0132)
					(mid 0 -4.0132)
					(end 0 4.0132)
				)
			)
			(stroke
				(width 0)
				(type default)
			)
			(fill no)
			(layer "F.CrtYd")
		)
		(pad "" np_thru_hole circle
			(at 0 0)
			(size 8.001 8.001)
			(drill 8.001)
			(layers "*.Cu" "*.Mask")
			(clearance 0.381)
			(thermal_gap 0.381)
		)
		(zone
			(layers "F.Cu" "B.Cu" "In1.Cu" "In2.Cu" "In3.Cu" "In4.Cu" "In5.Cu" "In6.Cu")
			(hatch none 0.5)
			(connect_pads
				(clearance 0)
			)
			(min_thickness 0.25)
			(keepout
				(tracks not_allowed)
				(vias allowed)
				(pads allowed)
				(copperpour not_allowed)
				(footprints allowed)
			)
			(placement
				(enabled no)
				(sheetname "")
			)
			(fill
				(thermal_gap 0.5)
				(thermal_bridge_width 0.5)
				(island_removal_mode 0)
			)
			(polygon
				(pts
					(arc
						(start 91.399868 -415.53892)
						(mid 91.399868 -424.58132)
						(end 91.399868 -415.53892)
					)
				)
			)
		)
	)
	(footprint ""
		(layer "F.Cu")
		(at 25.931622 -94.464886)
		(property "Reference" "R69"
			(at -4.080256 -0.075692 0)
			(unlocked yes)
			(layer "F.SilkS")
			(effects
				(font
					(size 0.7874 0.5842)
					(thickness 0.1524)
				)
				(justify left)
			)
		)
		(property "Value" ""
			(at 0 0 0)
			(layer "F.Fab")
			(effects
				(font
					(size 1.27 1.27)
				)
			)
		)
		(duplicate_pad_numbers_are_jumpers no)
		(fp_line
			(start -0.7874 -0.4064)
			(end 0.7874 -0.4064)
			(stroke
				(width 0.1524)
				(type default)
			)
			(layer "F.SilkS")
		)
		(fp_line
			(start -0.7874 0.4064)
			(end -0.7874 -0.4064)
			(stroke
				(width 0.1524)
				(type default)
			)
			(layer "F.SilkS")
		)
		(fp_line
			(start 0.7874 -0.4064)
			(end 0.7874 0.4064)
			(stroke
				(width 0.1524)
				(type default)
			)
			(layer "F.SilkS")
		)
		(fp_line
			(start 0.7874 0.4064)
			(end -0.7874 0.4064)
			(stroke
				(width 0.1524)
				(type default)
			)
			(layer "F.SilkS")
		)
		(fp_poly
			(pts
				(xy -0.508 0.2794) (xy -0.508 0.2286) (xy -0.635 0.2286) (xy -0.635 -0.254) (xy -0.5334 -0.254)
				(xy -0.5334 -0.2794) (xy 0.5334 -0.2794) (xy 0.5334 -0.254) (xy 0.635 -0.254) (xy 0.635 0.254) (xy 0.5334 0.254)
				(xy 0.5334 0.2794)
			)
			(stroke
				(width 0)
				(type default)
			)
			(fill no)
			(layer "F.CrtYd")
		)
		(pad "1" smd rect
			(at 0.40005 0)
			(size 0.4572 0.508)
			(layers "F.Cu" "F.Mask" "F.Paste")
			(net "PSU2_RESET")
		)
		(pad "2" smd rect
			(at -0.40005 0)
			(size 0.4572 0.508)
			(layers "F.Cu" "F.Mask" "F.Paste")
			(net "GND")
		)
	)
	(footprint ""
		(layer "F.Cu")
		(at 39.458392 -110.374176 90)
		(property "Reference" "R114"
			(at -2.70256 2.149348 90)
			(unlocked yes)
			(layer "F.SilkS")
			(effects
				(font
					(size 0.7874 0.5842)
					(thickness 0.1524)
				)
				(justify left)
			)
		)
		(property "Value" ""
			(at 0 0 90)
			(layer "F.Fab")
			(effects
				(font
					(size 1.27 1.27)
				)
			)
		)
		(duplicate_pad_numbers_are_jumpers no)
		(fp_line
			(start 0.7874 -0.4064)
			(end 0.7874 0.4064)
			(stroke
				(width 0.1524)
				(type default)
			)
			(layer "F.SilkS")
		)
		(fp_line
			(start -0.7874 -0.4064)
			(end 0.7874 -0.4064)
			(stroke
				(width 0.1524)
				(type default)
			)
			(layer "F.SilkS")
		)
		(fp_line
			(start 0.7874 0.4064)
			(end -0.7874 0.4064)
			(stroke
				(width 0.1524)
				(type default)
			)
			(layer "F.SilkS")
		)
		(fp_line
			(start -0.7874 0.4064)
			(end -0.7874 -0.4064)
			(stroke
				(width 0.1524)
				(type default)
			)
			(layer "F.SilkS")
		)
		(fp_poly
			(pts
				(xy -0.508 0.2794) (xy -0.508 0.2286) (xy -0.635 0.2286) (xy -0.635 -0.254) (xy -0.5334 -0.254)
				(xy -0.5334 -0.2794) (xy 0.5334 -0.2794) (xy 0.5334 -0.254) (xy 0.635 -0.254) (xy 0.635 0.254) (xy 0.5334 0.254)
				(xy 0.5334 0.2794)
			)
			(stroke
				(width 0)
				(type default)
			)
			(fill no)
			(layer "F.CrtYd")
		)
		(pad "1" smd rect
			(at 0.40005 0 90)
			(size 0.4572 0.508)
			(layers "F.Cu" "F.Mask" "F.Paste")
			(net "PSU2_REMOTE_P")
		)
		(pad "2" smd rect
			(at -0.40005 0 90)
			(size 0.4572 0.508)
			(layers "F.Cu" "F.Mask" "F.Paste")
			(net "PSU2_REMOTE_R2_P")
		)
	)
	(footprint ""
		(layer "F.Cu")
		(at 81.78927 -14.939772 -90)
		(property "Reference" "C7"
			(at -1.75133 -0.093726 90)
			(unlocked yes)
			(layer "F.SilkS")
			(effects
				(font
					(size 0.7874 0.5842)
					(thickness 0.1524)
				)
				(justify left)
			)
		)
		(property "Value" ""
			(at 0 0 270)
			(layer "F.Fab")
			(effects
				(font
					(size 1.27 1.27)
				)
			)
		)
		(duplicate_pad_numbers_are_jumpers no)
		(fp_line
			(start -0.7874 0.4064)
			(end -0.7874 -0.4064)
			(stroke
				(width 0.1524)
				(type default)
			)
			(layer "F.SilkS")
		)
		(fp_line
			(start 0.7874 0.4064)
			(end -0.7874 0.4064)
			(stroke
				(width 0.1524)
				(type default)
			)
			(layer "F.SilkS")
		)
		(fp_line
			(start 0 0.381)
			(end 0 -0.381)
			(stroke
				(width 0.1524)
				(type default)
			)
			(layer "F.SilkS")
		)
		(fp_line
			(start -0.7874 -0.4064)
			(end 0.7874 -0.4064)
			(stroke
				(width 0.1524)
				(type default)
			)
			(layer "F.SilkS")
		)
		(fp_line
			(start 0.7874 -0.4064)
			(end 0.7874 0.4064)
			(stroke
				(width 0.1524)
				(type default)
			)
			(layer "F.SilkS")
		)
		(fp_poly
			(pts
				(xy -0.5334 0.254) (xy -0.635 0.254) (xy -0.635 0.2286) (xy -0.635 -0.254) (xy -0.5334 -0.254) (xy -0.5334 -0.2794)
				(xy 0.5334 -0.2794) (xy 0.5334 -0.254) (xy 0.635 -0.254) (xy 0.635 0.254) (xy 0.5334 0.254) (xy 0.5334 0.2794)
				(xy -0.508 0.2794) (xy -0.5334 0.2794)
			)
			(stroke
				(width 0)
				(type default)
			)
			(fill no)
			(layer "F.CrtYd")
		)
		(pad "1" smd rect
			(at 0.40005 0 270)
			(size 0.4572 0.508)
			(layers "F.Cu" "F.Mask" "F.Paste")
			(net "P12V")
		)
		(pad "2" smd rect
			(at -0.40005 0 270)
			(size 0.4572 0.508)
			(layers "F.Cu" "F.Mask" "F.Paste")
			(net "GND")
		)
	)
	(footprint ""
		(layer "F.Cu")
		(at 40.157654 -14.412976 180)
		(property "Reference" "R9"
			(at 0.747014 1.214628 0)
			(unlocked yes)
			(layer "F.SilkS")
			(effects
				(font
					(size 0.7874 0.5842)
					(thickness 0.1524)
				)
				(justify left)
			)
		)
		(property "Value" ""
			(at 0 0 180)
			(layer "F.Fab")
			(effects
				(font
					(size 1.27 1.27)
				)
			)
		)
		(duplicate_pad_numbers_are_jumpers no)
		(fp_line
			(start 0.7874 0.4064)
			(end -0.7874 0.4064)
			(stroke
				(width 0.1524)
				(type default)
			)
			(layer "F.SilkS")
		)
		(fp_line
			(start 0.7874 -0.4064)
			(end 0.7874 0.4064)
			(stroke
				(width 0.1524)
				(type default)
			)
			(layer "F.SilkS")
		)
		(fp_line
			(start -0.7874 0.4064)
			(end -0.7874 -0.4064)
			(stroke
				(width 0.1524)
				(type default)
			)
			(layer "F.SilkS")
		)
		(fp_line
			(start -0.7874 -0.4064)
			(end 0.7874 -0.4064)
			(stroke
				(width 0.1524)
				(type default)
			)
			(layer "F.SilkS")
		)
		(fp_poly
			(pts
				(xy -0.508 0.2794) (xy -0.508 0.2286) (xy -0.635 0.2286) (xy -0.635 -0.254) (xy -0.5334 -0.254)
				(xy -0.5334 -0.2794) (xy 0.5334 -0.2794) (xy 0.5334 -0.254) (xy 0.635 -0.254) (xy 0.635 0.254) (xy 0.5334 0.254)
				(xy 0.5334 0.2794)
			)
			(stroke
				(width 0)
				(type default)
			)
			(fill no)
			(layer "F.CrtYd")
		)
		(pad "1" smd rect
			(at 0.40005 0 180)
			(size 0.4572 0.508)
			(layers "F.Cu" "F.Mask" "F.Paste")
			(net "PSU1_RETURN")
		)
		(pad "2" smd rect
			(at -0.40005 0 180)
			(size 0.4572 0.508)
			(layers "F.Cu" "F.Mask" "F.Paste")
			(net "GND")
		)
	)
	(footprint ""
		(layer "F.Cu")
		(at 72.185276 -307.819806 90)
		(property "Reference" "C55"
			(at -1.265682 5.175758 90)
			(unlocked yes)
			(layer "F.SilkS")
			(effects
				(font
					(size 0.7874 0.5842)
					(thickness 0.1524)
				)
				(justify left)
			)
		)
		(property "Value" ""
			(at 0 0 90)
			(layer "F.Fab")
			(effects
				(font
					(size 1.27 1.27)
				)
			)
		)
		(duplicate_pad_numbers_are_jumpers no)
		(fp_line
			(start 0.7874 -0.4064)
			(end 0.7874 0.4064)
			(stroke
				(width 0.1524)
				(type default)
			)
			(layer "F.SilkS")
		)
		(fp_line
			(start -0.7874 -0.4064)
			(end 0.7874 -0.4064)
			(stroke
				(width 0.1524)
				(type default)
			)
			(layer "F.SilkS")
		)
		(fp_line
			(start 0 0.381)
			(end 0 -0.381)
			(stroke
				(width 0.1524)
				(type default)
			)
			(layer "F.SilkS")
		)
		(fp_line
			(start 0.7874 0.4064)
			(end -0.7874 0.4064)
			(stroke
				(width 0.1524)
				(type default)
			)
			(layer "F.SilkS")
		)
		(fp_line
			(start -0.7874 0.4064)
			(end -0.7874 -0.4064)
			(stroke
				(width 0.1524)
				(type default)
			)
			(layer "F.SilkS")
		)
		(fp_poly
			(pts
				(xy -0.5334 0.254) (xy -0.635 0.254) (xy -0.635 0.2286) (xy -0.635 -0.254) (xy -0.5334 -0.254) (xy -0.5334 -0.2794)
				(xy 0.5334 -0.2794) (xy 0.5334 -0.254) (xy 0.635 -0.254) (xy 0.635 0.254) (xy 0.5334 0.254) (xy 0.5334 0.2794)
				(xy -0.508 0.2794) (xy -0.5334 0.2794)
			)
			(stroke
				(width 0)
				(type default)
			)
			(fill no)
			(layer "F.CrtYd")
		)
		(pad "1" smd rect
			(at 0.40005 0 90)
			(size 0.4572 0.508)
			(layers "F.Cu" "F.Mask" "F.Paste")
			(net "P12V")
		)
		(pad "2" smd rect
			(at -0.40005 0 90)
			(size 0.4572 0.508)
			(layers "F.Cu" "F.Mask" "F.Paste")
			(net "GND")
		)
	)
	(footprint ""
		(layer "F.Cu")
		(at 71.825104 -131.443476 90)
		(property "Reference" "C25"
			(at -3.902456 0.182626 90)
			(unlocked yes)
			(layer "F.SilkS")
			(effects
				(font
					(size 0.7874 0.5842)
					(thickness 0.1524)
				)
				(justify left)
			)
		)
		(property "Value" ""
			(at 0 0 90)
			(layer "F.Fab")
			(effects
				(font
					(size 1.27 1.27)
				)
			)
		)
		(duplicate_pad_numbers_are_jumpers no)
		(fp_line
			(start 0.7874 -0.4064)
			(end 0.7874 0.4064)
			(stroke
				(width 0.1524)
				(type default)
			)
			(layer "F.SilkS")
		)
		(fp_line
			(start -0.7874 -0.4064)
			(end 0.7874 -0.4064)
			(stroke
				(width 0.1524)
				(type default)
			)
			(layer "F.SilkS")
		)
		(fp_line
			(start 0 0.381)
			(end 0 -0.381)
			(stroke
				(width 0.1524)
				(type default)
			)
			(layer "F.SilkS")
		)
		(fp_line
			(start 0.7874 0.4064)
			(end -0.7874 0.4064)
			(stroke
				(width 0.1524)
				(type default)
			)
			(layer "F.SilkS")
		)
		(fp_line
			(start -0.7874 0.4064)
			(end -0.7874 -0.4064)
			(stroke
				(width 0.1524)
				(type default)
			)
			(layer "F.SilkS")
		)
		(fp_poly
			(pts
				(xy -0.5334 0.254) (xy -0.635 0.254) (xy -0.635 0.2286) (xy -0.635 -0.254) (xy -0.5334 -0.254) (xy -0.5334 -0.2794)
				(xy 0.5334 -0.2794) (xy 0.5334 -0.254) (xy 0.635 -0.254) (xy 0.635 0.254) (xy 0.5334 0.254) (xy 0.5334 0.2794)
				(xy -0.508 0.2794) (xy -0.5334 0.2794)
			)
			(stroke
				(width 0)
				(type default)
			)
			(fill no)
			(layer "F.CrtYd")
		)
		(pad "1" smd rect
			(at 0.40005 0 90)
			(size 0.4572 0.508)
			(layers "F.Cu" "F.Mask" "F.Paste")
			(net "P12V")
		)
		(pad "2" smd rect
			(at -0.40005 0 90)
			(size 0.4572 0.508)
			(layers "F.Cu" "F.Mask" "F.Paste")
			(net "GND")
		)
	)
	(footprint ""
		(layer "F.Cu")
		(at 69.726556 -175.945546 90)
		(property "Reference" "C34"
			(at -4.082034 0.14097 90)
			(unlocked yes)
			(layer "F.SilkS")
			(effects
				(font
					(size 0.7874 0.5842)
					(thickness 0.1524)
				)
				(justify left)
			)
		)
		(property "Value" ""
			(at 0 0 90)
			(layer "F.Fab")
			(effects
				(font
					(size 1.27 1.27)
				)
			)
		)
		(duplicate_pad_numbers_are_jumpers no)
		(fp_line
			(start 0.7874 -0.4064)
			(end 0.7874 0.4064)
			(stroke
				(width 0.1524)
				(type default)
			)
			(layer "F.SilkS")
		)
		(fp_line
			(start -0.7874 -0.4064)
			(end 0.7874 -0.4064)
			(stroke
				(width 0.1524)
				(type default)
			)
			(layer "F.SilkS")
		)
		(fp_line
			(start 0 0.381)
			(end 0 -0.381)
			(stroke
				(width 0.1524)
				(type default)
			)
			(layer "F.SilkS")
		)
		(fp_line
			(start 0.7874 0.4064)
			(end -0.7874 0.4064)
			(stroke
				(width 0.1524)
				(type default)
			)
			(layer "F.SilkS")
		)
		(fp_line
			(start -0.7874 0.4064)
			(end -0.7874 -0.4064)
			(stroke
				(width 0.1524)
				(type default)
			)
			(layer "F.SilkS")
		)
		(fp_poly
			(pts
				(xy -0.5334 0.254) (xy -0.635 0.254) (xy -0.635 0.2286) (xy -0.635 -0.254) (xy -0.5334 -0.254) (xy -0.5334 -0.2794)
				(xy 0.5334 -0.2794) (xy 0.5334 -0.254) (xy 0.635 -0.254) (xy 0.635 0.254) (xy 0.5334 0.254) (xy 0.5334 0.2794)
				(xy -0.508 0.2794) (xy -0.5334 0.2794)
			)
			(stroke
				(width 0)
				(type default)
			)
			(fill no)
			(layer "F.CrtYd")
		)
		(pad "1" smd rect
			(at 0.40005 0 90)
			(size 0.4572 0.508)
			(layers "F.Cu" "F.Mask" "F.Paste")
			(net "P12V")
		)
		(pad "2" smd rect
			(at -0.40005 0 90)
			(size 0.4572 0.508)
			(layers "F.Cu" "F.Mask" "F.Paste")
			(net "GND")
		)
	)
	(footprint ""
		(layer "F.Cu")
		(at 27.347672 -107.830366 90)
		(property "Reference" "R117"
			(at -3.30327 -1.060196 90)
			(unlocked yes)
			(layer "F.SilkS")
			(effects
				(font
					(size 0.7874 0.5842)
					(thickness 0.1524)
				)
				(justify left)
			)
		)
		(property "Value" ""
			(at 0 0 90)
			(layer "F.Fab")
			(effects
				(font
					(size 1.27 1.27)
				)
			)
		)
		(duplicate_pad_numbers_are_jumpers no)
		(fp_line
			(start 0.7874 -0.4064)
			(end 0.7874 0.4064)
			(stroke
				(width 0.1524)
				(type default)
			)
			(layer "F.SilkS")
		)
		(fp_line
			(start -0.7874 -0.4064)
			(end 0.7874 -0.4064)
			(stroke
				(width 0.1524)
				(type default)
			)
			(layer "F.SilkS")
		)
		(fp_line
			(start 0.7874 0.4064)
			(end -0.7874 0.4064)
			(stroke
				(width 0.1524)
				(type default)
			)
			(layer "F.SilkS")
		)
		(fp_line
			(start -0.7874 0.4064)
			(end -0.7874 -0.4064)
			(stroke
				(width 0.1524)
				(type default)
			)
			(layer "F.SilkS")
		)
		(fp_poly
			(pts
				(xy -0.508 0.2794) (xy -0.508 0.2286) (xy -0.635 0.2286) (xy -0.635 -0.254) (xy -0.5334 -0.254)
				(xy -0.5334 -0.2794) (xy 0.5334 -0.2794) (xy 0.5334 -0.254) (xy 0.635 -0.254) (xy 0.635 0.254) (xy 0.5334 0.254)
				(xy 0.5334 0.2794)
			)
			(stroke
				(width 0)
				(type default)
			)
			(fill no)
			(layer "F.CrtYd")
		)
		(pad "1" smd rect
			(at 0.40005 0 90)
			(size 0.4572 0.508)
			(layers "F.Cu" "F.Mask" "F.Paste")
			(net "PSU2_REMOTE_N")
		)
		(pad "2" smd rect
			(at -0.40005 0 90)
			(size 0.4572 0.508)
			(layers "F.Cu" "F.Mask" "F.Paste")
			(net "PSU2_REMOTE_R2_N")
		)
	)
	(footprint ""
		(layer "F.Cu")
		(at 71.405496 -263.260078 90)
		(property "Reference" "C49"
			(at -4.355846 -0.127762 90)
			(unlocked yes)
			(layer "F.SilkS")
			(effects
				(font
					(size 0.7874 0.5842)
					(thickness 0.1524)
				)
				(justify left)
			)
		)
		(property "Value" ""
			(at 0 0 90)
			(layer "F.Fab")
			(effects
				(font
					(size 1.27 1.27)
				)
			)
		)
		(duplicate_pad_numbers_are_jumpers no)
		(fp_line
			(start 0.7874 -0.4064)
			(end 0.7874 0.4064)
			(stroke
				(width 0.1524)
				(type default)
			)
			(layer "F.SilkS")
		)
		(fp_line
			(start -0.7874 -0.4064)
			(end 0.7874 -0.4064)
			(stroke
				(width 0.1524)
				(type default)
			)
			(layer "F.SilkS")
		)
		(fp_line
			(start 0 0.381)
			(end 0 -0.381)
			(stroke
				(width 0.1524)
				(type default)
			)
			(layer "F.SilkS")
		)
		(fp_line
			(start 0.7874 0.4064)
			(end -0.7874 0.4064)
			(stroke
				(width 0.1524)
				(type default)
			)
			(layer "F.SilkS")
		)
		(fp_line
			(start -0.7874 0.4064)
			(end -0.7874 -0.4064)
			(stroke
				(width 0.1524)
				(type default)
			)
			(layer "F.SilkS")
		)
		(fp_poly
			(pts
				(xy -0.5334 0.254) (xy -0.635 0.254) (xy -0.635 0.2286) (xy -0.635 -0.254) (xy -0.5334 -0.254) (xy -0.5334 -0.2794)
				(xy 0.5334 -0.2794) (xy 0.5334 -0.254) (xy 0.635 -0.254) (xy 0.635 0.254) (xy 0.5334 0.254) (xy 0.5334 0.2794)
				(xy -0.508 0.2794) (xy -0.5334 0.2794)
			)
			(stroke
				(width 0)
				(type default)
			)
			(fill no)
			(layer "F.CrtYd")
		)
		(pad "1" smd rect
			(at 0.40005 0 90)
			(size 0.4572 0.508)
			(layers "F.Cu" "F.Mask" "F.Paste")
			(net "P12V")
		)
		(pad "2" smd rect
			(at -0.40005 0 90)
			(size 0.4572 0.508)
			(layers "F.Cu" "F.Mask" "F.Paste")
			(net "GND")
		)
	)
	(footprint ""
		(layer "F.Cu")
		(at 26.068274 -186.752992)
		(property "Reference" "R48"
			(at -3.997198 0.128524 0)
			(unlocked yes)
			(layer "F.SilkS")
			(effects
				(font
					(size 0.7874 0.5842)
					(thickness 0.1524)
				)
				(justify left)
			)
		)
		(property "Value" ""
			(at 0 0 0)
			(layer "F.Fab")
			(effects
				(font
					(size 1.27 1.27)
				)
			)
		)
		(duplicate_pad_numbers_are_jumpers no)
		(fp_line
			(start -0.7874 -0.4064)
			(end 0.7874 -0.4064)
			(stroke
				(width 0.1524)
				(type default)
			)
			(layer "F.SilkS")
		)
		(fp_line
			(start -0.7874 0.4064)
			(end -0.7874 -0.4064)
			(stroke
				(width 0.1524)
				(type default)
			)
			(layer "F.SilkS")
		)
		(fp_line
			(start 0.7874 -0.4064)
			(end 0.7874 0.4064)
			(stroke
				(width 0.1524)
				(type default)
			)
			(layer "F.SilkS")
		)
		(fp_line
			(start 0.7874 0.4064)
			(end -0.7874 0.4064)
			(stroke
				(width 0.1524)
				(type default)
			)
			(layer "F.SilkS")
		)
		(fp_poly
			(pts
				(xy -0.508 0.2794) (xy -0.508 0.2286) (xy -0.635 0.2286) (xy -0.635 -0.254) (xy -0.5334 -0.254)
				(xy -0.5334 -0.2794) (xy 0.5334 -0.2794) (xy 0.5334 -0.254) (xy 0.635 -0.254) (xy 0.635 0.254) (xy 0.5334 0.254)
				(xy 0.5334 0.2794)
			)
			(stroke
				(width 0)
				(type default)
			)
			(fill no)
			(layer "F.CrtYd")
		)
		(pad "1" smd rect
			(at 0.40005 0)
			(size 0.4572 0.508)
			(layers "F.Cu" "F.Mask" "F.Paste")
			(net "PSU3_PS_KILL")
		)
		(pad "2" smd rect
			(at -0.40005 0)
			(size 0.4572 0.508)
			(layers "F.Cu" "F.Mask" "F.Paste")
			(net "GND")
		)
	)
	(footprint ""
		(layer "F.Cu")
		(at 39.821358 -18.414238)
		(property "Reference" "R40"
			(at 1.662938 0.015494 0)
			(unlocked yes)
			(layer "F.SilkS")
			(effects
				(font
					(size 0.7874 0.5842)
					(thickness 0.1524)
				)
				(justify left)
			)
		)
		(property "Value" ""
			(at 0 0 0)
			(layer "F.Fab")
			(effects
				(font
					(size 1.27 1.27)
				)
			)
		)
		(duplicate_pad_numbers_are_jumpers no)
		(fp_line
			(start -0.7874 -0.4064)
			(end 0.7874 -0.4064)
			(stroke
				(width 0.1524)
				(type default)
			)
			(layer "F.SilkS")
		)
		(fp_line
			(start -0.7874 0.4064)
			(end -0.7874 -0.4064)
			(stroke
				(width 0.1524)
				(type default)
			)
			(layer "F.SilkS")
		)
		(fp_line
			(start 0.7874 -0.4064)
			(end 0.7874 0.4064)
			(stroke
				(width 0.1524)
				(type default)
			)
			(layer "F.SilkS")
		)
		(fp_line
			(start 0.7874 0.4064)
			(end -0.7874 0.4064)
			(stroke
				(width 0.1524)
				(type default)
			)
			(layer "F.SilkS")
		)
		(fp_poly
			(pts
				(xy -0.508 0.2794) (xy -0.508 0.2286) (xy -0.635 0.2286) (xy -0.635 -0.254) (xy -0.5334 -0.254)
				(xy -0.5334 -0.2794) (xy 0.5334 -0.2794) (xy 0.5334 -0.254) (xy 0.635 -0.254) (xy 0.635 0.254) (xy 0.5334 0.254)
				(xy 0.5334 0.2794)
			)
			(stroke
				(width 0)
				(type default)
			)
			(fill no)
			(layer "F.CrtYd")
		)
		(pad "1" smd rect
			(at 0.40005 0)
			(size 0.4572 0.508)
			(layers "F.Cu" "F.Mask" "F.Paste")
			(net "GND")
		)
		(pad "2" smd rect
			(at -0.40005 0)
			(size 0.4572 0.508)
			(layers "F.Cu" "F.Mask" "F.Paste")
			(net "P12V_STBY")
		)
	)
	(footprint ""
		(layer "F.Cu")
		(at 27.246072 -20.26412 -90)
		(property "Reference" "R87"
			(at -1.149604 0.97536 90)
			(unlocked yes)
			(layer "F.SilkS")
			(effects
				(font
					(size 0.7874 0.5842)
					(thickness 0.1524)
				)
				(justify left)
			)
		)
		(property "Value" ""
			(at 0 0 270)
			(layer "F.Fab")
			(effects
				(font
					(size 1.27 1.27)
				)
			)
		)
		(duplicate_pad_numbers_are_jumpers no)
		(fp_line
			(start -0.7874 0.4064)
			(end -0.7874 -0.4064)
			(stroke
				(width 0.1524)
				(type default)
			)
			(layer "F.SilkS")
		)
		(fp_line
			(start 0.7874 0.4064)
			(end -0.7874 0.4064)
			(stroke
				(width 0.1524)
				(type default)
			)
			(layer "F.SilkS")
		)
		(fp_line
			(start -0.7874 -0.4064)
			(end 0.7874 -0.4064)
			(stroke
				(width 0.1524)
				(type default)
			)
			(layer "F.SilkS")
		)
		(fp_line
			(start 0.7874 -0.4064)
			(end 0.7874 0.4064)
			(stroke
				(width 0.1524)
				(type default)
			)
			(layer "F.SilkS")
		)
		(fp_poly
			(pts
				(xy -0.508 0.2794) (xy -0.508 0.2286) (xy -0.635 0.2286) (xy -0.635 -0.254) (xy -0.5334 -0.254)
				(xy -0.5334 -0.2794) (xy 0.5334 -0.2794) (xy 0.5334 -0.254) (xy 0.635 -0.254) (xy 0.635 0.254) (xy 0.5334 0.254)
				(xy 0.5334 0.2794)
			)
			(stroke
				(width 0)
				(type default)
			)
			(fill no)
			(layer "F.CrtYd")
		)
		(pad "1" smd rect
			(at 0.40005 0 270)
			(size 0.4572 0.508)
			(layers "F.Cu" "F.Mask" "F.Paste")
			(net "PSU1_REMOTE_N")
		)
		(pad "2" smd rect
			(at -0.40005 0 270)
			(size 0.4572 0.508)
			(layers "F.Cu" "F.Mask" "F.Paste")
			(net "PSU1_REMOTE_R_N")
		)
	)
	(footprint ""
		(layer "F.Cu")
		(at 80.947006 -297.892216 180)
		(property "Reference" "R123"
			(at 1.088644 1.215136 0)
			(unlocked yes)
			(layer "F.SilkS")
			(effects
				(font
					(size 0.7874 0.5842)
					(thickness 0.1524)
				)
				(justify left)
			)
		)
		(property "Value" ""
			(at 0 0 180)
			(layer "F.Fab")
			(effects
				(font
					(size 1.27 1.27)
				)
			)
		)
		(duplicate_pad_numbers_are_jumpers no)
		(fp_line
			(start 0.7874 0.4064)
			(end -0.7874 0.4064)
			(stroke
				(width 0.1524)
				(type default)
			)
			(layer "F.SilkS")
		)
		(fp_line
			(start 0.7874 -0.4064)
			(end 0.7874 0.4064)
			(stroke
				(width 0.1524)
				(type default)
			)
			(layer "F.SilkS")
		)
		(fp_line
			(start -0.7874 0.4064)
			(end -0.7874 -0.4064)
			(stroke
				(width 0.1524)
				(type default)
			)
			(layer "F.SilkS")
		)
		(fp_line
			(start -0.7874 -0.4064)
			(end 0.7874 -0.4064)
			(stroke
				(width 0.1524)
				(type default)
			)
			(layer "F.SilkS")
		)
		(fp_poly
			(pts
				(xy -0.508 0.2794) (xy -0.508 0.2286) (xy -0.635 0.2286) (xy -0.635 -0.254) (xy -0.5334 -0.254)
				(xy -0.5334 -0.2794) (xy 0.5334 -0.2794) (xy 0.5334 -0.254) (xy 0.635 -0.254) (xy 0.635 0.254) (xy 0.5334 0.254)
				(xy 0.5334 0.2794)
			)
			(stroke
				(width 0)
				(type default)
			)
			(fill no)
			(layer "F.CrtYd")
		)
		(pad "1" smd rect
			(at 0.40005 0 180)
			(size 0.4572 0.508)
			(layers "F.Cu" "F.Mask" "F.Paste")
			(net "PSU4_REMOTE_R2_P")
		)
		(pad "2" smd rect
			(at -0.40005 0 180)
			(size 0.4572 0.508)
			(layers "F.Cu" "F.Mask" "F.Paste")
			(net "P12V")
		)
	)
	(footprint ""
		(layer "F.Cu")
		(at 26.103834 -189.265306 180)
		(property "Reference" "R51"
			(at 4.040632 -0.318516 0)
			(unlocked yes)
			(layer "F.SilkS")
			(effects
				(font
					(size 0.7874 0.5842)
					(thickness 0.1524)
				)
				(justify left)
			)
		)
		(property "Value" ""
			(at 0 0 180)
			(layer "F.Fab")
			(effects
				(font
					(size 1.27 1.27)
				)
			)
		)
		(duplicate_pad_numbers_are_jumpers no)
		(fp_line
			(start 0.7874 0.4064)
			(end -0.7874 0.4064)
			(stroke
				(width 0.1524)
				(type default)
			)
			(layer "F.SilkS")
		)
		(fp_line
			(start 0.7874 -0.4064)
			(end 0.7874 0.4064)
			(stroke
				(width 0.1524)
				(type default)
			)
			(layer "F.SilkS")
		)
		(fp_line
			(start -0.7874 0.4064)
			(end -0.7874 -0.4064)
			(stroke
				(width 0.1524)
				(type default)
			)
			(layer "F.SilkS")
		)
		(fp_line
			(start -0.7874 -0.4064)
			(end 0.7874 -0.4064)
			(stroke
				(width 0.1524)
				(type default)
			)
			(layer "F.SilkS")
		)
		(fp_poly
			(pts
				(xy -0.508 0.2794) (xy -0.508 0.2286) (xy -0.635 0.2286) (xy -0.635 -0.254) (xy -0.5334 -0.254)
				(xy -0.5334 -0.2794) (xy 0.5334 -0.2794) (xy 0.5334 -0.254) (xy 0.635 -0.254) (xy 0.635 0.254) (xy 0.5334 0.254)
				(xy 0.5334 0.2794)
			)
			(stroke
				(width 0)
				(type default)
			)
			(fill no)
			(layer "F.CrtYd")
		)
		(pad "1" smd rect
			(at 0.40005 0 180)
			(size 0.4572 0.508)
			(layers "F.Cu" "F.Mask" "F.Paste")
			(net "GND")
		)
		(pad "2" smd rect
			(at -0.40005 0 180)
			(size 0.4572 0.508)
			(layers "F.Cu" "F.Mask" "F.Paste")
			(net "PSU3_PS_ON_N")
		)
	)
	(footprint ""
		(layer "F.Cu")
		(at 27.640026 -461.429862 90)
		(property "Reference" "R133"
			(at -3.59664 -1.369314 90)
			(unlocked yes)
			(layer "F.SilkS")
			(effects
				(font
					(size 0.7874 0.5842)
					(thickness 0.1524)
				)
				(justify left)
			)
		)
		(property "Value" ""
			(at 0 0 90)
			(layer "F.Fab")
			(effects
				(font
					(size 1.27 1.27)
				)
			)
		)
		(duplicate_pad_numbers_are_jumpers no)
		(fp_line
			(start 0.7874 -0.4064)
			(end 0.7874 0.4064)
			(stroke
				(width 0.1524)
				(type default)
			)
			(layer "F.SilkS")
		)
		(fp_line
			(start -0.7874 -0.4064)
			(end 0.7874 -0.4064)
			(stroke
				(width 0.1524)
				(type default)
			)
			(layer "F.SilkS")
		)
		(fp_line
			(start 0.7874 0.4064)
			(end -0.7874 0.4064)
			(stroke
				(width 0.1524)
				(type default)
			)
			(layer "F.SilkS")
		)
		(fp_line
			(start -0.7874 0.4064)
			(end -0.7874 -0.4064)
			(stroke
				(width 0.1524)
				(type default)
			)
			(layer "F.SilkS")
		)
		(fp_poly
			(pts
				(xy -0.508 0.2794) (xy -0.508 0.2286) (xy -0.635 0.2286) (xy -0.635 -0.254) (xy -0.5334 -0.254)
				(xy -0.5334 -0.2794) (xy 0.5334 -0.2794) (xy 0.5334 -0.254) (xy 0.635 -0.254) (xy 0.635 0.254) (xy 0.5334 0.254)
				(xy 0.5334 0.2794)
			)
			(stroke
				(width 0)
				(type default)
			)
			(fill no)
			(layer "F.CrtYd")
		)
		(pad "1" smd rect
			(at 0.40005 0 90)
			(size 0.4572 0.508)
			(layers "F.Cu" "F.Mask" "F.Paste")
			(net "PSU6_REMOTE_N")
		)
		(pad "2" smd rect
			(at -0.40005 0 90)
			(size 0.4572 0.508)
			(layers "F.Cu" "F.Mask" "F.Paste")
			(net "PSU6_REMOTE_R2_N")
		)
	)
	(footprint ""
		(layer "F.Cu")
		(at 69.580252 -131.443476 90)
		(property "Reference" "C27"
			(at -3.811778 -0.029718 90)
			(unlocked yes)
			(layer "F.SilkS")
			(effects
				(font
					(size 0.7874 0.5842)
					(thickness 0.1524)
				)
				(justify left)
			)
		)
		(property "Value" ""
			(at 0 0 90)
			(layer "F.Fab")
			(effects
				(font
					(size 1.27 1.27)
				)
			)
		)
		(duplicate_pad_numbers_are_jumpers no)
		(fp_line
			(start 0.7874 -0.4064)
			(end 0.7874 0.4064)
			(stroke
				(width 0.1524)
				(type default)
			)
			(layer "F.SilkS")
		)
		(fp_line
			(start -0.7874 -0.4064)
			(end 0.7874 -0.4064)
			(stroke
				(width 0.1524)
				(type default)
			)
			(layer "F.SilkS")
		)
		(fp_line
			(start 0 0.381)
			(end 0 -0.381)
			(stroke
				(width 0.1524)
				(type default)
			)
			(layer "F.SilkS")
		)
		(fp_line
			(start 0.7874 0.4064)
			(end -0.7874 0.4064)
			(stroke
				(width 0.1524)
				(type default)
			)
			(layer "F.SilkS")
		)
		(fp_line
			(start -0.7874 0.4064)
			(end -0.7874 -0.4064)
			(stroke
				(width 0.1524)
				(type default)
			)
			(layer "F.SilkS")
		)
		(fp_poly
			(pts
				(xy -0.5334 0.254) (xy -0.635 0.254) (xy -0.635 0.2286) (xy -0.635 -0.254) (xy -0.5334 -0.254) (xy -0.5334 -0.2794)
				(xy 0.5334 -0.2794) (xy 0.5334 -0.254) (xy 0.635 -0.254) (xy 0.635 0.254) (xy 0.5334 0.254) (xy 0.5334 0.2794)
				(xy -0.508 0.2794) (xy -0.5334 0.2794)
			)
			(stroke
				(width 0)
				(type default)
			)
			(fill no)
			(layer "F.CrtYd")
		)
		(pad "1" smd rect
			(at 0.40005 0 90)
			(size 0.4572 0.508)
			(layers "F.Cu" "F.Mask" "F.Paste")
			(net "P12V")
		)
		(pad "2" smd rect
			(at -0.40005 0 90)
			(size 0.4572 0.508)
			(layers "F.Cu" "F.Mask" "F.Paste")
			(net "GND")
		)
	)
	(footprint ""
		(layer "F.Cu")
		(at 39.873936 -22.379432 180)
		(property "Reference" "R1"
			(at -2.42951 0.191262 0)
			(unlocked yes)
			(layer "F.SilkS")
			(effects
				(font
					(size 0.7874 0.5842)
					(thickness 0.1524)
				)
				(justify left)
			)
		)
		(property "Value" ""
			(at 0 0 180)
			(layer "F.Fab")
			(effects
				(font
					(size 1.27 1.27)
				)
			)
		)
		(duplicate_pad_numbers_are_jumpers no)
		(fp_line
			(start 0.7874 0.4064)
			(end -0.7874 0.4064)
			(stroke
				(width 0.1524)
				(type default)
			)
			(layer "F.SilkS")
		)
		(fp_line
			(start 0.7874 -0.4064)
			(end 0.7874 0.4064)
			(stroke
				(width 0.1524)
				(type default)
			)
			(layer "F.SilkS")
		)
		(fp_line
			(start -0.7874 0.4064)
			(end -0.7874 -0.4064)
			(stroke
				(width 0.1524)
				(type default)
			)
			(layer "F.SilkS")
		)
		(fp_line
			(start -0.7874 -0.4064)
			(end 0.7874 -0.4064)
			(stroke
				(width 0.1524)
				(type default)
			)
			(layer "F.SilkS")
		)
		(fp_poly
			(pts
				(xy -0.508 0.2794) (xy -0.508 0.2286) (xy -0.635 0.2286) (xy -0.635 -0.254) (xy -0.5334 -0.254)
				(xy -0.5334 -0.2794) (xy 0.5334 -0.2794) (xy 0.5334 -0.254) (xy 0.635 -0.254) (xy 0.635 0.254) (xy 0.5334 0.254)
				(xy 0.5334 0.2794)
			)
			(stroke
				(width 0)
				(type default)
			)
			(fill no)
			(layer "F.CrtYd")
		)
		(pad "1" smd rect
			(at 0.40005 0 180)
			(size 0.4572 0.508)
			(layers "F.Cu" "F.Mask" "F.Paste")
			(net "PSU1_REMOTE_P")
		)
		(pad "2" smd rect
			(at -0.40005 0 180)
			(size 0.4572 0.508)
			(layers "F.Cu" "F.Mask" "F.Paste")
			(net "P12V")
		)
	)
	(footprint ""
		(layer "F.Cu")
		(at 13.455142 -321.89166 180)
		(property "Reference" "R143"
			(at -1.144016 -0.053848 0)
			(unlocked yes)
			(layer "F.SilkS")
			(effects
				(font
					(size 0.7874 0.5842)
					(thickness 0.1524)
				)
				(justify left)
			)
		)
		(property "Value" ""
			(at 0 0 180)
			(layer "F.Fab")
			(effects
				(font
					(size 1.27 1.27)
				)
			)
		)
		(duplicate_pad_numbers_are_jumpers no)
		(fp_line
			(start 0.7874 0.4064)
			(end -0.7874 0.4064)
			(stroke
				(width 0.1524)
				(type default)
			)
			(layer "F.SilkS")
		)
		(fp_line
			(start 0.7874 -0.4064)
			(end 0.7874 0.4064)
			(stroke
				(width 0.1524)
				(type default)
			)
			(layer "F.SilkS")
		)
		(fp_line
			(start -0.7874 0.4064)
			(end -0.7874 -0.4064)
			(stroke
				(width 0.1524)
				(type default)
			)
			(layer "F.SilkS")
		)
		(fp_line
			(start -0.7874 -0.4064)
			(end 0.7874 -0.4064)
			(stroke
				(width 0.1524)
				(type default)
			)
			(layer "F.SilkS")
		)
		(fp_poly
			(pts
				(xy -0.508 0.2794) (xy -0.508 0.2286) (xy -0.635 0.2286) (xy -0.635 -0.254) (xy -0.5334 -0.254)
				(xy -0.5334 -0.2794) (xy 0.5334 -0.2794) (xy 0.5334 -0.254) (xy 0.635 -0.254) (xy 0.635 0.254) (xy 0.5334 0.254)
				(xy 0.5334 0.2794)
			)
			(stroke
				(width 0)
				(type default)
			)
			(fill no)
			(layer "F.CrtYd")
		)
		(pad "1" smd rect
			(at 0.40005 0 180)
			(size 0.4572 0.508)
			(layers "F.Cu" "F.Mask" "F.Paste")
			(net "FAN2_TACH")
		)
		(pad "2" smd rect
			(at -0.40005 0 180)
			(size 0.4572 0.508)
			(layers "F.Cu" "F.Mask" "F.Paste")
			(net "P12V")
		)
	)
	(footprint ""
		(layer "F.Cu")
		(at 13.36929 -320.828162 180)
		(property "Reference" "R144"
			(at -1.17983 -0.176784 0)
			(unlocked yes)
			(layer "F.SilkS")
			(effects
				(font
					(size 0.7874 0.5842)
					(thickness 0.1524)
				)
				(justify left)
			)
		)
		(property "Value" ""
			(at 0 0 180)
			(layer "F.Fab")
			(effects
				(font
					(size 1.27 1.27)
				)
			)
		)
		(duplicate_pad_numbers_are_jumpers no)
		(fp_line
			(start 0.7874 0.4064)
			(end -0.7874 0.4064)
			(stroke
				(width 0.1524)
				(type default)
			)
			(layer "F.SilkS")
		)
		(fp_line
			(start 0.7874 -0.4064)
			(end 0.7874 0.4064)
			(stroke
				(width 0.1524)
				(type default)
			)
			(layer "F.SilkS")
		)
		(fp_line
			(start -0.7874 0.4064)
			(end -0.7874 -0.4064)
			(stroke
				(width 0.1524)
				(type default)
			)
			(layer "F.SilkS")
		)
		(fp_line
			(start -0.7874 -0.4064)
			(end 0.7874 -0.4064)
			(stroke
				(width 0.1524)
				(type default)
			)
			(layer "F.SilkS")
		)
		(fp_poly
			(pts
				(xy -0.508 0.2794) (xy -0.508 0.2286) (xy -0.635 0.2286) (xy -0.635 -0.254) (xy -0.5334 -0.254)
				(xy -0.5334 -0.2794) (xy 0.5334 -0.2794) (xy 0.5334 -0.254) (xy 0.635 -0.254) (xy 0.635 0.254) (xy 0.5334 0.254)
				(xy 0.5334 0.2794)
			)
			(stroke
				(width 0)
				(type default)
			)
			(fill no)
			(layer "F.CrtYd")
		)
		(pad "1" smd rect
			(at 0.40005 0 180)
			(size 0.4572 0.508)
			(layers "F.Cu" "F.Mask" "F.Paste")
			(net "FAN3_TACH")
		)
		(pad "2" smd rect
			(at -0.40005 0 180)
			(size 0.4572 0.508)
			(layers "F.Cu" "F.Mask" "F.Paste")
			(net "P12V")
		)
	)
	(footprint ""
		(layer "F.Cu")
		(at 39.934642 -374.14708)
		(property "Reference" "R44"
			(at 2.011172 0.405638 0)
			(unlocked yes)
			(layer "F.SilkS")
			(effects
				(font
					(size 0.7874 0.5842)
					(thickness 0.1524)
				)
				(justify left)
			)
		)
		(property "Value" ""
			(at 0 0 0)
			(layer "F.Fab")
			(effects
				(font
					(size 1.27 1.27)
				)
			)
		)
		(duplicate_pad_numbers_are_jumpers no)
		(fp_line
			(start -0.7874 -0.4064)
			(end 0.7874 -0.4064)
			(stroke
				(width 0.1524)
				(type default)
			)
			(layer "F.SilkS")
		)
		(fp_line
			(start -0.7874 0.4064)
			(end -0.7874 -0.4064)
			(stroke
				(width 0.1524)
				(type default)
			)
			(layer "F.SilkS")
		)
		(fp_line
			(start 0.7874 -0.4064)
			(end 0.7874 0.4064)
			(stroke
				(width 0.1524)
				(type default)
			)
			(layer "F.SilkS")
		)
		(fp_line
			(start 0.7874 0.4064)
			(end -0.7874 0.4064)
			(stroke
				(width 0.1524)
				(type default)
			)
			(layer "F.SilkS")
		)
		(fp_poly
			(pts
				(xy -0.508 0.2794) (xy -0.508 0.2286) (xy -0.635 0.2286) (xy -0.635 -0.254) (xy -0.5334 -0.254)
				(xy -0.5334 -0.2794) (xy 0.5334 -0.2794) (xy 0.5334 -0.254) (xy 0.635 -0.254) (xy 0.635 0.254) (xy 0.5334 0.254)
				(xy 0.5334 0.2794)
			)
			(stroke
				(width 0)
				(type default)
			)
			(fill no)
			(layer "F.CrtYd")
		)
		(pad "1" smd rect
			(at 0.40005 0)
			(size 0.4572 0.508)
			(layers "F.Cu" "F.Mask" "F.Paste")
			(net "GND")
		)
		(pad "2" smd rect
			(at -0.40005 0)
			(size 0.4572 0.508)
			(layers "F.Cu" "F.Mask" "F.Paste")
			(net "P12V_STBY")
		)
	)
	(footprint ""
		(layer "F.Cu")
		(at 73.909936 -149.113748 -90)
		(property "Reference" "C23"
			(at -2.638552 0.124206 90)
			(unlocked yes)
			(layer "F.SilkS")
			(effects
				(font
					(size 0.7874 0.5842)
					(thickness 0.1524)
				)
				(justify left)
			)
		)
		(property "Value" ""
			(at 0 0 270)
			(layer "F.Fab")
			(effects
				(font
					(size 1.27 1.27)
				)
			)
		)
		(duplicate_pad_numbers_are_jumpers no)
		(fp_line
			(start -0.7874 0.4064)
			(end -0.7874 -0.4064)
			(stroke
				(width 0.1524)
				(type default)
			)
			(layer "F.SilkS")
		)
		(fp_line
			(start 0.7874 0.4064)
			(end -0.7874 0.4064)
			(stroke
				(width 0.1524)
				(type default)
			)
			(layer "F.SilkS")
		)
		(fp_line
			(start 0 0.381)
			(end 0 -0.381)
			(stroke
				(width 0.1524)
				(type default)
			)
			(layer "F.SilkS")
		)
		(fp_line
			(start -0.7874 -0.4064)
			(end 0.7874 -0.4064)
			(stroke
				(width 0.1524)
				(type default)
			)
			(layer "F.SilkS")
		)
		(fp_line
			(start 0.7874 -0.4064)
			(end 0.7874 0.4064)
			(stroke
				(width 0.1524)
				(type default)
			)
			(layer "F.SilkS")
		)
		(fp_poly
			(pts
				(xy -0.5334 0.254) (xy -0.635 0.254) (xy -0.635 0.2286) (xy -0.635 -0.254) (xy -0.5334 -0.254) (xy -0.5334 -0.2794)
				(xy 0.5334 -0.2794) (xy 0.5334 -0.254) (xy 0.635 -0.254) (xy 0.635 0.254) (xy 0.5334 0.254) (xy 0.5334 0.2794)
				(xy -0.508 0.2794) (xy -0.5334 0.2794)
			)
			(stroke
				(width 0)
				(type default)
			)
			(fill no)
			(layer "F.CrtYd")
		)
		(pad "1" smd rect
			(at 0.40005 0 270)
			(size 0.4572 0.508)
			(layers "F.Cu" "F.Mask" "F.Paste")
			(net "P12V")
		)
		(pad "2" smd rect
			(at -0.40005 0 270)
			(size 0.4572 0.508)
			(layers "F.Cu" "F.Mask" "F.Paste")
			(net "GND")
		)
	)
	(footprint ""
		(layer "F.Cu")
		(at 91.399868 -108.909866)
		(property "Reference" "H17"
			(at -5.1308 -5.23113 0)
			(unlocked yes)
			(layer "F.SilkS")
			(effects
				(font
					(size 0.7874 0.5842)
					(thickness 0.1524)
				)
				(justify left)
			)
		)
		(property "Value" ""
			(at 0 0 0)
			(layer "F.Fab")
			(effects
				(font
					(size 1.27 1.27)
				)
			)
		)
		(duplicate_pad_numbers_are_jumpers no)
		(fp_circle
			(center 0 0)
			(end 4.826 0)
			(stroke
				(width 0.1524)
				(type default)
			)
			(fill no)
			(layer "F.SilkS")
		)
		(fp_circle
			(center 0 0)
			(end 4.826 0)
			(stroke
				(width 0.1524)
				(type default)
			)
			(fill no)
			(layer "B.SilkS")
		)
		(fp_poly
			(pts
				(arc
					(start 0 4.0132)
					(mid 0 -4.0132)
					(end 0 4.0132)
				)
			)
			(stroke
				(width 0)
				(type default)
			)
			(fill no)
			(layer "F.CrtYd")
		)
		(pad "" np_thru_hole circle
			(at 0 0)
			(size 8.001 8.001)
			(drill 8.001)
			(layers "*.Cu" "*.Mask")
			(clearance 0.381)
			(thermal_gap 0.381)
		)
		(zone
			(layers "F.Cu" "B.Cu" "In1.Cu" "In2.Cu" "In3.Cu" "In4.Cu" "In5.Cu" "In6.Cu")
			(hatch none 0.5)
			(connect_pads
				(clearance 0)
			)
			(min_thickness 0.25)
			(keepout
				(tracks not_allowed)
				(vias allowed)
				(pads allowed)
				(copperpour not_allowed)
				(footprints allowed)
			)
			(placement
				(enabled no)
				(sheetname "")
			)
			(fill
				(thermal_gap 0.5)
				(thermal_bridge_width 0.5)
				(island_removal_mode 0)
			)
			(polygon
				(pts
					(arc
						(start 91.399868 -104.388666)
						(mid 91.399868 -113.431066)
						(end 91.399868 -104.388666)
					)
				)
			)
		)
	)
	(footprint ""
		(layer "F.Cu")
		(at 68.639436 -371.109748 -90)
		(property "Reference" "C57"
			(at -3.246628 0.156972 90)
			(unlocked yes)
			(layer "F.SilkS")
			(effects
				(font
					(size 0.7874 0.5842)
					(thickness 0.1524)
				)
			)
		)
		(property "Value" ""
			(at 0 0 270)
			(layer "F.Fab")
			(effects
				(font
					(size 1.27 1.27)
				)
			)
		)
		(duplicate_pad_numbers_are_jumpers no)
		(fp_line
			(start -1.2954 0.5842)
			(end -1.2954 -0.5842)
			(stroke
				(width 0.1524)
				(type default)
			)
			(layer "F.SilkS")
		)
		(fp_line
			(start 1.2954 0.5842)
			(end -1.2954 0.5842)
			(stroke
				(width 0.1524)
				(type default)
			)
			(layer "F.SilkS")
		)
		(fp_line
			(start -1.2954 -0.5842)
			(end 1.2954 -0.5842)
			(stroke
				(width 0.1524)
				(type default)
			)
			(layer "F.SilkS")
		)
		(fp_line
			(start 0 -0.5842)
			(end 0 0.5842)
			(stroke
				(width 0.1524)
				(type default)
			)
			(layer "F.SilkS")
		)
		(fp_line
			(start 1.2954 -0.5842)
			(end 1.2954 0.5842)
			(stroke
				(width 0.1524)
				(type default)
			)
			(layer "F.SilkS")
		)
		(fp_poly
			(pts
				(xy 0.8636 -0.4572) (xy 0.8636 -0.3556) (xy 1.143 -0.3556) (xy 1.143 0.3556) (xy 0.8636 0.3556)
				(xy 0.8636 0.4572) (xy -0.8636 0.4572) (xy -0.8636 0.3556) (xy -1.143 0.3556) (xy -1.143 -0.3556)
				(xy -0.8636 -0.3556) (xy -0.8636 -0.4572)
			)
			(stroke
				(width 0)
				(type default)
			)
			(fill no)
			(layer "F.CrtYd")
		)
		(fp_line
			(start -0.884936 0.504952)
			(end -0.884936 -0.504952)
			(stroke
				(width 0.1)
				(type default)
			)
			(layer "F.Fab")
		)
		(fp_line
			(start 0.884936 0.504952)
			(end -0.884936 0.504952)
			(stroke
				(width 0.1)
				(type default)
			)
			(layer "F.Fab")
		)
		(fp_line
			(start -0.884936 -0.504952)
			(end 0.884936 -0.504952)
			(stroke
				(width 0.1)
				(type default)
			)
			(layer "F.Fab")
		)
		(fp_line
			(start 0.884936 -0.504952)
			(end 0.884936 0.504952)
			(stroke
				(width 0.1)
				(type default)
			)
			(layer "F.Fab")
		)
		(pad "1" smd rect
			(at 0.7366 0)
			(size 0.7112 0.8128)
			(layers "F.Cu" "F.Mask" "F.Paste")
			(net "P12V")
		)
		(pad "2" smd rect
			(at -0.7366 0)
			(size 0.7112 0.8128)
			(layers "F.Cu" "F.Mask" "F.Paste")
			(net "GND")
		)
	)
	(footprint ""
		(layer "F.Cu")
		(at 70.278244 -220.425772 90)
		(property "Reference" "C41"
			(at -3.909568 -0.209296 90)
			(unlocked yes)
			(layer "F.SilkS")
			(effects
				(font
					(size 0.7874 0.5842)
					(thickness 0.1524)
				)
				(justify left)
			)
		)
		(property "Value" ""
			(at 0 0 90)
			(layer "F.Fab")
			(effects
				(font
					(size 1.27 1.27)
				)
			)
		)
		(duplicate_pad_numbers_are_jumpers no)
		(fp_line
			(start 0.7874 -0.4064)
			(end 0.7874 0.4064)
			(stroke
				(width 0.1524)
				(type default)
			)
			(layer "F.SilkS")
		)
		(fp_line
			(start -0.7874 -0.4064)
			(end 0.7874 -0.4064)
			(stroke
				(width 0.1524)
				(type default)
			)
			(layer "F.SilkS")
		)
		(fp_line
			(start 0 0.381)
			(end 0 -0.381)
			(stroke
				(width 0.1524)
				(type default)
			)
			(layer "F.SilkS")
		)
		(fp_line
			(start 0.7874 0.4064)
			(end -0.7874 0.4064)
			(stroke
				(width 0.1524)
				(type default)
			)
			(layer "F.SilkS")
		)
		(fp_line
			(start -0.7874 0.4064)
			(end -0.7874 -0.4064)
			(stroke
				(width 0.1524)
				(type default)
			)
			(layer "F.SilkS")
		)
		(fp_poly
			(pts
				(xy -0.5334 0.254) (xy -0.635 0.254) (xy -0.635 0.2286) (xy -0.635 -0.254) (xy -0.5334 -0.254) (xy -0.5334 -0.2794)
				(xy 0.5334 -0.2794) (xy 0.5334 -0.254) (xy 0.635 -0.254) (xy 0.635 0.254) (xy 0.5334 0.254) (xy 0.5334 0.2794)
				(xy -0.508 0.2794) (xy -0.5334 0.2794)
			)
			(stroke
				(width 0)
				(type default)
			)
			(fill no)
			(layer "F.CrtYd")
		)
		(pad "1" smd rect
			(at 0.40005 0 90)
			(size 0.4572 0.508)
			(layers "F.Cu" "F.Mask" "F.Paste")
			(net "P12V")
		)
		(pad "2" smd rect
			(at -0.40005 0 90)
			(size 0.4572 0.508)
			(layers "F.Cu" "F.Mask" "F.Paste")
			(net "GND")
		)
	)
	(footprint ""
		(layer "F.Cu")
		(at 39.90086 -194.114674 180)
		(property "Reference" "R13"
			(at -1.710182 -0.085344 0)
			(unlocked yes)
			(layer "F.SilkS")
			(effects
				(font
					(size 0.7874 0.5842)
					(thickness 0.1524)
				)
				(justify left)
			)
		)
		(property "Value" ""
			(at 0 0 180)
			(layer "F.Fab")
			(effects
				(font
					(size 1.27 1.27)
				)
			)
		)
		(duplicate_pad_numbers_are_jumpers no)
		(fp_line
			(start 0.7874 0.4064)
			(end -0.7874 0.4064)
			(stroke
				(width 0.1524)
				(type default)
			)
			(layer "F.SilkS")
		)
		(fp_line
			(start 0.7874 -0.4064)
			(end 0.7874 0.4064)
			(stroke
				(width 0.1524)
				(type default)
			)
			(layer "F.SilkS")
		)
		(fp_line
			(start -0.7874 0.4064)
			(end -0.7874 -0.4064)
			(stroke
				(width 0.1524)
				(type default)
			)
			(layer "F.SilkS")
		)
		(fp_line
			(start -0.7874 -0.4064)
			(end 0.7874 -0.4064)
			(stroke
				(width 0.1524)
				(type default)
			)
			(layer "F.SilkS")
		)
		(fp_poly
			(pts
				(xy -0.508 0.2794) (xy -0.508 0.2286) (xy -0.635 0.2286) (xy -0.635 -0.254) (xy -0.5334 -0.254)
				(xy -0.5334 -0.2794) (xy 0.5334 -0.2794) (xy 0.5334 -0.254) (xy 0.635 -0.254) (xy 0.635 0.254) (xy 0.5334 0.254)
				(xy 0.5334 0.2794)
			)
			(stroke
				(width 0)
				(type default)
			)
			(fill no)
			(layer "F.CrtYd")
		)
		(pad "1" smd rect
			(at 0.40005 0 180)
			(size 0.4572 0.508)
			(layers "F.Cu" "F.Mask" "F.Paste")
			(net "PSU3_AD0")
		)
		(pad "2" smd rect
			(at -0.40005 0 180)
			(size 0.4572 0.508)
			(layers "F.Cu" "F.Mask" "F.Paste")
			(net "GND")
		)
	)
	(footprint ""
		(layer "F.Cu")
		(at 68.716144 -117.627146 180)
		(property "Reference" "R116"
			(at 1.552448 -1.398016 0)
			(unlocked yes)
			(layer "F.SilkS")
			(effects
				(font
					(size 0.7874 0.5842)
					(thickness 0.1524)
				)
				(justify left)
			)
		)
		(property "Value" ""
			(at 0 0 180)
			(layer "F.Fab")
			(effects
				(font
					(size 1.27 1.27)
				)
			)
		)
		(duplicate_pad_numbers_are_jumpers no)
		(fp_line
			(start 0.7874 0.4064)
			(end -0.7874 0.4064)
			(stroke
				(width 0.1524)
				(type default)
			)
			(layer "F.SilkS")
		)
		(fp_line
			(start 0.7874 -0.4064)
			(end 0.7874 0.4064)
			(stroke
				(width 0.1524)
				(type default)
			)
			(layer "F.SilkS")
		)
		(fp_line
			(start -0.7874 0.4064)
			(end -0.7874 -0.4064)
			(stroke
				(width 0.1524)
				(type default)
			)
			(layer "F.SilkS")
		)
		(fp_line
			(start -0.7874 -0.4064)
			(end 0.7874 -0.4064)
			(stroke
				(width 0.1524)
				(type default)
			)
			(layer "F.SilkS")
		)
		(fp_poly
			(pts
				(xy -0.508 0.2794) (xy -0.508 0.2286) (xy -0.635 0.2286) (xy -0.635 -0.254) (xy -0.5334 -0.254)
				(xy -0.5334 -0.2794) (xy 0.5334 -0.2794) (xy 0.5334 -0.254) (xy 0.635 -0.254) (xy 0.635 0.254) (xy 0.5334 0.254)
				(xy 0.5334 0.2794)
			)
			(stroke
				(width 0)
				(type default)
			)
			(fill no)
			(layer "F.CrtYd")
		)
		(pad "1" smd rect
			(at 0.40005 0 180)
			(size 0.4572 0.508)
			(layers "F.Cu" "F.Mask" "F.Paste")
			(net "PSU2_REMOTE_R2_N")
		)
		(pad "2" smd rect
			(at -0.40005 0 180)
			(size 0.4572 0.508)
			(layers "F.Cu" "F.Mask" "F.Paste")
			(net "GND")
		)
	)
	(footprint ""
		(layer "F.Cu")
		(at 39.460424 -198.769478 90)
		(property "Reference" "R118"
			(at -0.484632 1.99009 0)
			(unlocked yes)
			(layer "F.SilkS")
			(effects
				(font
					(size 0.7874 0.5842)
					(thickness 0.1524)
				)
				(justify left)
			)
		)
		(property "Value" ""
			(at 0 0 90)
			(layer "F.Fab")
			(effects
				(font
					(size 1.27 1.27)
				)
			)
		)
		(duplicate_pad_numbers_are_jumpers no)
		(fp_line
			(start 0.7874 -0.4064)
			(end 0.7874 0.4064)
			(stroke
				(width 0.1524)
				(type default)
			)
			(layer "F.SilkS")
		)
		(fp_line
			(start -0.7874 -0.4064)
			(end 0.7874 -0.4064)
			(stroke
				(width 0.1524)
				(type default)
			)
			(layer "F.SilkS")
		)
		(fp_line
			(start 0.7874 0.4064)
			(end -0.7874 0.4064)
			(stroke
				(width 0.1524)
				(type default)
			)
			(layer "F.SilkS")
		)
		(fp_line
			(start -0.7874 0.4064)
			(end -0.7874 -0.4064)
			(stroke
				(width 0.1524)
				(type default)
			)
			(layer "F.SilkS")
		)
		(fp_poly
			(pts
				(xy -0.508 0.2794) (xy -0.508 0.2286) (xy -0.635 0.2286) (xy -0.635 -0.254) (xy -0.5334 -0.254)
				(xy -0.5334 -0.2794) (xy 0.5334 -0.2794) (xy 0.5334 -0.254) (xy 0.635 -0.254) (xy 0.635 0.254) (xy 0.5334 0.254)
				(xy 0.5334 0.2794)
			)
			(stroke
				(width 0)
				(type default)
			)
			(fill no)
			(layer "F.CrtYd")
		)
		(pad "1" smd rect
			(at 0.40005 0 90)
			(size 0.4572 0.508)
			(layers "F.Cu" "F.Mask" "F.Paste")
			(net "PSU3_REMOTE_P")
		)
		(pad "2" smd rect
			(at -0.40005 0 90)
			(size 0.4572 0.508)
			(layers "F.Cu" "F.Mask" "F.Paste")
			(net "PSU3_REMOTE_R2_P")
		)
	)
	(footprint ""
		(layer "F.Cu")
		(at 27.577542 -373.832628 -90)
		(property "Reference" "R105"
			(at -1.488948 1.318514 90)
			(unlocked yes)
			(layer "F.SilkS")
			(effects
				(font
					(size 0.7874 0.5842)
					(thickness 0.1524)
				)
				(justify left)
			)
		)
		(property "Value" ""
			(at 0 0 270)
			(layer "F.Fab")
			(effects
				(font
					(size 1.27 1.27)
				)
			)
		)
		(duplicate_pad_numbers_are_jumpers no)
		(fp_line
			(start -0.7874 0.4064)
			(end -0.7874 -0.4064)
			(stroke
				(width 0.1524)
				(type default)
			)
			(layer "F.SilkS")
		)
		(fp_line
			(start 0.7874 0.4064)
			(end -0.7874 0.4064)
			(stroke
				(width 0.1524)
				(type default)
			)
			(layer "F.SilkS")
		)
		(fp_line
			(start -0.7874 -0.4064)
			(end 0.7874 -0.4064)
			(stroke
				(width 0.1524)
				(type default)
			)
			(layer "F.SilkS")
		)
		(fp_line
			(start 0.7874 -0.4064)
			(end 0.7874 0.4064)
			(stroke
				(width 0.1524)
				(type default)
			)
			(layer "F.SilkS")
		)
		(fp_poly
			(pts
				(xy -0.508 0.2794) (xy -0.508 0.2286) (xy -0.635 0.2286) (xy -0.635 -0.254) (xy -0.5334 -0.254)
				(xy -0.5334 -0.2794) (xy 0.5334 -0.2794) (xy 0.5334 -0.254) (xy 0.635 -0.254) (xy 0.635 0.254) (xy 0.5334 0.254)
				(xy 0.5334 0.2794)
			)
			(stroke
				(width 0)
				(type default)
			)
			(fill no)
			(layer "F.CrtYd")
		)
		(pad "1" smd rect
			(at 0.40005 0 270)
			(size 0.4572 0.508)
			(layers "F.Cu" "F.Mask" "F.Paste")
			(net "PSU5_REMOTE_N")
		)
		(pad "2" smd rect
			(at -0.40005 0 270)
			(size 0.4572 0.508)
			(layers "F.Cu" "F.Mask" "F.Paste")
			(net "PSU5_REMOTE_R_N")
		)
	)
	(footprint ""
		(layer "F.Cu")
		(at 66.82994 -32.569912 180)
		(property "Reference" "R111"
			(at 1.090422 -1.06934 0)
			(unlocked yes)
			(layer "F.SilkS")
			(effects
				(font
					(size 0.7874 0.5842)
					(thickness 0.1524)
				)
				(justify left)
			)
		)
		(property "Value" ""
			(at 0 0 180)
			(layer "F.Fab")
			(effects
				(font
					(size 1.27 1.27)
				)
			)
		)
		(duplicate_pad_numbers_are_jumpers no)
		(fp_line
			(start 0.7874 0.4064)
			(end -0.7874 0.4064)
			(stroke
				(width 0.1524)
				(type default)
			)
			(layer "F.SilkS")
		)
		(fp_line
			(start 0.7874 -0.4064)
			(end 0.7874 0.4064)
			(stroke
				(width 0.1524)
				(type default)
			)
			(layer "F.SilkS")
		)
		(fp_line
			(start -0.7874 0.4064)
			(end -0.7874 -0.4064)
			(stroke
				(width 0.1524)
				(type default)
			)
			(layer "F.SilkS")
		)
		(fp_line
			(start -0.7874 -0.4064)
			(end 0.7874 -0.4064)
			(stroke
				(width 0.1524)
				(type default)
			)
			(layer "F.SilkS")
		)
		(fp_poly
			(pts
				(xy -0.508 0.2794) (xy -0.508 0.2286) (xy -0.635 0.2286) (xy -0.635 -0.254) (xy -0.5334 -0.254)
				(xy -0.5334 -0.2794) (xy 0.5334 -0.2794) (xy 0.5334 -0.254) (xy 0.635 -0.254) (xy 0.635 0.254) (xy 0.5334 0.254)
				(xy 0.5334 0.2794)
			)
			(stroke
				(width 0)
				(type default)
			)
			(fill no)
			(layer "F.CrtYd")
		)
		(pad "1" smd rect
			(at 0.40005 0 180)
			(size 0.4572 0.508)
			(layers "F.Cu" "F.Mask" "F.Paste")
			(net "PSU1_REMOTE_R2_P")
		)
		(pad "2" smd rect
			(at -0.40005 0 180)
			(size 0.4572 0.508)
			(layers "F.Cu" "F.Mask" "F.Paste")
			(net "P12V")
		)
	)
	(footprint ""
		(layer "F.Cu")
		(at 27.244802 -19.46402 90)
		(property "Reference" "R113"
			(at -3.094482 -0.932688 90)
			(unlocked yes)
			(layer "F.SilkS")
			(effects
				(font
					(size 0.7874 0.5842)
					(thickness 0.1524)
				)
				(justify left)
			)
		)
		(property "Value" ""
			(at 0 0 90)
			(layer "F.Fab")
			(effects
				(font
					(size 1.27 1.27)
				)
			)
		)
		(duplicate_pad_numbers_are_jumpers no)
		(fp_line
			(start 0.7874 -0.4064)
			(end 0.7874 0.4064)
			(stroke
				(width 0.1524)
				(type default)
			)
			(layer "F.SilkS")
		)
		(fp_line
			(start -0.7874 -0.4064)
			(end 0.7874 -0.4064)
			(stroke
				(width 0.1524)
				(type default)
			)
			(layer "F.SilkS")
		)
		(fp_line
			(start 0.7874 0.4064)
			(end -0.7874 0.4064)
			(stroke
				(width 0.1524)
				(type default)
			)
			(layer "F.SilkS")
		)
		(fp_line
			(start -0.7874 0.4064)
			(end -0.7874 -0.4064)
			(stroke
				(width 0.1524)
				(type default)
			)
			(layer "F.SilkS")
		)
		(fp_poly
			(pts
				(xy -0.508 0.2794) (xy -0.508 0.2286) (xy -0.635 0.2286) (xy -0.635 -0.254) (xy -0.5334 -0.254)
				(xy -0.5334 -0.2794) (xy 0.5334 -0.2794) (xy 0.5334 -0.254) (xy 0.635 -0.254) (xy 0.635 0.254) (xy 0.5334 0.254)
				(xy 0.5334 0.2794)
			)
			(stroke
				(width 0)
				(type default)
			)
			(fill no)
			(layer "F.CrtYd")
		)
		(pad "1" smd rect
			(at 0.40005 0 90)
			(size 0.4572 0.508)
			(layers "F.Cu" "F.Mask" "F.Paste")
			(net "PSU1_REMOTE_N")
		)
		(pad "2" smd rect
			(at -0.40005 0 90)
			(size 0.4572 0.508)
			(layers "F.Cu" "F.Mask" "F.Paste")
			(net "PSU1_REMOTE_R2_N")
		)
	)
	(footprint ""
		(layer "F.Cu")
		(at 91.399868 -508.96012)
		(property "Reference" "H24"
			(at -5.1308 -5.23113 0)
			(unlocked yes)
			(layer "F.SilkS")
			(effects
				(font
					(size 0.7874 0.5842)
					(thickness 0.1524)
				)
				(justify left)
			)
		)
		(property "Value" ""
			(at 0 0 0)
			(layer "F.Fab")
			(effects
				(font
					(size 1.27 1.27)
				)
			)
		)
		(duplicate_pad_numbers_are_jumpers no)
		(fp_circle
			(center 0 0)
			(end 4.826 0)
			(stroke
				(width 0.1524)
				(type default)
			)
			(fill no)
			(layer "F.SilkS")
		)
		(fp_circle
			(center 0 0)
			(end 4.826 0)
			(stroke
				(width 0.1524)
				(type default)
			)
			(fill no)
			(layer "B.SilkS")
		)
		(fp_poly
			(pts
				(arc
					(start 0 4.0132)
					(mid 0 -4.0132)
					(end 0 4.0132)
				)
			)
			(stroke
				(width 0)
				(type default)
			)
			(fill no)
			(layer "F.CrtYd")
		)
		(pad "" np_thru_hole circle
			(at 0 0)
			(size 8.001 8.001)
			(drill 8.001)
			(layers "*.Cu" "*.Mask")
			(clearance 0.381)
			(thermal_gap 0.381)
		)
		(zone
			(layers "F.Cu" "B.Cu" "In1.Cu" "In2.Cu" "In3.Cu" "In4.Cu" "In5.Cu" "In6.Cu")
			(hatch none 0.5)
			(connect_pads
				(clearance 0)
			)
			(min_thickness 0.25)
			(keepout
				(tracks not_allowed)
				(vias allowed)
				(pads allowed)
				(copperpour not_allowed)
				(footprints allowed)
			)
			(placement
				(enabled no)
				(sheetname "")
			)
			(fill
				(thermal_gap 0.5)
				(thermal_bridge_width 0.5)
				(island_removal_mode 0)
			)
			(polygon
				(pts
					(arc
						(start 91.399868 -504.43892)
						(mid 91.399868 -513.48132)
						(end 91.399868 -504.43892)
					)
				)
			)
		)
	)
	(footprint ""
		(layer "F.Cu")
		(at 39.437056 -287.977326 -90)
		(property "Reference" "R106"
			(at -1.168146 -0.000762 90)
			(unlocked yes)
			(layer "F.SilkS")
			(effects
				(font
					(size 0.7874 0.5842)
					(thickness 0.1524)
				)
				(justify left)
			)
		)
		(property "Value" ""
			(at 0 0 270)
			(layer "F.Fab")
			(effects
				(font
					(size 1.27 1.27)
				)
			)
		)
		(duplicate_pad_numbers_are_jumpers no)
		(fp_line
			(start -0.7874 0.4064)
			(end -0.7874 -0.4064)
			(stroke
				(width 0.1524)
				(type default)
			)
			(layer "F.SilkS")
		)
		(fp_line
			(start 0.7874 0.4064)
			(end -0.7874 0.4064)
			(stroke
				(width 0.1524)
				(type default)
			)
			(layer "F.SilkS")
		)
		(fp_line
			(start -0.7874 -0.4064)
			(end 0.7874 -0.4064)
			(stroke
				(width 0.1524)
				(type default)
			)
			(layer "F.SilkS")
		)
		(fp_line
			(start 0.7874 -0.4064)
			(end 0.7874 0.4064)
			(stroke
				(width 0.1524)
				(type default)
			)
			(layer "F.SilkS")
		)
		(fp_poly
			(pts
				(xy -0.508 0.2794) (xy -0.508 0.2286) (xy -0.635 0.2286) (xy -0.635 -0.254) (xy -0.5334 -0.254)
				(xy -0.5334 -0.2794) (xy 0.5334 -0.2794) (xy 0.5334 -0.254) (xy 0.635 -0.254) (xy 0.635 0.254) (xy 0.5334 0.254)
				(xy 0.5334 0.2794)
			)
			(stroke
				(width 0)
				(type default)
			)
			(fill no)
			(layer "F.CrtYd")
		)
		(pad "1" smd rect
			(at 0.40005 0 270)
			(size 0.4572 0.508)
			(layers "F.Cu" "F.Mask" "F.Paste")
			(net "PSU4_REMOTE_P")
		)
		(pad "2" smd rect
			(at -0.40005 0 270)
			(size 0.4572 0.508)
			(layers "F.Cu" "F.Mask" "F.Paste")
			(net "PSU4_REMOTE_R_P")
		)
	)
	(footprint ""
		(layer "F.Cu")
		(at 71.423022 -60.163456 -90)
		(property "Reference" "C10"
			(at -2.559304 0.082804 90)
			(unlocked yes)
			(layer "F.SilkS")
			(effects
				(font
					(size 0.7874 0.5842)
					(thickness 0.1524)
				)
				(justify left)
			)
		)
		(property "Value" ""
			(at 0 0 270)
			(layer "F.Fab")
			(effects
				(font
					(size 1.27 1.27)
				)
			)
		)
		(duplicate_pad_numbers_are_jumpers no)
		(fp_line
			(start -0.7874 0.4064)
			(end -0.7874 -0.4064)
			(stroke
				(width 0.1524)
				(type default)
			)
			(layer "F.SilkS")
		)
		(fp_line
			(start 0.7874 0.4064)
			(end -0.7874 0.4064)
			(stroke
				(width 0.1524)
				(type default)
			)
			(layer "F.SilkS")
		)
		(fp_line
			(start 0 0.381)
			(end 0 -0.381)
			(stroke
				(width 0.1524)
				(type default)
			)
			(layer "F.SilkS")
		)
		(fp_line
			(start -0.7874 -0.4064)
			(end 0.7874 -0.4064)
			(stroke
				(width 0.1524)
				(type default)
			)
			(layer "F.SilkS")
		)
		(fp_line
			(start 0.7874 -0.4064)
			(end 0.7874 0.4064)
			(stroke
				(width 0.1524)
				(type default)
			)
			(layer "F.SilkS")
		)
		(fp_poly
			(pts
				(xy -0.5334 0.254) (xy -0.635 0.254) (xy -0.635 0.2286) (xy -0.635 -0.254) (xy -0.5334 -0.254) (xy -0.5334 -0.2794)
				(xy 0.5334 -0.2794) (xy 0.5334 -0.254) (xy 0.635 -0.254) (xy 0.635 0.254) (xy 0.5334 0.254) (xy 0.5334 0.2794)
				(xy -0.508 0.2794) (xy -0.5334 0.2794)
			)
			(stroke
				(width 0)
				(type default)
			)
			(fill no)
			(layer "F.CrtYd")
		)
		(pad "1" smd rect
			(at 0.40005 0 270)
			(size 0.4572 0.508)
			(layers "F.Cu" "F.Mask" "F.Paste")
			(net "P12V")
		)
		(pad "2" smd rect
			(at -0.40005 0 270)
			(size 0.4572 0.508)
			(layers "F.Cu" "F.Mask" "F.Paste")
			(net "GND")
		)
	)
	(footprint ""
		(layer "F.Cu")
		(at 45.911516 -260.355588 180)
		(property "Reference" "R103"
			(at 4.696206 0.233172 0)
			(unlocked yes)
			(layer "F.SilkS")
			(effects
				(font
					(size 0.7874 0.5842)
					(thickness 0.1524)
				)
				(justify left)
			)
		)
		(property "Value" ""
			(at 0 0 180)
			(layer "F.Fab")
			(effects
				(font
					(size 1.27 1.27)
				)
			)
		)
		(duplicate_pad_numbers_are_jumpers no)
		(fp_line
			(start 0.7874 0.4064)
			(end -0.7874 0.4064)
			(stroke
				(width 0.1524)
				(type default)
			)
			(layer "F.SilkS")
		)
		(fp_line
			(start 0.7874 -0.4064)
			(end 0.7874 0.4064)
			(stroke
				(width 0.1524)
				(type default)
			)
			(layer "F.SilkS")
		)
		(fp_line
			(start -0.7874 0.4064)
			(end -0.7874 -0.4064)
			(stroke
				(width 0.1524)
				(type default)
			)
			(layer "F.SilkS")
		)
		(fp_line
			(start -0.7874 -0.4064)
			(end 0.7874 -0.4064)
			(stroke
				(width 0.1524)
				(type default)
			)
			(layer "F.SilkS")
		)
		(fp_poly
			(pts
				(xy -0.508 0.2794) (xy -0.508 0.2286) (xy -0.635 0.2286) (xy -0.635 -0.254) (xy -0.5334 -0.254)
				(xy -0.5334 -0.2794) (xy 0.5334 -0.2794) (xy 0.5334 -0.254) (xy 0.635 -0.254) (xy 0.635 0.254) (xy 0.5334 0.254)
				(xy 0.5334 0.2794)
			)
			(stroke
				(width 0)
				(type default)
			)
			(fill no)
			(layer "F.CrtYd")
		)
		(pad "1" smd rect
			(at 0.40005 0 180)
			(size 0.4572 0.508)
			(layers "F.Cu" "F.Mask" "F.Paste")
			(net "PSU5_REMOTE_R_N")
		)
		(pad "2" smd rect
			(at -0.40005 0 180)
			(size 0.4572 0.508)
			(layers "F.Cu" "F.Mask" "F.Paste")
			(net "GND")
		)
	)
	(footprint ""
		(layer "F.Cu")
		(at 26.226008 -450.980556)
		(property "Reference" "R82"
			(at -3.597402 -0.121666 0)
			(unlocked yes)
			(layer "F.SilkS")
			(effects
				(font
					(size 0.7874 0.5842)
					(thickness 0.1524)
				)
				(justify left)
			)
		)
		(property "Value" ""
			(at 0 0 0)
			(layer "F.Fab")
			(effects
				(font
					(size 1.27 1.27)
				)
			)
		)
		(duplicate_pad_numbers_are_jumpers no)
		(fp_line
			(start -0.7874 -0.4064)
			(end 0.7874 -0.4064)
			(stroke
				(width 0.1524)
				(type default)
			)
			(layer "F.SilkS")
		)
		(fp_line
			(start -0.7874 0.4064)
			(end -0.7874 -0.4064)
			(stroke
				(width 0.1524)
				(type default)
			)
			(layer "F.SilkS")
		)
		(fp_line
			(start 0.7874 -0.4064)
			(end 0.7874 0.4064)
			(stroke
				(width 0.1524)
				(type default)
			)
			(layer "F.SilkS")
		)
		(fp_line
			(start 0.7874 0.4064)
			(end -0.7874 0.4064)
			(stroke
				(width 0.1524)
				(type default)
			)
			(layer "F.SilkS")
		)
		(fp_poly
			(pts
				(xy -0.508 0.2794) (xy -0.508 0.2286) (xy -0.635 0.2286) (xy -0.635 -0.254) (xy -0.5334 -0.254)
				(xy -0.5334 -0.2794) (xy 0.5334 -0.2794) (xy 0.5334 -0.254) (xy 0.635 -0.254) (xy 0.635 0.254) (xy 0.5334 0.254)
				(xy 0.5334 0.2794)
			)
			(stroke
				(width 0)
				(type default)
			)
			(fill no)
			(layer "F.CrtYd")
		)
		(pad "1" smd rect
			(at 0.40005 0)
			(size 0.4572 0.508)
			(layers "F.Cu" "F.Mask" "F.Paste")
			(net "PSU6_PS_KILL")
		)
		(pad "2" smd rect
			(at -0.40005 0)
			(size 0.4572 0.508)
			(layers "F.Cu" "F.Mask" "F.Paste")
			(net "P12V_STBY")
		)
	)
	(footprint ""
		(layer "F.Cu")
		(at 50.743612 -151.92502 180)
		(property "Reference" "CE8"
			(at -4.261612 -1.5494 0)
			(unlocked yes)
			(layer "F.SilkS")
			(effects
				(font
					(size 0.7874 0.5842)
					(thickness 0.1524)
				)
				(justify left)
			)
		)
		(property "Value" ""
			(at 0 0 180)
			(layer "F.Fab")
			(effects
				(font
					(size 1.27 1.27)
				)
			)
		)
		(duplicate_pad_numbers_are_jumpers no)
		(fp_line
			(start 0 -4.2672)
			(end 0 4.2672)
			(stroke
				(width 0.1524)
				(type default)
			)
			(layer "F.SilkS")
		)
		(fp_circle
			(center 0 0)
			(end -4.2672 0)
			(stroke
				(width 0.1524)
				(type default)
			)
			(fill no)
			(layer "F.SilkS")
		)
		(fp_poly
			(pts
				(arc
					(start 0 -4.2672)
					(mid 4.2672 0)
					(end 0 4.2672)
				)
			)
			(stroke
				(width 0)
				(type default)
			)
			(fill yes)
			(layer "F.SilkS")
		)
		(fp_poly
			(pts
				(xy -2.5146 -0.762) (xy -0.9906 -0.762) (xy -0.9906 0.762) (xy -2.5146 0.762)
			)
			(stroke
				(width 0)
				(type default)
			)
			(fill no)
			(layer "B.CrtYd")
		)
		(fp_poly
			(pts
				(arc
					(start 1.7526 0.762)
					(mid 2.291415 -0.538815)
					(end 0.9906 0)
				)
				(arc
					(start 0.9906 0.0254)
					(mid 1.206345 0.546255)
					(end 1.7272 0.762)
				)
			)
			(stroke
				(width 0)
				(type default)
			)
			(fill no)
			(layer "B.CrtYd")
		)
		(fp_poly
			(pts
				(arc
					(start -4.2672 0)
					(mid 4.2672 0)
					(end -4.2672 0)
				)
			)
			(stroke
				(width 0)
				(type default)
			)
			(fill no)
			(layer "F.CrtYd")
		)
		(fp_circle
			(center 0 0)
			(end -4.2672 0)
			(stroke
				(width 0.1)
				(type default)
			)
			(fill no)
			(layer "F.Fab")
		)
		(fp_text user "+"
			(at -4.996688 -2.849372 180)
			(unlocked yes)
			(layer "F.SilkS")
			(effects
				(font
					(size 0.7874 0.5842)
					(thickness 0.1524)
				)
				(justify left)
			)
		)
		(fp_text user "+"
			(at -5.6642 -0.34925 180)
			(unlocked yes)
			(layer "F.Fab")
			(effects
				(font
					(size 1.905 1.4224)
					(thickness 0.000001)
				)
				(justify left)
			)
		)
		(pad "1" thru_hole rect
			(at -1.75006 0 180)
			(size 1.397 1.397)
			(drill 0.9144)
			(layers "*.Cu" "*.Mask")
			(remove_unused_layers no)
			(net "P12V")
			(clearance 0.0127)
			(thermal_gap 0.0127)
			(padstack
				(mode front_inner_back)
				(layer "Inner"
					(shape circle)
					(size 1.397 1.397)
					(clearance 0.0127)
				)
				(layer "B.Cu"
					(shape rect)
					(size 1.397 1.397)
					(clearance 0.0127)
				)
			)
		)
		(pad "2" thru_hole circle
			(at 1.75006 0 180)
			(size 1.397 1.397)
			(drill 0.9144)
			(layers "*.Cu" "*.Mask")
			(remove_unused_layers no)
			(net "GND")
			(clearance 0.0127)
			(thermal_gap 0.0127)
		)
	)
	(footprint ""
		(layer "F.Cu")
		(at 26.226008 -452.257668)
		(property "Reference" "R83"
			(at -3.597402 -0.121666 0)
			(unlocked yes)
			(layer "F.SilkS")
			(effects
				(font
					(size 0.7874 0.5842)
					(thickness 0.1524)
				)
				(justify left)
			)
		)
		(property "Value" ""
			(at 0 0 0)
			(layer "F.Fab")
			(effects
				(font
					(size 1.27 1.27)
				)
			)
		)
		(duplicate_pad_numbers_are_jumpers no)
		(fp_line
			(start -0.7874 -0.4064)
			(end 0.7874 -0.4064)
			(stroke
				(width 0.1524)
				(type default)
			)
			(layer "F.SilkS")
		)
		(fp_line
			(start -0.7874 0.4064)
			(end -0.7874 -0.4064)
			(stroke
				(width 0.1524)
				(type default)
			)
			(layer "F.SilkS")
		)
		(fp_line
			(start 0.7874 -0.4064)
			(end 0.7874 0.4064)
			(stroke
				(width 0.1524)
				(type default)
			)
			(layer "F.SilkS")
		)
		(fp_line
			(start 0.7874 0.4064)
			(end -0.7874 0.4064)
			(stroke
				(width 0.1524)
				(type default)
			)
			(layer "F.SilkS")
		)
		(fp_poly
			(pts
				(xy -0.508 0.2794) (xy -0.508 0.2286) (xy -0.635 0.2286) (xy -0.635 -0.254) (xy -0.5334 -0.254)
				(xy -0.5334 -0.2794) (xy 0.5334 -0.2794) (xy 0.5334 -0.254) (xy 0.635 -0.254) (xy 0.635 0.254) (xy 0.5334 0.254)
				(xy 0.5334 0.2794)
			)
			(stroke
				(width 0)
				(type default)
			)
			(fill no)
			(layer "F.CrtYd")
		)
		(pad "1" smd rect
			(at 0.40005 0)
			(size 0.4572 0.508)
			(layers "F.Cu" "F.Mask" "F.Paste")
			(net "PSU6_PS_KILL")
		)
		(pad "2" smd rect
			(at -0.40005 0)
			(size 0.4572 0.508)
			(layers "F.Cu" "F.Mask" "F.Paste")
			(net "GND")
		)
	)
	(footprint ""
		(layer "F.Cu")
		(at 72.087232 -327.030588 -90)
		(property "Reference" "C50"
			(at -3.323844 -0.030226 90)
			(unlocked yes)
			(layer "F.SilkS")
			(effects
				(font
					(size 0.7874 0.5842)
					(thickness 0.1524)
				)
			)
		)
		(property "Value" ""
			(at 0 0 270)
			(layer "F.Fab")
			(effects
				(font
					(size 1.27 1.27)
				)
			)
		)
		(duplicate_pad_numbers_are_jumpers no)
		(fp_line
			(start -1.2954 0.5842)
			(end -1.2954 -0.5842)
			(stroke
				(width 0.1524)
				(type default)
			)
			(layer "F.SilkS")
		)
		(fp_line
			(start 1.2954 0.5842)
			(end -1.2954 0.5842)
			(stroke
				(width 0.1524)
				(type default)
			)
			(layer "F.SilkS")
		)
		(fp_line
			(start -1.2954 -0.5842)
			(end 1.2954 -0.5842)
			(stroke
				(width 0.1524)
				(type default)
			)
			(layer "F.SilkS")
		)
		(fp_line
			(start 0 -0.5842)
			(end 0 0.5842)
			(stroke
				(width 0.1524)
				(type default)
			)
			(layer "F.SilkS")
		)
		(fp_line
			(start 1.2954 -0.5842)
			(end 1.2954 0.5842)
			(stroke
				(width 0.1524)
				(type default)
			)
			(layer "F.SilkS")
		)
		(fp_poly
			(pts
				(xy 0.8636 -0.4572) (xy 0.8636 -0.3556) (xy 1.143 -0.3556) (xy 1.143 0.3556) (xy 0.8636 0.3556)
				(xy 0.8636 0.4572) (xy -0.8636 0.4572) (xy -0.8636 0.3556) (xy -1.143 0.3556) (xy -1.143 -0.3556)
				(xy -0.8636 -0.3556) (xy -0.8636 -0.4572)
			)
			(stroke
				(width 0)
				(type default)
			)
			(fill no)
			(layer "F.CrtYd")
		)
		(fp_line
			(start -0.884936 0.504952)
			(end -0.884936 -0.504952)
			(stroke
				(width 0.1)
				(type default)
			)
			(layer "F.Fab")
		)
		(fp_line
			(start 0.884936 0.504952)
			(end -0.884936 0.504952)
			(stroke
				(width 0.1)
				(type default)
			)
			(layer "F.Fab")
		)
		(fp_line
			(start -0.884936 -0.504952)
			(end 0.884936 -0.504952)
			(stroke
				(width 0.1)
				(type default)
			)
			(layer "F.Fab")
		)
		(fp_line
			(start 0.884936 -0.504952)
			(end 0.884936 0.504952)
			(stroke
				(width 0.1)
				(type default)
			)
			(layer "F.Fab")
		)
		(pad "1" smd rect
			(at 0.7366 0)
			(size 0.7112 0.8128)
			(layers "F.Cu" "F.Mask" "F.Paste")
			(net "P12V")
		)
		(pad "2" smd rect
			(at -0.7366 0)
			(size 0.7112 0.8128)
			(layers "F.Cu" "F.Mask" "F.Paste")
			(net "GND")
		)
	)
	(footprint ""
		(layer "F.Cu")
		(at 13.438124 -322.972176 180)
		(property "Reference" "R147"
			(at -1.094232 -0.065024 0)
			(unlocked yes)
			(layer "F.SilkS")
			(effects
				(font
					(size 0.7874 0.5842)
					(thickness 0.1524)
				)
				(justify left)
			)
		)
		(property "Value" ""
			(at 0 0 180)
			(layer "F.Fab")
			(effects
				(font
					(size 1.27 1.27)
				)
			)
		)
		(duplicate_pad_numbers_are_jumpers no)
		(fp_line
			(start 0.7874 0.4064)
			(end -0.7874 0.4064)
			(stroke
				(width 0.1524)
				(type default)
			)
			(layer "F.SilkS")
		)
		(fp_line
			(start 0.7874 -0.4064)
			(end 0.7874 0.4064)
			(stroke
				(width 0.1524)
				(type default)
			)
			(layer "F.SilkS")
		)
		(fp_line
			(start -0.7874 0.4064)
			(end -0.7874 -0.4064)
			(stroke
				(width 0.1524)
				(type default)
			)
			(layer "F.SilkS")
		)
		(fp_line
			(start -0.7874 -0.4064)
			(end 0.7874 -0.4064)
			(stroke
				(width 0.1524)
				(type default)
			)
			(layer "F.SilkS")
		)
		(fp_poly
			(pts
				(xy -0.508 0.2794) (xy -0.508 0.2286) (xy -0.635 0.2286) (xy -0.635 -0.254) (xy -0.5334 -0.254)
				(xy -0.5334 -0.2794) (xy 0.5334 -0.2794) (xy 0.5334 -0.254) (xy 0.635 -0.254) (xy 0.635 0.254) (xy 0.5334 0.254)
				(xy 0.5334 0.2794)
			)
			(stroke
				(width 0)
				(type default)
			)
			(fill no)
			(layer "F.CrtYd")
		)
		(pad "1" smd rect
			(at 0.40005 0 180)
			(size 0.4572 0.508)
			(layers "F.Cu" "F.Mask" "F.Paste")
			(net "FAN6_TACH")
		)
		(pad "2" smd rect
			(at -0.40005 0 180)
			(size 0.4572 0.508)
			(layers "F.Cu" "F.Mask" "F.Paste")
			(net "P12V")
		)
	)
	(footprint ""
		(layer "F.Cu")
		(at 73.00468 -42.631106 90)
		(property "Reference" "C13"
			(at -1.139444 4.766056 90)
			(unlocked yes)
			(layer "F.SilkS")
			(effects
				(font
					(size 0.7874 0.5842)
					(thickness 0.1524)
				)
				(justify left)
			)
		)
		(property "Value" ""
			(at 0 0 90)
			(layer "F.Fab")
			(effects
				(font
					(size 1.27 1.27)
				)
			)
		)
		(duplicate_pad_numbers_are_jumpers no)
		(fp_line
			(start 0.7874 -0.4064)
			(end 0.7874 0.4064)
			(stroke
				(width 0.1524)
				(type default)
			)
			(layer "F.SilkS")
		)
		(fp_line
			(start -0.7874 -0.4064)
			(end 0.7874 -0.4064)
			(stroke
				(width 0.1524)
				(type default)
			)
			(layer "F.SilkS")
		)
		(fp_line
			(start 0 0.381)
			(end 0 -0.381)
			(stroke
				(width 0.1524)
				(type default)
			)
			(layer "F.SilkS")
		)
		(fp_line
			(start 0.7874 0.4064)
			(end -0.7874 0.4064)
			(stroke
				(width 0.1524)
				(type default)
			)
			(layer "F.SilkS")
		)
		(fp_line
			(start -0.7874 0.4064)
			(end -0.7874 -0.4064)
			(stroke
				(width 0.1524)
				(type default)
			)
			(layer "F.SilkS")
		)
		(fp_poly
			(pts
				(xy -0.5334 0.254) (xy -0.635 0.254) (xy -0.635 0.2286) (xy -0.635 -0.254) (xy -0.5334 -0.254) (xy -0.5334 -0.2794)
				(xy 0.5334 -0.2794) (xy 0.5334 -0.254) (xy 0.635 -0.254) (xy 0.635 0.254) (xy 0.5334 0.254) (xy 0.5334 0.2794)
				(xy -0.508 0.2794) (xy -0.5334 0.2794)
			)
			(stroke
				(width 0)
				(type default)
			)
			(fill no)
			(layer "F.CrtYd")
		)
		(pad "1" smd rect
			(at 0.40005 0 90)
			(size 0.4572 0.508)
			(layers "F.Cu" "F.Mask" "F.Paste")
			(net "P12V")
		)
		(pad "2" smd rect
			(at -0.40005 0 90)
			(size 0.4572 0.508)
			(layers "F.Cu" "F.Mask" "F.Paste")
			(net "GND")
		)
	)
	(footprint ""
		(layer "F.Cu")
		(at 77.993494 -384.526282 180)
		(property "Reference" "R128"
			(at 1.129792 -1.375156 0)
			(unlocked yes)
			(layer "F.SilkS")
			(effects
				(font
					(size 0.7874 0.5842)
					(thickness 0.1524)
				)
				(justify left)
			)
		)
		(property "Value" ""
			(at 0 0 180)
			(layer "F.Fab")
			(effects
				(font
					(size 1.27 1.27)
				)
			)
		)
		(duplicate_pad_numbers_are_jumpers no)
		(fp_line
			(start 0.7874 0.4064)
			(end -0.7874 0.4064)
			(stroke
				(width 0.1524)
				(type default)
			)
			(layer "F.SilkS")
		)
		(fp_line
			(start 0.7874 -0.4064)
			(end 0.7874 0.4064)
			(stroke
				(width 0.1524)
				(type default)
			)
			(layer "F.SilkS")
		)
		(fp_line
			(start -0.7874 0.4064)
			(end -0.7874 -0.4064)
			(stroke
				(width 0.1524)
				(type default)
			)
			(layer "F.SilkS")
		)
		(fp_line
			(start -0.7874 -0.4064)
			(end 0.7874 -0.4064)
			(stroke
				(width 0.1524)
				(type default)
			)
			(layer "F.SilkS")
		)
		(fp_poly
			(pts
				(xy -0.508 0.2794) (xy -0.508 0.2286) (xy -0.635 0.2286) (xy -0.635 -0.254) (xy -0.5334 -0.254)
				(xy -0.5334 -0.2794) (xy 0.5334 -0.2794) (xy 0.5334 -0.254) (xy 0.635 -0.254) (xy 0.635 0.254) (xy 0.5334 0.254)
				(xy 0.5334 0.2794)
			)
			(stroke
				(width 0)
				(type default)
			)
			(fill no)
			(layer "F.CrtYd")
		)
		(pad "1" smd rect
			(at 0.40005 0 180)
			(size 0.4572 0.508)
			(layers "F.Cu" "F.Mask" "F.Paste")
			(net "PSU5_REMOTE_R2_N")
		)
		(pad "2" smd rect
			(at -0.40005 0 180)
			(size 0.4572 0.508)
			(layers "F.Cu" "F.Mask" "F.Paste")
			(net "GND")
		)
	)
	(footprint ""
		(layer "F.Cu")
		(at 76.120498 -14.939772 -90)
		(property "Reference" "C2"
			(at -1.75133 0.044704 90)
			(unlocked yes)
			(layer "F.SilkS")
			(effects
				(font
					(size 0.7874 0.5842)
					(thickness 0.1524)
				)
				(justify left)
			)
		)
		(property "Value" ""
			(at 0 0 270)
			(layer "F.Fab")
			(effects
				(font
					(size 1.27 1.27)
				)
			)
		)
		(duplicate_pad_numbers_are_jumpers no)
		(fp_line
			(start -0.7874 0.4064)
			(end -0.7874 -0.4064)
			(stroke
				(width 0.1524)
				(type default)
			)
			(layer "F.SilkS")
		)
		(fp_line
			(start 0.7874 0.4064)
			(end -0.7874 0.4064)
			(stroke
				(width 0.1524)
				(type default)
			)
			(layer "F.SilkS")
		)
		(fp_line
			(start 0 0.381)
			(end 0 -0.381)
			(stroke
				(width 0.1524)
				(type default)
			)
			(layer "F.SilkS")
		)
		(fp_line
			(start -0.7874 -0.4064)
			(end 0.7874 -0.4064)
			(stroke
				(width 0.1524)
				(type default)
			)
			(layer "F.SilkS")
		)
		(fp_line
			(start 0.7874 -0.4064)
			(end 0.7874 0.4064)
			(stroke
				(width 0.1524)
				(type default)
			)
			(layer "F.SilkS")
		)
		(fp_poly
			(pts
				(xy -0.5334 0.254) (xy -0.635 0.254) (xy -0.635 0.2286) (xy -0.635 -0.254) (xy -0.5334 -0.254) (xy -0.5334 -0.2794)
				(xy 0.5334 -0.2794) (xy 0.5334 -0.254) (xy 0.635 -0.254) (xy 0.635 0.254) (xy 0.5334 0.254) (xy 0.5334 0.2794)
				(xy -0.508 0.2794) (xy -0.5334 0.2794)
			)
			(stroke
				(width 0)
				(type default)
			)
			(fill no)
			(layer "F.CrtYd")
		)
		(pad "1" smd rect
			(at 0.40005 0 270)
			(size 0.4572 0.508)
			(layers "F.Cu" "F.Mask" "F.Paste")
			(net "P12V")
		)
		(pad "2" smd rect
			(at -0.40005 0 270)
			(size 0.4572 0.508)
			(layers "F.Cu" "F.Mask" "F.Paste")
			(net "GND")
		)
	)
	(footprint ""
		(layer "F.Cu")
		(at 30.45968 -348.52991)
		(property "Reference" "J4"
			(at 7.95274 12.227052 0)
			(unlocked yes)
			(layer "F.SilkS")
			(effects
				(font
					(size 0.7874 0.5842)
					(thickness 0.1524)
				)
				(justify left)
			)
		)
		(property "Value" ""
			(at 0 0 0)
			(layer "F.Fab")
			(effects
				(font
					(size 1.27 1.27)
				)
			)
		)
		(duplicate_pad_numbers_are_jumpers no)
		(fp_line
			(start -2.135124 -4.560062)
			(end -2.135124 83.300062)
			(stroke
				(width 0.1524)
				(type default)
			)
			(layer "F.SilkS")
		)
		(fp_line
			(start -2.135124 83.300062)
			(end 7.215124 83.300062)
			(stroke
				(width 0.1524)
				(type default)
			)
			(layer "F.SilkS")
		)
		(fp_line
			(start 7.215124 -4.560062)
			(end -2.135124 -4.560062)
			(stroke
				(width 0.1524)
				(type default)
			)
			(layer "F.SilkS")
		)
		(fp_line
			(start 7.215124 83.300062)
			(end 7.215124 -4.560062)
			(stroke
				(width 0.1524)
				(type default)
			)
			(layer "F.SilkS")
		)
		(fp_poly
			(pts
				(xy -2.422398 -0.000762) (xy -5.122418 -0.700786) (xy -5.122418 0.699262)
			)
			(stroke
				(width 0)
				(type default)
			)
			(fill yes)
			(layer "F.SilkS")
		)
		(fp_poly
			(pts
				(xy -2.28219 -0.127) (xy -4.98221 -0.827024) (xy -4.98221 0.573024)
			)
			(stroke
				(width 0)
				(type default)
			)
			(fill yes)
			(layer "B.SilkS")
		)
		(fp_poly
			(pts
				(xy -0.8636 -0.8636) (xy -0.8636 79.6036) (xy -0.8636 79.629) (xy 5.9436 79.629) (xy 5.9436 79.6036)
				(xy 5.9436 -0.8636) (xy 5.9436 -0.889) (xy -0.8636 -0.889)
			)
			(stroke
				(width 0)
				(type default)
			)
			(fill no)
			(layer "B.CrtYd")
		)
		(fp_rect
			(start -2.135124 -4.560062)
			(end 7.21487 83.300062)
			(stroke
				(width 0)
				(type default)
			)
			(fill no)
			(layer "F.CrtYd")
		)
		(fp_line
			(start -2.135124 -4.560062)
			(end 7.215124 -4.560062)
			(stroke
				(width 0.1)
				(type default)
			)
			(layer "F.Fab")
		)
		(fp_line
			(start -2.135124 83.300062)
			(end -2.135124 -4.560062)
			(stroke
				(width 0.1)
				(type default)
			)
			(layer "F.Fab")
		)
		(fp_line
			(start 7.215124 -4.560062)
			(end 7.215124 83.300062)
			(stroke
				(width 0.1)
				(type default)
			)
			(layer "F.Fab")
		)
		(fp_line
			(start 7.215124 83.300062)
			(end -2.135124 83.300062)
			(stroke
				(width 0.1)
				(type default)
			)
			(layer "F.Fab")
		)
		(fp_text user "32"
			(at -3.83159 78.970124 0)
			(unlocked yes)
			(layer "F.SilkS")
			(effects
				(font
					(size 0.7874 0.5842)
					(thickness 0.1524)
				)
				(justify left)
			)
		)
		(fp_text user "1"
			(at -3.299206 -1.063752 0)
			(unlocked yes)
			(layer "F.SilkS")
			(effects
				(font
					(size 0.7874 0.5842)
					(thickness 0.1524)
				)
				(justify left)
			)
		)
		(fp_text user "33"
			(at 7.548626 82.342482 0)
			(unlocked yes)
			(layer "F.SilkS")
			(effects
				(font
					(size 0.7874 0.5842)
					(thickness 0.1524)
				)
				(justify left)
			)
		)
		(fp_text user "64"
			(at 7.602728 -0.1905 0)
			(unlocked yes)
			(layer "F.SilkS")
			(effects
				(font
					(size 0.7874 0.5842)
					(thickness 0.1524)
				)
				(justify left)
			)
		)
		(fp_text user "1"
			(at -1.714246 -0.92456 0)
			(unlocked yes)
			(layer "B.SilkS")
			(effects
				(font
					(size 0.7874 0.5842)
					(thickness 0.1524)
				)
				(justify left mirror)
			)
		)
		(fp_text user "32"
			(at -0.789432 79.774796 0)
			(unlocked yes)
			(layer "B.SilkS")
			(effects
				(font
					(size 0.7874 0.5842)
					(thickness 0.1524)
				)
				(justify left mirror)
			)
		)
		(fp_text user "64"
			(at 5.867146 -1.71323 0)
			(unlocked yes)
			(layer "B.SilkS")
			(effects
				(font
					(size 0.7874 0.5842)
					(thickness 0.1524)
				)
				(justify left mirror)
			)
		)
		(fp_text user "33"
			(at 5.969508 82.246216 0)
			(unlocked yes)
			(layer "B.SilkS")
			(effects
				(font
					(size 0.7874 0.5842)
					(thickness 0.1524)
				)
				(justify left mirror)
			)
		)
		(pad "1" thru_hole rect
			(at 0 0 270)
			(size 1.6256 1.6256)
			(drill 1.1176)
			(layers "*.Cu" "*.Mask")
			(remove_unused_layers no)
			(net "P12V")
			(clearance 0)
			(padstack
				(mode front_inner_back)
				(layer "Inner"
					(shape circle)
					(size 1.6256 1.6256)
					(clearance 0)
				)
				(layer "B.Cu"
					(shape rect)
					(size 1.6256 1.6256)
					(clearance 0)
				)
			)
		)
		(pad "2" thru_hole circle
			(at 0 2.54 270)
			(size 1.6256 1.6256)
			(drill 1.1176)
			(layers "*.Cu" "*.Mask")
			(remove_unused_layers no)
			(net "P12V")
			(clearance 0)
		)
		(pad "3" thru_hole circle
			(at 0 5.08 270)
			(size 1.6256 1.6256)
			(drill 1.1176)
			(layers "*.Cu" "*.Mask")
			(remove_unused_layers no)
			(net "P12V")
			(clearance 0)
		)
		(pad "4" thru_hole circle
			(at 0 7.62 270)
			(size 1.6256 1.6256)
			(drill 1.1176)
			(layers "*.Cu" "*.Mask")
			(remove_unused_layers no)
			(net "P12V")
			(clearance 0)
		)
		(pad "5" thru_hole circle
			(at 0 10.16 270)
			(size 1.6256 1.6256)
			(drill 1.1176)
			(layers "*.Cu" "*.Mask")
			(remove_unused_layers no)
			(net "P12V")
			(clearance 0)
		)
		(pad "6" thru_hole circle
			(at 0 12.7 270)
			(size 1.6256 1.6256)
			(drill 1.1176)
			(layers "*.Cu" "*.Mask")
			(remove_unused_layers no)
			(net "P12V")
			(clearance 0)
		)
		(pad "7" thru_hole circle
			(at 0 15.24 270)
			(size 1.6256 1.6256)
			(drill 1.1176)
			(layers "*.Cu" "*.Mask")
			(remove_unused_layers no)
			(net "P12V")
			(clearance 0)
		)
		(pad "8" thru_hole circle
			(at 0 17.78 270)
			(size 1.6256 1.6256)
			(drill 1.1176)
			(layers "*.Cu" "*.Mask")
			(remove_unused_layers no)
			(net "P12V")
			(clearance 0)
		)
		(pad "9" thru_hole circle
			(at 0 20.32 270)
			(size 1.6256 1.6256)
			(drill 1.1176)
			(layers "*.Cu" "*.Mask")
			(remove_unused_layers no)
			(net "P12V")
			(clearance 0)
		)
		(pad "10" thru_hole circle
			(at 0 22.86 270)
			(size 1.6256 1.6256)
			(drill 1.1176)
			(layers "*.Cu" "*.Mask")
			(remove_unused_layers no)
			(net "P12V")
			(clearance 0)
		)
		(pad "11" thru_hole circle
			(at 0 25.4 270)
			(size 1.6256 1.6256)
			(drill 1.1176)
			(layers "*.Cu" "*.Mask")
			(remove_unused_layers no)
			(net "P12V")
			(clearance 0)
		)
		(pad "12" thru_hole circle
			(at 0 27.94 270)
			(size 1.6256 1.6256)
			(drill 1.1176)
			(layers "*.Cu" "*.Mask")
			(remove_unused_layers no)
			(net "P12V")
			(clearance 0)
		)
		(pad "13" thru_hole circle
			(at 0 30.48 270)
			(size 1.6256 1.6256)
			(drill 1.1176)
			(layers "*.Cu" "*.Mask")
			(remove_unused_layers no)
			(net "GND")
			(clearance 0)
		)
		(pad "14" thru_hole circle
			(at 0 33.02 270)
			(size 1.6256 1.6256)
			(drill 1.1176)
			(layers "*.Cu" "*.Mask")
			(remove_unused_layers no)
			(net "GND")
			(clearance 0)
		)
		(pad "15" thru_hole circle
			(at 0 35.56 270)
			(size 1.6256 1.6256)
			(drill 1.1176)
			(layers "*.Cu" "*.Mask")
			(remove_unused_layers no)
			(net "GND")
			(clearance 0)
		)
		(pad "16" thru_hole circle
			(at 0 38.1 270)
			(size 1.6256 1.6256)
			(drill 1.1176)
			(layers "*.Cu" "*.Mask")
			(remove_unused_layers no)
			(net "GND")
			(clearance 0)
		)
		(pad "17" thru_hole circle
			(at 0 40.64 270)
			(size 1.6256 1.6256)
			(drill 1.1176)
			(layers "*.Cu" "*.Mask")
			(remove_unused_layers no)
			(net "GND")
			(clearance 0)
		)
		(pad "18" thru_hole circle
			(at 0 43.18 270)
			(size 1.6256 1.6256)
			(drill 1.1176)
			(layers "*.Cu" "*.Mask")
			(remove_unused_layers no)
			(net "GND")
			(clearance 0)
		)
		(pad "19" thru_hole circle
			(at 0 45.72 270)
			(size 1.6256 1.6256)
			(drill 1.1176)
			(layers "*.Cu" "*.Mask")
			(remove_unused_layers no)
			(net "GND")
			(clearance 0)
		)
		(pad "20" thru_hole circle
			(at 0 48.26 270)
			(size 1.6256 1.6256)
			(drill 1.1176)
			(layers "*.Cu" "*.Mask")
			(remove_unused_layers no)
			(net "GND")
			(clearance 0)
		)
		(pad "21" thru_hole circle
			(at 0 50.8 270)
			(size 1.6256 1.6256)
			(drill 1.1176)
			(layers "*.Cu" "*.Mask")
			(remove_unused_layers no)
			(net "GND")
			(clearance 0)
		)
		(pad "22" thru_hole circle
			(at 0 53.34 270)
			(size 1.6256 1.6256)
			(drill 1.1176)
			(layers "*.Cu" "*.Mask")
			(remove_unused_layers no)
			(net "GND")
			(clearance 0)
		)
		(pad "23" thru_hole circle
			(at 0 55.88 270)
			(size 1.6256 1.6256)
			(drill 1.1176)
			(layers "*.Cu" "*.Mask")
			(remove_unused_layers no)
			(net "GND")
			(clearance 0)
		)
		(pad "24" thru_hole circle
			(at 0 58.42 270)
			(size 1.6256 1.6256)
			(drill 1.1176)
			(layers "*.Cu" "*.Mask")
			(remove_unused_layers no)
			(net "GND")
			(clearance 0)
		)
		(pad "25" thru_hole circle
			(at 0 60.96 270)
			(size 1.6256 1.6256)
			(drill 1.1176)
			(layers "*.Cu" "*.Mask")
			(remove_unused_layers no)
			(net "Net_401")
			(clearance 0)
		)
		(pad "26" thru_hole circle
			(at 0 63.5 270)
			(size 1.6256 1.6256)
			(drill 1.1176)
			(layers "*.Cu" "*.Mask")
			(remove_unused_layers no)
			(net "PSU4_REMOTE_N")
			(clearance 0)
		)
		(pad "27" thru_hole circle
			(at 0 66.04 270)
			(size 1.6256 1.6256)
			(drill 1.1176)
			(layers "*.Cu" "*.Mask")
			(remove_unused_layers no)
			(net "PSU4_AC_OK")
			(clearance 0)
		)
		(pad "28" thru_hole circle
			(at 0 68.58 270)
			(size 1.6256 1.6256)
			(drill 1.1176)
			(layers "*.Cu" "*.Mask")
			(remove_unused_layers no)
			(net "PSU4_CSAHRE")
			(clearance 0)
		)
		(pad "29" thru_hole circle
			(at 0 71.12 270)
			(size 1.6256 1.6256)
			(drill 1.1176)
			(layers "*.Cu" "*.Mask")
			(remove_unused_layers no)
			(net "PSU4_PS_ON_N")
			(clearance 0)
		)
		(pad "30" thru_hole circle
			(at 0 73.66 270)
			(size 1.6256 1.6256)
			(drill 1.1176)
			(layers "*.Cu" "*.Mask")
			(remove_unused_layers no)
			(net "PSU4_PS_KILL")
			(clearance 0)
		)
		(pad "31" thru_hole circle
			(at 0 76.2 270)
			(size 1.6256 1.6256)
			(drill 1.1176)
			(layers "*.Cu" "*.Mask")
			(remove_unused_layers no)
			(net "PSU4_RESET")
			(clearance 0)
		)
		(pad "32" thru_hole circle
			(at 0 78.74 270)
			(size 1.6256 1.6256)
			(drill 1.1176)
			(layers "*.Cu" "*.Mask")
			(remove_unused_layers no)
			(net "PSU_ALERT_N")
			(clearance 0)
		)
		(pad "33" thru_hole circle
			(at 5.08 78.74 270)
			(size 1.6256 1.6256)
			(drill 1.1176)
			(layers "*.Cu" "*.Mask")
			(remove_unused_layers no)
			(net "I2C_PSU2_SDA")
			(clearance 0)
		)
		(pad "34" thru_hole circle
			(at 5.08 76.2 270)
			(size 1.6256 1.6256)
			(drill 1.1176)
			(layers "*.Cu" "*.Mask")
			(remove_unused_layers no)
			(net "Net_402")
			(clearance 0)
		)
		(pad "35" thru_hole circle
			(at 5.08 73.66 270)
			(size 1.6256 1.6256)
			(drill 1.1176)
			(layers "*.Cu" "*.Mask")
			(remove_unused_layers no)
			(net "I2C_PSU2_SCL")
			(clearance 0)
		)
		(pad "36" thru_hole circle
			(at 5.08 71.12 270)
			(size 1.6256 1.6256)
			(drill 1.1176)
			(layers "*.Cu" "*.Mask")
			(remove_unused_layers no)
			(net "PSU4_RETURN")
			(clearance 0)
		)
		(pad "37" thru_hole circle
			(at 5.08 68.58 270)
			(size 1.6256 1.6256)
			(drill 1.1176)
			(layers "*.Cu" "*.Mask")
			(remove_unused_layers no)
			(net "PSU4_DC_OK")
			(clearance 0)
		)
		(pad "38" thru_hole circle
			(at 5.08 66.04 270)
			(size 1.6256 1.6256)
			(drill 1.1176)
			(layers "*.Cu" "*.Mask")
			(remove_unused_layers no)
			(net "PSU4_AD0")
			(clearance 0)
		)
		(pad "39" thru_hole circle
			(at 5.08 63.5 270)
			(size 1.6256 1.6256)
			(drill 1.1176)
			(layers "*.Cu" "*.Mask")
			(remove_unused_layers no)
			(net "P12V_STBY")
			(clearance 0)
		)
		(pad "40" thru_hole circle
			(at 5.08 60.96 270)
			(size 1.6256 1.6256)
			(drill 1.1176)
			(layers "*.Cu" "*.Mask")
			(remove_unused_layers no)
			(net "PSU4_REMOTE_P")
			(clearance 0)
		)
		(pad "41" thru_hole circle
			(at 5.08 58.42 270)
			(size 1.6256 1.6256)
			(drill 1.1176)
			(layers "*.Cu" "*.Mask")
			(remove_unused_layers no)
			(net "GND")
			(clearance 0)
		)
		(pad "42" thru_hole circle
			(at 5.08 55.88 270)
			(size 1.6256 1.6256)
			(drill 1.1176)
			(layers "*.Cu" "*.Mask")
			(remove_unused_layers no)
			(net "GND")
			(clearance 0)
		)
		(pad "43" thru_hole circle
			(at 5.08 53.34 270)
			(size 1.6256 1.6256)
			(drill 1.1176)
			(layers "*.Cu" "*.Mask")
			(remove_unused_layers no)
			(net "GND")
			(clearance 0)
		)
		(pad "44" thru_hole circle
			(at 5.08 50.8 270)
			(size 1.6256 1.6256)
			(drill 1.1176)
			(layers "*.Cu" "*.Mask")
			(remove_unused_layers no)
			(net "GND")
			(clearance 0)
		)
		(pad "45" thru_hole circle
			(at 5.08 48.26 270)
			(size 1.6256 1.6256)
			(drill 1.1176)
			(layers "*.Cu" "*.Mask")
			(remove_unused_layers no)
			(net "GND")
			(clearance 0)
		)
		(pad "46" thru_hole circle
			(at 5.08 45.72 270)
			(size 1.6256 1.6256)
			(drill 1.1176)
			(layers "*.Cu" "*.Mask")
			(remove_unused_layers no)
			(net "GND")
			(clearance 0)
		)
		(pad "47" thru_hole circle
			(at 5.08 43.18 270)
			(size 1.6256 1.6256)
			(drill 1.1176)
			(layers "*.Cu" "*.Mask")
			(remove_unused_layers no)
			(net "GND")
			(clearance 0)
		)
		(pad "48" thru_hole circle
			(at 5.08 40.64 270)
			(size 1.6256 1.6256)
			(drill 1.1176)
			(layers "*.Cu" "*.Mask")
			(remove_unused_layers no)
			(net "GND")
			(clearance 0)
		)
		(pad "49" thru_hole circle
			(at 5.08 38.1 270)
			(size 1.6256 1.6256)
			(drill 1.1176)
			(layers "*.Cu" "*.Mask")
			(remove_unused_layers no)
			(net "GND")
			(clearance 0)
		)
		(pad "50" thru_hole circle
			(at 5.08 35.56 270)
			(size 1.6256 1.6256)
			(drill 1.1176)
			(layers "*.Cu" "*.Mask")
			(remove_unused_layers no)
			(net "GND")
			(clearance 0)
		)
		(pad "51" thru_hole circle
			(at 5.08 33.02 270)
			(size 1.6256 1.6256)
			(drill 1.1176)
			(layers "*.Cu" "*.Mask")
			(remove_unused_layers no)
			(net "GND")
			(clearance 0)
		)
		(pad "52" thru_hole circle
			(at 5.08 30.48 270)
			(size 1.6256 1.6256)
			(drill 1.1176)
			(layers "*.Cu" "*.Mask")
			(remove_unused_layers no)
			(net "GND")
			(clearance 0)
		)
		(pad "53" thru_hole circle
			(at 5.08 27.94 270)
			(size 1.6256 1.6256)
			(drill 1.1176)
			(layers "*.Cu" "*.Mask")
			(remove_unused_layers no)
			(net "P12V")
			(clearance 0)
		)
		(pad "54" thru_hole circle
			(at 5.08 25.4 270)
			(size 1.6256 1.6256)
			(drill 1.1176)
			(layers "*.Cu" "*.Mask")
			(remove_unused_layers no)
			(net "P12V")
			(clearance 0)
		)
		(pad "55" thru_hole circle
			(at 5.08 22.86 270)
			(size 1.6256 1.6256)
			(drill 1.1176)
			(layers "*.Cu" "*.Mask")
			(remove_unused_layers no)
			(net "P12V")
			(clearance 0)
		)
		(pad "56" thru_hole circle
			(at 5.08 20.32 270)
			(size 1.6256 1.6256)
			(drill 1.1176)
			(layers "*.Cu" "*.Mask")
			(remove_unused_layers no)
			(net "P12V")
			(clearance 0)
		)
		(pad "57" thru_hole circle
			(at 5.08 17.78 270)
			(size 1.6256 1.6256)
			(drill 1.1176)
			(layers "*.Cu" "*.Mask")
			(remove_unused_layers no)
			(net "P12V")
			(clearance 0)
		)
		(pad "58" thru_hole circle
			(at 5.08 15.24 270)
			(size 1.6256 1.6256)
			(drill 1.1176)
			(layers "*.Cu" "*.Mask")
			(remove_unused_layers no)
			(net "P12V")
			(clearance 0)
		)
		(pad "59" thru_hole circle
			(at 5.08 12.7 270)
			(size 1.6256 1.6256)
			(drill 1.1176)
			(layers "*.Cu" "*.Mask")
			(remove_unused_layers no)
			(net "P12V")
			(clearance 0)
		)
		(pad "60" thru_hole circle
			(at 5.08 10.16 270)
			(size 1.6256 1.6256)
			(drill 1.1176)
			(layers "*.Cu" "*.Mask")
			(remove_unused_layers no)
			(net "P12V")
			(clearance 0)
		)
		(pad "61" thru_hole circle
			(at 5.08 7.62 270)
			(size 1.6256 1.6256)
			(drill 1.1176)
			(layers "*.Cu" "*.Mask")
			(remove_unused_layers no)
			(net "P12V")
			(clearance 0)
		)
		(pad "62" thru_hole circle
			(at 5.08 5.08 270)
			(size 1.6256 1.6256)
			(drill 1.1176)
			(layers "*.Cu" "*.Mask")
			(remove_unused_layers no)
			(net "P12V")
			(clearance 0)
		)
		(pad "63" thru_hole circle
			(at 5.08 2.54 270)
			(size 1.6256 1.6256)
			(drill 1.1176)
			(layers "*.Cu" "*.Mask")
			(remove_unused_layers no)
			(net "P12V")
			(clearance 0)
		)
		(pad "64" thru_hole circle
			(at 5.08 0 270)
			(size 1.6256 1.6256)
			(drill 1.1176)
			(layers "*.Cu" "*.Mask")
			(remove_unused_layers no)
			(net "P12V")
			(clearance 0)
		)
	)
	(footprint ""
		(layer "F.Cu")
		(at 13.39469 -61.927994 180)
		(property "Reference" "J23"
			(at 4.71551 13.578078 0)
			(unlocked yes)
			(layer "F.SilkS")
			(effects
				(font
					(size 0.7874 0.5842)
					(thickness 0.1524)
				)
				(justify left)
			)
		)
		(property "Value" ""
			(at 0 0 180)
			(layer "F.Fab")
			(effects
				(font
					(size 1.27 1.27)
				)
			)
		)
		(duplicate_pad_numbers_are_jumpers no)
		(fp_line
			(start 12.260072 12.830048)
			(end -3.370072 12.830048)
			(stroke
				(width 0.1524)
				(type default)
			)
			(layer "F.SilkS")
		)
		(fp_line
			(start 12.260072 -3.81)
			(end 12.260072 12.830048)
			(stroke
				(width 0.1524)
				(type default)
			)
			(layer "F.SilkS")
		)
		(fp_line
			(start -3.370072 12.830048)
			(end -3.370072 -3.81)
			(stroke
				(width 0.1524)
				(type default)
			)
			(layer "F.SilkS")
		)
		(fp_line
			(start -3.370072 -3.81)
			(end 12.260072 -3.81)
			(stroke
				(width 0.1524)
				(type default)
			)
			(layer "F.SilkS")
		)
		(fp_poly
			(pts
				(xy -3.560064 -0.233934) (xy -4.459224 0.215646) (xy -4.459224 -0.683514)
			)
			(stroke
				(width 0)
				(type default)
			)
			(fill yes)
			(layer "F.SilkS")
		)
		(fp_poly
			(pts
				(xy -0.762 0.762) (xy 8.382 0.762) (xy 8.382 -1.8034) (xy 9.652 -1.8034) (xy 9.652 -3.302) (xy 0.508 -3.302)
				(xy 0.508 -0.762) (xy -0.762 -0.762)
			)
			(stroke
				(width 0)
				(type default)
			)
			(fill no)
			(layer "B.CrtYd")
		)
		(fp_poly
			(pts
				(arc
					(start 8.2296 6.35)
					(mid 12.0904 6.35)
					(end 8.2296 6.35)
				)
			)
			(stroke
				(width 0)
				(type default)
			)
			(fill no)
			(layer "B.CrtYd")
		)
		(fp_poly
			(pts
				(arc
					(start -3.2004 6.35)
					(mid 0.6604 6.35)
					(end -3.2004 6.35)
				)
			)
			(stroke
				(width 0)
				(type default)
			)
			(fill no)
			(layer "B.CrtYd")
		)
		(fp_poly
			(pts
				(xy -3.370072 12.830048) (xy 12.260072 12.830048) (xy 12.260072 -3.81) (xy -3.370072 -3.81)
			)
			(stroke
				(width 0)
				(type default)
			)
			(fill no)
			(layer "F.CrtYd")
		)
		(fp_line
			(start 12.260072 12.830048)
			(end -3.370072 12.830048)
			(stroke
				(width 0.1)
				(type default)
			)
			(layer "F.Fab")
		)
		(fp_line
			(start 12.260072 -3.81)
			(end 12.260072 12.830048)
			(stroke
				(width 0.1)
				(type default)
			)
			(layer "F.Fab")
		)
		(fp_line
			(start -3.370072 12.830048)
			(end -3.370072 -3.81)
			(stroke
				(width 0.1)
				(type default)
			)
			(layer "F.Fab")
		)
		(fp_line
			(start -3.370072 -3.81)
			(end 12.260072 -3.81)
			(stroke
				(width 0.1)
				(type default)
			)
			(layer "F.Fab")
		)
		(fp_poly
			(pts
				(xy -3.576828 0) (xy -5.0038 0.713486) (xy -5.0038 -0.713486)
			)
			(stroke
				(width 0)
				(type default)
			)
			(fill yes)
			(layer "F.Fab")
		)
		(fp_text user "7"
			(at 12.709398 0.115316 0)
			(unlocked yes)
			(layer "F.SilkS")
			(effects
				(font
					(size 0.7874 0.5842)
					(thickness 0.1524)
				)
			)
		)
		(fp_text user "8"
			(at 12.709398 -2.348484 0)
			(unlocked yes)
			(layer "F.SilkS")
			(effects
				(font
					(size 0.7874 0.5842)
					(thickness 0.1524)
				)
			)
		)
		(fp_text user "1"
			(at -3.878072 1.046734 0)
			(unlocked yes)
			(layer "F.SilkS")
			(effects
				(font
					(size 0.7874 0.5842)
					(thickness 0.1524)
				)
			)
		)
		(fp_text user "2"
			(at -3.944874 -2.361946 0)
			(unlocked yes)
			(layer "F.SilkS")
			(effects
				(font
					(size 0.7874 0.5842)
					(thickness 0.1524)
				)
			)
		)
		(fp_text user "8"
			(at 10.250932 -2.563622 0)
			(unlocked yes)
			(layer "B.SilkS")
			(effects
				(font
					(size 0.7874 0.5842)
					(thickness 0.1524)
				)
				(justify mirror)
			)
		)
		(fp_text user "7"
			(at 8.980932 0.077978 0)
			(unlocked yes)
			(layer "B.SilkS")
			(effects
				(font
					(size 0.7874 0.5842)
					(thickness 0.1524)
				)
				(justify mirror)
			)
		)
		(fp_text user "2"
			(at 0.167132 -2.741422 0)
			(unlocked yes)
			(layer "B.SilkS")
			(effects
				(font
					(size 0.7874 0.5842)
					(thickness 0.1524)
				)
				(justify mirror)
			)
		)
		(fp_text user "1"
			(at -1.128268 -0.074422 0)
			(unlocked yes)
			(layer "B.SilkS")
			(effects
				(font
					(size 0.7874 0.5842)
					(thickness 0.1524)
				)
				(justify mirror)
			)
		)
		(fp_text user "8"
			(at 10.0838 -2.403348 180)
			(unlocked yes)
			(layer "B.Fab")
			(effects
				(font
					(size 0.7874 0.5842)
					(thickness 0.000001)
				)
				(justify mirror)
			)
		)
		(fp_text user "7"
			(at 8.8138 0.238252 180)
			(unlocked yes)
			(layer "B.Fab")
			(effects
				(font
					(size 0.7874 0.5842)
					(thickness 0.000001)
				)
				(justify mirror)
			)
		)
		(fp_text user "2"
			(at 0 -2.581148 180)
			(unlocked yes)
			(layer "B.Fab")
			(effects
				(font
					(size 0.7874 0.5842)
					(thickness 0.000001)
				)
				(justify mirror)
			)
		)
		(fp_text user "1"
			(at -1.2954 0.085852 180)
			(unlocked yes)
			(layer "B.Fab")
			(effects
				(font
					(size 0.7874 0.5842)
					(thickness 0.000001)
				)
				(justify mirror)
			)
		)
		(fp_text user "7"
			(at 12.7762 -0.091948 180)
			(unlocked yes)
			(layer "F.Fab")
			(effects
				(font
					(size 0.7874 0.5842)
					(thickness 0.000001)
				)
			)
		)
		(fp_text user "8"
			(at 12.7762 -2.555748 180)
			(unlocked yes)
			(layer "F.Fab")
			(effects
				(font
					(size 0.7874 0.5842)
					(thickness 0.000001)
				)
			)
		)
		(fp_text user "1"
			(at -3.9116 -0.930148 180)
			(unlocked yes)
			(layer "F.Fab")
			(effects
				(font
					(size 0.7874 0.5842)
					(thickness 0.000001)
				)
			)
		)
		(fp_text user "2"
			(at -3.9624 -2.428748 180)
			(unlocked yes)
			(layer "F.Fab")
			(effects
				(font
					(size 0.7874 0.5842)
					(thickness 0.000001)
				)
			)
		)
		(pad "" np_thru_hole circle
			(at -1.27 6.35 180)
			(size 3.3528 3.3528)
			(drill 3.3528)
			(layers "*.Cu" "*.Mask")
			(clearance 0.381)
			(thermal_gap 0.381)
		)
		(pad "" np_thru_hole circle
			(at 10.16 6.35 180)
			(size 3.3528 3.3528)
			(drill 3.3528)
			(layers "*.Cu" "*.Mask")
			(clearance 0.381)
			(thermal_gap 0.381)
		)
		(pad "1" thru_hole rect
			(at 0 0 180)
			(size 1.397 1.397)
			(drill 0.9906)
			(layers "*.Cu" "*.Mask")
			(remove_unused_layers no)
			(net "UART_RTS_P5_L_N")
			(clearance 0.0508)
			(thermal_gap 0.0508)
			(padstack
				(mode front_inner_back)
				(layer "Inner"
					(shape circle)
					(size 1.397 1.397)
					(clearance 0.0508)
				)
				(layer "B.Cu"
					(shape rect)
					(size 1.397 1.397)
					(clearance 0.0508)
				)
			)
		)
		(pad "2" thru_hole circle
			(at 1.27 -2.54 180)
			(size 1.397 1.397)
			(drill 0.9906)
			(layers "*.Cu" "*.Mask")
			(remove_unused_layers no)
			(net "UART_DSR_P5_L_N")
			(clearance 0.0508)
			(thermal_gap 0.0508)
		)
		(pad "3" thru_hole circle
			(at 2.54 0 180)
			(size 1.397 1.397)
			(drill 0.9906)
			(layers "*.Cu" "*.Mask")
			(remove_unused_layers no)
			(net "UART_RX_P5_L")
			(clearance 0.0508)
			(thermal_gap 0.0508)
		)
		(pad "4" thru_hole circle
			(at 3.81 -2.54 180)
			(size 1.397 1.397)
			(drill 0.9906)
			(layers "*.Cu" "*.Mask")
			(remove_unused_layers no)
			(net "UART_RI_P5_L_N")
			(clearance 0.0508)
			(thermal_gap 0.0508)
		)
		(pad "5" thru_hole circle
			(at 5.08 0 180)
			(size 1.397 1.397)
			(drill 0.9906)
			(layers "*.Cu" "*.Mask")
			(remove_unused_layers no)
			(net "GND")
			(clearance 0.0508)
			(thermal_gap 0.0508)
		)
		(pad "6" thru_hole circle
			(at 6.35 -2.54 180)
			(size 1.397 1.397)
			(drill 0.9906)
			(layers "*.Cu" "*.Mask")
			(remove_unused_layers no)
			(net "UART_TX_P5_L")
			(clearance 0.0508)
			(thermal_gap 0.0508)
		)
		(pad "7" thru_hole circle
			(at 7.62 0 180)
			(size 1.397 1.397)
			(drill 0.9906)
			(layers "*.Cu" "*.Mask")
			(remove_unused_layers no)
			(net "UART_DTR_P5_L_N")
			(clearance 0.0508)
			(thermal_gap 0.0508)
		)
		(pad "8" thru_hole circle
			(at 8.89 -2.54 180)
			(size 1.397 1.397)
			(drill 0.9906)
			(layers "*.Cu" "*.Mask")
			(remove_unused_layers no)
			(net "UART_CTS_P5_L_N")
			(clearance 0.0508)
			(thermal_gap 0.0508)
		)
		(zone
			(layers "F.Cu" "B.Cu" "In1.Cu" "In2.Cu" "In3.Cu" "In4.Cu" "In5.Cu" "In6.Cu")
			(hatch none 0.5)
			(connect_pads
				(clearance 0)
			)
			(min_thickness 0.25)
			(keepout
				(tracks not_allowed)
				(vias allowed)
				(pads allowed)
				(copperpour not_allowed)
				(footprints allowed)
			)
			(placement
				(enabled no)
				(sheetname "")
			)
			(fill
				(thermal_gap 0.5)
				(thermal_bridge_width 0.5)
				(island_removal_mode 0)
			)
			(polygon
				(pts
					(arc
						(start 5.31749 -68.277994)
						(mid 1.15189 -68.277994)
						(end 5.31749 -68.277994)
					)
				)
			)
		)
		(zone
			(layers "F.Cu" "B.Cu" "In1.Cu" "In2.Cu" "In3.Cu" "In4.Cu" "In5.Cu" "In6.Cu")
			(hatch none 0.5)
			(connect_pads
				(clearance 0)
			)
			(min_thickness 0.25)
			(keepout
				(tracks not_allowed)
				(vias allowed)
				(pads allowed)
				(copperpour not_allowed)
				(footprints allowed)
			)
			(placement
				(enabled no)
				(sheetname "")
			)
			(fill
				(thermal_gap 0.5)
				(thermal_bridge_width 0.5)
				(island_removal_mode 0)
			)
			(polygon
				(pts
					(arc
						(start 16.74749 -68.277994)
						(mid 12.58189 -68.277994)
						(end 16.74749 -68.277994)
					)
				)
			)
		)
	)
	(footprint ""
		(layer "F.Cu")
		(at 26.102056 -273.532854)
		(property "Reference" "R76"
			(at -4.037838 -0.005334 0)
			(unlocked yes)
			(layer "F.SilkS")
			(effects
				(font
					(size 0.7874 0.5842)
					(thickness 0.1524)
				)
				(justify left)
			)
		)
		(property "Value" ""
			(at 0 0 0)
			(layer "F.Fab")
			(effects
				(font
					(size 1.27 1.27)
				)
			)
		)
		(duplicate_pad_numbers_are_jumpers no)
		(fp_line
			(start -0.7874 -0.4064)
			(end 0.7874 -0.4064)
			(stroke
				(width 0.1524)
				(type default)
			)
			(layer "F.SilkS")
		)
		(fp_line
			(start -0.7874 0.4064)
			(end -0.7874 -0.4064)
			(stroke
				(width 0.1524)
				(type default)
			)
			(layer "F.SilkS")
		)
		(fp_line
			(start 0.7874 -0.4064)
			(end 0.7874 0.4064)
			(stroke
				(width 0.1524)
				(type default)
			)
			(layer "F.SilkS")
		)
		(fp_line
			(start 0.7874 0.4064)
			(end -0.7874 0.4064)
			(stroke
				(width 0.1524)
				(type default)
			)
			(layer "F.SilkS")
		)
		(fp_poly
			(pts
				(xy -0.508 0.2794) (xy -0.508 0.2286) (xy -0.635 0.2286) (xy -0.635 -0.254) (xy -0.5334 -0.254)
				(xy -0.5334 -0.2794) (xy 0.5334 -0.2794) (xy 0.5334 -0.254) (xy 0.635 -0.254) (xy 0.635 0.254) (xy 0.5334 0.254)
				(xy 0.5334 0.2794)
			)
			(stroke
				(width 0)
				(type default)
			)
			(fill no)
			(layer "F.CrtYd")
		)
		(pad "1" smd rect
			(at 0.40005 0)
			(size 0.4572 0.508)
			(layers "F.Cu" "F.Mask" "F.Paste")
			(net "PSU4_RESET")
		)
		(pad "2" smd rect
			(at -0.40005 0)
			(size 0.4572 0.508)
			(layers "F.Cu" "F.Mask" "F.Paste")
			(net "P12V_STBY")
		)
	)
	(footprint ""
		(layer "F.Cu")
		(at 80.662018 -14.939772 -90)
		(property "Reference" "C6"
			(at -1.75133 0.018796 90)
			(unlocked yes)
			(layer "F.SilkS")
			(effects
				(font
					(size 0.7874 0.5842)
					(thickness 0.1524)
				)
				(justify left)
			)
		)
		(property "Value" ""
			(at 0 0 270)
			(layer "F.Fab")
			(effects
				(font
					(size 1.27 1.27)
				)
			)
		)
		(duplicate_pad_numbers_are_jumpers no)
		(fp_line
			(start -0.7874 0.4064)
			(end -0.7874 -0.4064)
			(stroke
				(width 0.1524)
				(type default)
			)
			(layer "F.SilkS")
		)
		(fp_line
			(start 0.7874 0.4064)
			(end -0.7874 0.4064)
			(stroke
				(width 0.1524)
				(type default)
			)
			(layer "F.SilkS")
		)
		(fp_line
			(start 0 0.381)
			(end 0 -0.381)
			(stroke
				(width 0.1524)
				(type default)
			)
			(layer "F.SilkS")
		)
		(fp_line
			(start -0.7874 -0.4064)
			(end 0.7874 -0.4064)
			(stroke
				(width 0.1524)
				(type default)
			)
			(layer "F.SilkS")
		)
		(fp_line
			(start 0.7874 -0.4064)
			(end 0.7874 0.4064)
			(stroke
				(width 0.1524)
				(type default)
			)
			(layer "F.SilkS")
		)
		(fp_poly
			(pts
				(xy -0.5334 0.254) (xy -0.635 0.254) (xy -0.635 0.2286) (xy -0.635 -0.254) (xy -0.5334 -0.254) (xy -0.5334 -0.2794)
				(xy 0.5334 -0.2794) (xy 0.5334 -0.254) (xy 0.635 -0.254) (xy 0.635 0.254) (xy 0.5334 0.254) (xy 0.5334 0.2794)
				(xy -0.508 0.2794) (xy -0.5334 0.2794)
			)
			(stroke
				(width 0)
				(type default)
			)
			(fill no)
			(layer "F.CrtYd")
		)
		(pad "1" smd rect
			(at 0.40005 0 270)
			(size 0.4572 0.508)
			(layers "F.Cu" "F.Mask" "F.Paste")
			(net "P12V")
		)
		(pad "2" smd rect
			(at -0.40005 0 270)
			(size 0.4572 0.508)
			(layers "F.Cu" "F.Mask" "F.Paste")
			(net "GND")
		)
	)
	(footprint ""
		(layer "F.Cu")
		(at 82.499962 -504.305824 -90)
		(property "Reference" "C80"
			(at -2.739136 0.096774 90)
			(unlocked yes)
			(layer "F.SilkS")
			(effects
				(font
					(size 0.7874 0.5842)
					(thickness 0.1524)
				)
				(justify left)
			)
		)
		(property "Value" ""
			(at 0 0 270)
			(layer "F.Fab")
			(effects
				(font
					(size 1.27 1.27)
				)
			)
		)
		(duplicate_pad_numbers_are_jumpers no)
		(fp_line
			(start -0.7874 0.4064)
			(end -0.7874 -0.4064)
			(stroke
				(width 0.1524)
				(type default)
			)
			(layer "F.SilkS")
		)
		(fp_line
			(start 0.7874 0.4064)
			(end -0.7874 0.4064)
			(stroke
				(width 0.1524)
				(type default)
			)
			(layer "F.SilkS")
		)
		(fp_line
			(start 0 0.381)
			(end 0 -0.381)
			(stroke
				(width 0.1524)
				(type default)
			)
			(layer "F.SilkS")
		)
		(fp_line
			(start -0.7874 -0.4064)
			(end 0.7874 -0.4064)
			(stroke
				(width 0.1524)
				(type default)
			)
			(layer "F.SilkS")
		)
		(fp_line
			(start 0.7874 -0.4064)
			(end 0.7874 0.4064)
			(stroke
				(width 0.1524)
				(type default)
			)
			(layer "F.SilkS")
		)
		(fp_poly
			(pts
				(xy -0.5334 0.254) (xy -0.635 0.254) (xy -0.635 0.2286) (xy -0.635 -0.254) (xy -0.5334 -0.254) (xy -0.5334 -0.2794)
				(xy 0.5334 -0.2794) (xy 0.5334 -0.254) (xy 0.635 -0.254) (xy 0.635 0.254) (xy 0.5334 0.254) (xy 0.5334 0.2794)
				(xy -0.508 0.2794) (xy -0.5334 0.2794)
			)
			(stroke
				(width 0)
				(type default)
			)
			(fill no)
			(layer "F.CrtYd")
		)
		(pad "1" smd rect
			(at 0.40005 0 270)
			(size 0.4572 0.508)
			(layers "F.Cu" "F.Mask" "F.Paste")
			(net "P12V")
		)
		(pad "2" smd rect
			(at -0.40005 0 270)
			(size 0.4572 0.508)
			(layers "F.Cu" "F.Mask" "F.Paste")
			(net "GND")
		)
	)
	(footprint ""
		(layer "F.Cu")
		(at 25.857708 -361.78236)
		(property "Reference" "R81"
			(at -3.917442 -0.225298 0)
			(unlocked yes)
			(layer "F.SilkS")
			(effects
				(font
					(size 0.7874 0.5842)
					(thickness 0.1524)
				)
				(justify left)
			)
		)
		(property "Value" ""
			(at 0 0 0)
			(layer "F.Fab")
			(effects
				(font
					(size 1.27 1.27)
				)
			)
		)
		(duplicate_pad_numbers_are_jumpers no)
		(fp_line
			(start -0.7874 -0.4064)
			(end 0.7874 -0.4064)
			(stroke
				(width 0.1524)
				(type default)
			)
			(layer "F.SilkS")
		)
		(fp_line
			(start -0.7874 0.4064)
			(end -0.7874 -0.4064)
			(stroke
				(width 0.1524)
				(type default)
			)
			(layer "F.SilkS")
		)
		(fp_line
			(start 0.7874 -0.4064)
			(end 0.7874 0.4064)
			(stroke
				(width 0.1524)
				(type default)
			)
			(layer "F.SilkS")
		)
		(fp_line
			(start 0.7874 0.4064)
			(end -0.7874 0.4064)
			(stroke
				(width 0.1524)
				(type default)
			)
			(layer "F.SilkS")
		)
		(fp_poly
			(pts
				(xy -0.508 0.2794) (xy -0.508 0.2286) (xy -0.635 0.2286) (xy -0.635 -0.254) (xy -0.5334 -0.254)
				(xy -0.5334 -0.2794) (xy 0.5334 -0.2794) (xy 0.5334 -0.254) (xy 0.635 -0.254) (xy 0.635 0.254) (xy 0.5334 0.254)
				(xy 0.5334 0.2794)
			)
			(stroke
				(width 0)
				(type default)
			)
			(fill no)
			(layer "F.CrtYd")
		)
		(pad "1" smd rect
			(at 0.40005 0)
			(size 0.4572 0.508)
			(layers "F.Cu" "F.Mask" "F.Paste")
			(net "PSU5_RESET")
		)
		(pad "2" smd rect
			(at -0.40005 0)
			(size 0.4572 0.508)
			(layers "F.Cu" "F.Mask" "F.Paste")
			(net "GND")
		)
	)
	(footprint ""
		(layer "F.Cu")
		(at 91.399868 -242.26012)
		(property "Reference" "H18"
			(at -5.1308 -5.23113 0)
			(unlocked yes)
			(layer "F.SilkS")
			(effects
				(font
					(size 0.7874 0.5842)
					(thickness 0.1524)
				)
				(justify left)
			)
		)
		(property "Value" ""
			(at 0 0 0)
			(layer "F.Fab")
			(effects
				(font
					(size 1.27 1.27)
				)
			)
		)
		(duplicate_pad_numbers_are_jumpers no)
		(fp_circle
			(center 0 0)
			(end 4.826 0)
			(stroke
				(width 0.1524)
				(type default)
			)
			(fill no)
			(layer "F.SilkS")
		)
		(fp_circle
			(center 0 0)
			(end 4.826 0)
			(stroke
				(width 0.1524)
				(type default)
			)
			(fill no)
			(layer "B.SilkS")
		)
		(fp_poly
			(pts
				(arc
					(start 0 4.0132)
					(mid 0 -4.0132)
					(end 0 4.0132)
				)
			)
			(stroke
				(width 0)
				(type default)
			)
			(fill no)
			(layer "F.CrtYd")
		)
		(pad "" np_thru_hole circle
			(at 0 0)
			(size 8.001 8.001)
			(drill 8.001)
			(layers "*.Cu" "*.Mask")
			(clearance 0.381)
			(thermal_gap 0.381)
		)
		(zone
			(layers "F.Cu" "B.Cu" "In1.Cu" "In2.Cu" "In3.Cu" "In4.Cu" "In5.Cu" "In6.Cu")
			(hatch none 0.5)
			(connect_pads
				(clearance 0)
			)
			(min_thickness 0.25)
			(keepout
				(tracks not_allowed)
				(vias allowed)
				(pads allowed)
				(copperpour not_allowed)
				(footprints allowed)
			)
			(placement
				(enabled no)
				(sheetname "")
			)
			(fill
				(thermal_gap 0.5)
				(thermal_bridge_width 0.5)
				(island_removal_mode 0)
			)
			(polygon
				(pts
					(arc
						(start 91.399868 -237.73892)
						(mid 91.399868 -246.78132)
						(end 91.399868 -237.73892)
					)
				)
			)
		)
	)
	(footprint ""
		(layer "F.Cu")
		(at 78.000098 -519.049762)
		(property "Reference" "H1"
			(at -5.872734 -7.468108 0)
			(unlocked yes)
			(layer "F.SilkS")
			(effects
				(font
					(size 0.7874 0.5842)
					(thickness 0.1524)
				)
				(justify left)
			)
		)
		(property "Value" ""
			(at 0 0 0)
			(layer "F.Fab")
			(effects
				(font
					(size 1.27 1.27)
				)
			)
		)
		(duplicate_pad_numbers_are_jumpers no)
		(fp_circle
			(center 0 0)
			(end 7.999984 0)
			(stroke
				(width 0.1524)
				(type default)
			)
			(fill no)
			(layer "F.SilkS")
		)
		(fp_circle
			(center 0 0)
			(end 14.7066 0)
			(stroke
				(width 0.1524)
				(type default)
			)
			(fill no)
			(layer "B.SilkS")
		)
		(fp_poly
			(pts
				(arc
					(start 5.0038 0)
					(mid -5.0038 0)
					(end 5.0038 0)
				)
			)
			(stroke
				(width 0)
				(type default)
			)
			(fill no)
			(layer "F.CrtYd")
		)
		(pad "" np_thru_hole circle
			(at 0 0)
			(size 4.0132 4.0132)
			(drill 4.0132)
			(layers "*.Cu" "*.Mask")
			(clearance 0.381)
			(thermal_gap 0.381)
		)
		(pad "2" thru_hole circle
			(at 0 -3.50012)
			(size 0.762 0.762)
			(drill 0.5588)
			(layers "*.Cu" "*.Mask")
			(remove_unused_layers no)
			(net "GND")
			(clearance 0.1524)
			(thermal_gap 0.1524)
		)
		(pad "3" thru_hole circle
			(at -2.500122 -2.500122)
			(size 0.762 0.762)
			(drill 0.5588)
			(layers "*.Cu" "*.Mask")
			(remove_unused_layers no)
			(net "GND")
			(clearance 0.1524)
			(thermal_gap 0.1524)
		)
		(pad "4" thru_hole circle
			(at -3.50012 0)
			(size 0.762 0.762)
			(drill 0.5588)
			(layers "*.Cu" "*.Mask")
			(remove_unused_layers no)
			(net "GND")
			(clearance 0.1524)
			(thermal_gap 0.1524)
		)
		(pad "5" thru_hole circle
			(at -2.500122 2.500122)
			(size 0.762 0.762)
			(drill 0.5588)
			(layers "*.Cu" "*.Mask")
			(remove_unused_layers no)
			(net "GND")
			(clearance 0.1524)
			(thermal_gap 0.1524)
		)
		(pad "6" thru_hole circle
			(at 0 3.50012)
			(size 0.762 0.762)
			(drill 0.5588)
			(layers "*.Cu" "*.Mask")
			(remove_unused_layers no)
			(net "GND")
			(clearance 0.1524)
			(thermal_gap 0.1524)
		)
		(pad "7" thru_hole circle
			(at 2.500122 2.500122)
			(size 0.762 0.762)
			(drill 0.5588)
			(layers "*.Cu" "*.Mask")
			(remove_unused_layers no)
			(net "GND")
			(clearance 0.1524)
			(thermal_gap 0.1524)
		)
		(pad "8" thru_hole circle
			(at 3.50012 0)
			(size 0.762 0.762)
			(drill 0.5588)
			(layers "*.Cu" "*.Mask")
			(remove_unused_layers no)
			(net "GND")
			(clearance 0.1524)
			(thermal_gap 0.1524)
		)
		(pad "9" thru_hole circle
			(at 2.500122 -2.500122)
			(size 0.762 0.762)
			(drill 0.5588)
			(layers "*.Cu" "*.Mask")
			(remove_unused_layers no)
			(net "GND")
			(clearance 0.1524)
			(thermal_gap 0.1524)
		)
		(zone
			(layer "F.Cu")
			(hatch none 0.5)
			(connect_pads
				(clearance 0)
			)
			(min_thickness 0.25)
			(keepout
				(tracks not_allowed)
				(vias allowed)
				(pads allowed)
				(copperpour not_allowed)
				(footprints allowed)
			)
			(placement
				(enabled no)
				(sheetname "")
			)
			(fill
				(thermal_gap 0.5)
				(thermal_bridge_width 0.5)
				(island_removal_mode 0)
			)
			(polygon
				(pts
					(arc
						(start 78.000098 -527.050762)
						(mid 69.999098 -519.049762)
						(end 78.000098 -511.048762)
					)
					(arc
						(start 78.000098 -511.048762)
						(mid 79.435198 -512.483862)
						(end 78.000098 -513.918962)
					)
					(arc
						(start 78.000098 -513.918962)
						(mid 72.869298 -519.049762)
						(end 78.000098 -524.180562)
					)
					(arc
						(start 78.000098 -524.180562)
						(mid 79.435198 -525.615662)
						(end 78.000098 -527.050762)
					)
				)
			)
		)
		(zone
			(layer "F.Cu")
			(hatch none 0.5)
			(connect_pads
				(clearance 0)
			)
			(min_thickness 0.25)
			(keepout
				(tracks not_allowed)
				(vias allowed)
				(pads allowed)
				(copperpour not_allowed)
				(footprints allowed)
			)
			(placement
				(enabled no)
				(sheetname "")
			)
			(fill
				(thermal_gap 0.5)
				(thermal_bridge_width 0.5)
				(island_removal_mode 0)
			)
			(polygon
				(pts
					(arc
						(start 78.000098 -527.050762)
						(mid 86.001098 -519.049762)
						(end 78.000098 -511.048762)
					)
					(arc
						(start 78.000098 -511.048762)
						(mid 76.564998 -512.483862)
						(end 78.000098 -513.918962)
					)
					(arc
						(start 78.000098 -513.918962)
						(mid 83.130898 -519.049762)
						(end 78.000098 -524.180562)
					)
					(arc
						(start 78.000098 -524.180562)
						(mid 76.564998 -525.615662)
						(end 78.000098 -527.050762)
					)
				)
			)
		)
		(zone
			(layers "F.Cu" "B.Cu" "In1.Cu" "In2.Cu" "In3.Cu" "In4.Cu" "In5.Cu" "In6.Cu")
			(hatch none 0.5)
			(connect_pads
				(clearance 0)
			)
			(min_thickness 0.25)
			(keepout
				(tracks not_allowed)
				(vias allowed)
				(pads allowed)
				(copperpour not_allowed)
				(footprints allowed)
			)
			(placement
				(enabled no)
				(sheetname "")
			)
			(fill
				(thermal_gap 0.5)
				(thermal_bridge_width 0.5)
				(island_removal_mode 0)
			)
			(polygon
				(pts
					(arc
						(start 80.512158 -519.049762)
						(mid 75.488038 -519.049762)
						(end 80.512158 -519.049762)
					)
				)
			)
		)
	)
	(footprint ""
		(layer "F.Cu")
		(at 72.284082 -442.84646 90)
		(property "Reference" "C75"
			(at -3.89128 0.132334 90)
			(unlocked yes)
			(layer "F.SilkS")
			(effects
				(font
					(size 0.7874 0.5842)
					(thickness 0.1524)
				)
				(justify left)
			)
		)
		(property "Value" ""
			(at 0 0 90)
			(layer "F.Fab")
			(effects
				(font
					(size 1.27 1.27)
				)
			)
		)
		(duplicate_pad_numbers_are_jumpers no)
		(fp_line
			(start 0.7874 -0.4064)
			(end 0.7874 0.4064)
			(stroke
				(width 0.1524)
				(type default)
			)
			(layer "F.SilkS")
		)
		(fp_line
			(start -0.7874 -0.4064)
			(end 0.7874 -0.4064)
			(stroke
				(width 0.1524)
				(type default)
			)
			(layer "F.SilkS")
		)
		(fp_line
			(start 0 0.381)
			(end 0 -0.381)
			(stroke
				(width 0.1524)
				(type default)
			)
			(layer "F.SilkS")
		)
		(fp_line
			(start 0.7874 0.4064)
			(end -0.7874 0.4064)
			(stroke
				(width 0.1524)
				(type default)
			)
			(layer "F.SilkS")
		)
		(fp_line
			(start -0.7874 0.4064)
			(end -0.7874 -0.4064)
			(stroke
				(width 0.1524)
				(type default)
			)
			(layer "F.SilkS")
		)
		(fp_poly
			(pts
				(xy -0.5334 0.254) (xy -0.635 0.254) (xy -0.635 0.2286) (xy -0.635 -0.254) (xy -0.5334 -0.254) (xy -0.5334 -0.2794)
				(xy 0.5334 -0.2794) (xy 0.5334 -0.254) (xy 0.635 -0.254) (xy 0.635 0.254) (xy 0.5334 0.254) (xy 0.5334 0.2794)
				(xy -0.508 0.2794) (xy -0.5334 0.2794)
			)
			(stroke
				(width 0)
				(type default)
			)
			(fill no)
			(layer "F.CrtYd")
		)
		(pad "1" smd rect
			(at 0.40005 0 90)
			(size 0.4572 0.508)
			(layers "F.Cu" "F.Mask" "F.Paste")
			(net "P12V")
		)
		(pad "2" smd rect
			(at -0.40005 0 90)
			(size 0.4572 0.508)
			(layers "F.Cu" "F.Mask" "F.Paste")
			(net "GND")
		)
	)
	(footprint ""
		(layer "F.Cu")
		(at 39.459154 -111.174022 -90)
		(property "Reference" "R90"
			(at -1.104392 -0.0254 90)
			(unlocked yes)
			(layer "F.SilkS")
			(effects
				(font
					(size 0.7874 0.5842)
					(thickness 0.1524)
				)
				(justify left)
			)
		)
		(property "Value" ""
			(at 0 0 270)
			(layer "F.Fab")
			(effects
				(font
					(size 1.27 1.27)
				)
			)
		)
		(duplicate_pad_numbers_are_jumpers no)
		(fp_line
			(start -0.7874 0.4064)
			(end -0.7874 -0.4064)
			(stroke
				(width 0.1524)
				(type default)
			)
			(layer "F.SilkS")
		)
		(fp_line
			(start 0.7874 0.4064)
			(end -0.7874 0.4064)
			(stroke
				(width 0.1524)
				(type default)
			)
			(layer "F.SilkS")
		)
		(fp_line
			(start -0.7874 -0.4064)
			(end 0.7874 -0.4064)
			(stroke
				(width 0.1524)
				(type default)
			)
			(layer "F.SilkS")
		)
		(fp_line
			(start 0.7874 -0.4064)
			(end 0.7874 0.4064)
			(stroke
				(width 0.1524)
				(type default)
			)
			(layer "F.SilkS")
		)
		(fp_poly
			(pts
				(xy -0.508 0.2794) (xy -0.508 0.2286) (xy -0.635 0.2286) (xy -0.635 -0.254) (xy -0.5334 -0.254)
				(xy -0.5334 -0.2794) (xy 0.5334 -0.2794) (xy 0.5334 -0.254) (xy 0.635 -0.254) (xy 0.635 0.254) (xy 0.5334 0.254)
				(xy 0.5334 0.2794)
			)
			(stroke
				(width 0)
				(type default)
			)
			(fill no)
			(layer "F.CrtYd")
		)
		(pad "1" smd rect
			(at 0.40005 0 270)
			(size 0.4572 0.508)
			(layers "F.Cu" "F.Mask" "F.Paste")
			(net "PSU2_REMOTE_P")
		)
		(pad "2" smd rect
			(at -0.40005 0 270)
			(size 0.4572 0.508)
			(layers "F.Cu" "F.Mask" "F.Paste")
			(net "PSU2_REMOTE_R_P")
		)
	)
	(footprint ""
		(layer "F.Cu")
		(at 72.928734 -487.29138 90)
		(property "Reference" "C81"
			(at -4.217416 0.323088 90)
			(unlocked yes)
			(layer "F.SilkS")
			(effects
				(font
					(size 0.7874 0.5842)
					(thickness 0.1524)
				)
				(justify left)
			)
		)
		(property "Value" ""
			(at 0 0 90)
			(layer "F.Fab")
			(effects
				(font
					(size 1.27 1.27)
				)
			)
		)
		(duplicate_pad_numbers_are_jumpers no)
		(fp_line
			(start 0.7874 -0.4064)
			(end 0.7874 0.4064)
			(stroke
				(width 0.1524)
				(type default)
			)
			(layer "F.SilkS")
		)
		(fp_line
			(start -0.7874 -0.4064)
			(end 0.7874 -0.4064)
			(stroke
				(width 0.1524)
				(type default)
			)
			(layer "F.SilkS")
		)
		(fp_line
			(start 0 0.381)
			(end 0 -0.381)
			(stroke
				(width 0.1524)
				(type default)
			)
			(layer "F.SilkS")
		)
		(fp_line
			(start 0.7874 0.4064)
			(end -0.7874 0.4064)
			(stroke
				(width 0.1524)
				(type default)
			)
			(layer "F.SilkS")
		)
		(fp_line
			(start -0.7874 0.4064)
			(end -0.7874 -0.4064)
			(stroke
				(width 0.1524)
				(type default)
			)
			(layer "F.SilkS")
		)
		(fp_poly
			(pts
				(xy -0.5334 0.254) (xy -0.635 0.254) (xy -0.635 0.2286) (xy -0.635 -0.254) (xy -0.5334 -0.254) (xy -0.5334 -0.2794)
				(xy 0.5334 -0.2794) (xy 0.5334 -0.254) (xy 0.635 -0.254) (xy 0.635 0.254) (xy 0.5334 0.254) (xy 0.5334 0.2794)
				(xy -0.508 0.2794) (xy -0.5334 0.2794)
			)
			(stroke
				(width 0)
				(type default)
			)
			(fill no)
			(layer "F.CrtYd")
		)
		(pad "1" smd rect
			(at 0.40005 0 90)
			(size 0.4572 0.508)
			(layers "F.Cu" "F.Mask" "F.Paste")
			(net "P12V")
		)
		(pad "2" smd rect
			(at -0.40005 0 90)
			(size 0.4572 0.508)
			(layers "F.Cu" "F.Mask" "F.Paste")
			(net "GND")
		)
	)
	(footprint ""
		(layer "F.Cu")
		(at 91.399868 -286.709866)
		(property "Reference" "H21"
			(at -5.1308 -5.23113 0)
			(unlocked yes)
			(layer "F.SilkS")
			(effects
				(font
					(size 0.7874 0.5842)
					(thickness 0.1524)
				)
				(justify left)
			)
		)
		(property "Value" ""
			(at 0 0 0)
			(layer "F.Fab")
			(effects
				(font
					(size 1.27 1.27)
				)
			)
		)
		(duplicate_pad_numbers_are_jumpers no)
		(fp_circle
			(center 0 0)
			(end 4.826 0)
			(stroke
				(width 0.1524)
				(type default)
			)
			(fill no)
			(layer "F.SilkS")
		)
		(fp_circle
			(center 0 0)
			(end 4.826 0)
			(stroke
				(width 0.1524)
				(type default)
			)
			(fill no)
			(layer "B.SilkS")
		)
		(fp_poly
			(pts
				(arc
					(start 0 4.0132)
					(mid 0 -4.0132)
					(end 0 4.0132)
				)
			)
			(stroke
				(width 0)
				(type default)
			)
			(fill no)
			(layer "F.CrtYd")
		)
		(pad "" np_thru_hole circle
			(at 0 0)
			(size 8.001 8.001)
			(drill 8.001)
			(layers "*.Cu" "*.Mask")
			(clearance 0.381)
			(thermal_gap 0.381)
		)
		(zone
			(layers "F.Cu" "B.Cu" "In1.Cu" "In2.Cu" "In3.Cu" "In4.Cu" "In5.Cu" "In6.Cu")
			(hatch none 0.5)
			(connect_pads
				(clearance 0)
			)
			(min_thickness 0.25)
			(keepout
				(tracks not_allowed)
				(vias allowed)
				(pads allowed)
				(copperpour not_allowed)
				(footprints allowed)
			)
			(placement
				(enabled no)
				(sheetname "")
			)
			(fill
				(thermal_gap 0.5)
				(thermal_bridge_width 0.5)
				(island_removal_mode 0)
			)
			(polygon
				(pts
					(arc
						(start 91.399868 -282.188666)
						(mid 91.399868 -291.231066)
						(end 91.399868 -282.188666)
					)
				)
			)
		)
	)
	(footprint ""
		(layer "F.Cu")
		(at 16.599916 -473.69984)
		(property "Reference" "H8"
			(at -6.4516 -7.127748 0)
			(unlocked yes)
			(layer "F.SilkS")
			(effects
				(font
					(size 0.7874 0.5842)
					(thickness 0.1524)
				)
				(justify left)
			)
		)
		(property "Value" ""
			(at 0 0 0)
			(layer "F.Fab")
			(effects
				(font
					(size 1.27 1.27)
				)
			)
		)
		(duplicate_pad_numbers_are_jumpers no)
		(fp_circle
			(center 0 0)
			(end 7.999984 0)
			(stroke
				(width 0.1524)
				(type default)
			)
			(fill no)
			(layer "F.SilkS")
		)
		(fp_circle
			(center 0 0)
			(end 14.7066 0)
			(stroke
				(width 0.1524)
				(type default)
			)
			(fill no)
			(layer "B.SilkS")
		)
		(fp_poly
			(pts
				(arc
					(start 0 5.0038)
					(mid 0 -5.0038)
					(end 0 5.0038)
				)
			)
			(stroke
				(width 0)
				(type default)
			)
			(fill no)
			(layer "F.CrtYd")
		)
		(pad "" np_thru_hole circle
			(at 0 0)
			(size 4.0132 4.0132)
			(drill 4.0132)
			(layers "*.Cu" "*.Mask")
			(clearance 0.381)
			(thermal_gap 0.381)
		)
		(pad "2" thru_hole circle
			(at 0 -3.50012)
			(size 0.762 0.762)
			(drill 0.5588)
			(layers "*.Cu" "*.Mask")
			(remove_unused_layers no)
			(net "GND")
			(clearance 0.1524)
			(thermal_gap 0.1524)
		)
		(pad "3" thru_hole circle
			(at -2.500122 -2.500122)
			(size 0.762 0.762)
			(drill 0.5588)
			(layers "*.Cu" "*.Mask")
			(remove_unused_layers no)
			(net "GND")
			(clearance 0.1524)
			(thermal_gap 0.1524)
		)
		(pad "4" thru_hole circle
			(at -3.50012 0)
			(size 0.762 0.762)
			(drill 0.5588)
			(layers "*.Cu" "*.Mask")
			(remove_unused_layers no)
			(net "GND")
			(clearance 0.1524)
			(thermal_gap 0.1524)
		)
		(pad "5" thru_hole circle
			(at -2.500122 2.500122)
			(size 0.762 0.762)
			(drill 0.5588)
			(layers "*.Cu" "*.Mask")
			(remove_unused_layers no)
			(net "GND")
			(clearance 0.1524)
			(thermal_gap 0.1524)
		)
		(pad "6" thru_hole circle
			(at 0 3.50012)
			(size 0.762 0.762)
			(drill 0.5588)
			(layers "*.Cu" "*.Mask")
			(remove_unused_layers no)
			(net "GND")
			(clearance 0.1524)
			(thermal_gap 0.1524)
		)
		(pad "7" thru_hole circle
			(at 2.500122 2.500122)
			(size 0.762 0.762)
			(drill 0.5588)
			(layers "*.Cu" "*.Mask")
			(remove_unused_layers no)
			(net "GND")
			(clearance 0.1524)
			(thermal_gap 0.1524)
		)
		(pad "8" thru_hole circle
			(at 3.50012 0)
			(size 0.762 0.762)
			(drill 0.5588)
			(layers "*.Cu" "*.Mask")
			(remove_unused_layers no)
			(net "GND")
			(clearance 0.1524)
			(thermal_gap 0.1524)
		)
		(pad "9" thru_hole circle
			(at 2.500122 -2.500122)
			(size 0.762 0.762)
			(drill 0.5588)
			(layers "*.Cu" "*.Mask")
			(remove_unused_layers no)
			(net "GND")
			(clearance 0.1524)
			(thermal_gap 0.1524)
		)
		(zone
			(layer "F.Cu")
			(hatch none 0.5)
			(connect_pads
				(clearance 0)
			)
			(min_thickness 0.25)
			(keepout
				(tracks not_allowed)
				(vias allowed)
				(pads allowed)
				(copperpour not_allowed)
				(footprints allowed)
			)
			(placement
				(enabled no)
				(sheetname "")
			)
			(fill
				(thermal_gap 0.5)
				(thermal_bridge_width 0.5)
				(island_removal_mode 0)
			)
			(polygon
				(pts
					(arc
						(start 16.599916 -481.70084)
						(mid 8.598916 -473.69984)
						(end 16.599916 -465.69884)
					)
					(arc
						(start 16.599916 -465.69884)
						(mid 18.035016 -467.13394)
						(end 16.599916 -468.56904)
					)
					(arc
						(start 16.599916 -468.56904)
						(mid 11.469116 -473.69984)
						(end 16.599916 -478.83064)
					)
					(arc
						(start 16.599916 -478.83064)
						(mid 18.035016 -480.26574)
						(end 16.599916 -481.70084)
					)
				)
			)
		)
		(zone
			(layer "F.Cu")
			(hatch none 0.5)
			(connect_pads
				(clearance 0)
			)
			(min_thickness 0.25)
			(keepout
				(tracks not_allowed)
				(vias allowed)
				(pads allowed)
				(copperpour not_allowed)
				(footprints allowed)
			)
			(placement
				(enabled no)
				(sheetname "")
			)
			(fill
				(thermal_gap 0.5)
				(thermal_bridge_width 0.5)
				(island_removal_mode 0)
			)
			(polygon
				(pts
					(arc
						(start 16.599916 -481.70084)
						(mid 24.600916 -473.69984)
						(end 16.599916 -465.69884)
					)
					(arc
						(start 16.599916 -465.69884)
						(mid 15.164816 -467.13394)
						(end 16.599916 -468.56904)
					)
					(arc
						(start 16.599916 -468.56904)
						(mid 21.730716 -473.69984)
						(end 16.599916 -478.83064)
					)
					(arc
						(start 16.599916 -478.83064)
						(mid 15.164816 -480.26574)
						(end 16.599916 -481.70084)
					)
				)
			)
		)
		(zone
			(layers "F.Cu" "B.Cu" "In1.Cu" "In2.Cu" "In3.Cu" "In4.Cu" "In5.Cu" "In6.Cu")
			(hatch none 0.5)
			(connect_pads
				(clearance 0)
			)
			(min_thickness 0.25)
			(keepout
				(tracks not_allowed)
				(vias allowed)
				(pads allowed)
				(copperpour not_allowed)
				(footprints allowed)
			)
			(placement
				(enabled no)
				(sheetname "")
			)
			(fill
				(thermal_gap 0.5)
				(thermal_bridge_width 0.5)
				(island_removal_mode 0)
			)
			(polygon
				(pts
					(arc
						(start 16.599916 -471.18778)
						(mid 16.599916 -476.2119)
						(end 16.599916 -471.18778)
					)
				)
			)
		)
	)
	(footprint ""
		(layer "F.Cu")
		(at 71.810118 -487.29138 90)
		(property "Reference" "C82"
			(at -4.162806 0.225044 90)
			(unlocked yes)
			(layer "F.SilkS")
			(effects
				(font
					(size 0.7874 0.5842)
					(thickness 0.1524)
				)
				(justify left)
			)
		)
		(property "Value" ""
			(at 0 0 90)
			(layer "F.Fab")
			(effects
				(font
					(size 1.27 1.27)
				)
			)
		)
		(duplicate_pad_numbers_are_jumpers no)
		(fp_line
			(start 0.7874 -0.4064)
			(end 0.7874 0.4064)
			(stroke
				(width 0.1524)
				(type default)
			)
			(layer "F.SilkS")
		)
		(fp_line
			(start -0.7874 -0.4064)
			(end 0.7874 -0.4064)
			(stroke
				(width 0.1524)
				(type default)
			)
			(layer "F.SilkS")
		)
		(fp_line
			(start 0 0.381)
			(end 0 -0.381)
			(stroke
				(width 0.1524)
				(type default)
			)
			(layer "F.SilkS")
		)
		(fp_line
			(start 0.7874 0.4064)
			(end -0.7874 0.4064)
			(stroke
				(width 0.1524)
				(type default)
			)
			(layer "F.SilkS")
		)
		(fp_line
			(start -0.7874 0.4064)
			(end -0.7874 -0.4064)
			(stroke
				(width 0.1524)
				(type default)
			)
			(layer "F.SilkS")
		)
		(fp_poly
			(pts
				(xy -0.5334 0.254) (xy -0.635 0.254) (xy -0.635 0.2286) (xy -0.635 -0.254) (xy -0.5334 -0.254) (xy -0.5334 -0.2794)
				(xy 0.5334 -0.2794) (xy 0.5334 -0.254) (xy 0.635 -0.254) (xy 0.635 0.254) (xy 0.5334 0.254) (xy 0.5334 0.2794)
				(xy -0.508 0.2794) (xy -0.5334 0.2794)
			)
			(stroke
				(width 0)
				(type default)
			)
			(fill no)
			(layer "F.CrtYd")
		)
		(pad "1" smd rect
			(at 0.40005 0 90)
			(size 0.4572 0.508)
			(layers "F.Cu" "F.Mask" "F.Paste")
			(net "P12V")
		)
		(pad "2" smd rect
			(at -0.40005 0 90)
			(size 0.4572 0.508)
			(layers "F.Cu" "F.Mask" "F.Paste")
			(net "GND")
		)
	)
	(footprint ""
		(layer "F.Cu")
		(at 45.911008 -261.777988 180)
		(property "Reference" "R104"
			(at 4.5974 0.054356 0)
			(unlocked yes)
			(layer "F.SilkS")
			(effects
				(font
					(size 0.7874 0.5842)
					(thickness 0.1524)
				)
				(justify left)
			)
		)
		(property "Value" ""
			(at 0 0 180)
			(layer "F.Fab")
			(effects
				(font
					(size 1.27 1.27)
				)
			)
		)
		(duplicate_pad_numbers_are_jumpers no)
		(fp_line
			(start 0.7874 0.4064)
			(end -0.7874 0.4064)
			(stroke
				(width 0.1524)
				(type default)
			)
			(layer "F.SilkS")
		)
		(fp_line
			(start 0.7874 -0.4064)
			(end 0.7874 0.4064)
			(stroke
				(width 0.1524)
				(type default)
			)
			(layer "F.SilkS")
		)
		(fp_line
			(start -0.7874 0.4064)
			(end -0.7874 -0.4064)
			(stroke
				(width 0.1524)
				(type default)
			)
			(layer "F.SilkS")
		)
		(fp_line
			(start -0.7874 -0.4064)
			(end 0.7874 -0.4064)
			(stroke
				(width 0.1524)
				(type default)
			)
			(layer "F.SilkS")
		)
		(fp_poly
			(pts
				(xy -0.508 0.2794) (xy -0.508 0.2286) (xy -0.635 0.2286) (xy -0.635 -0.254) (xy -0.5334 -0.254)
				(xy -0.5334 -0.2794) (xy 0.5334 -0.2794) (xy 0.5334 -0.254) (xy 0.635 -0.254) (xy 0.635 0.254) (xy 0.5334 0.254)
				(xy 0.5334 0.2794)
			)
			(stroke
				(width 0)
				(type default)
			)
			(fill no)
			(layer "F.CrtYd")
		)
		(pad "1" smd rect
			(at 0.40005 0 180)
			(size 0.4572 0.508)
			(layers "F.Cu" "F.Mask" "F.Paste")
			(net "PSU5_REMOTE_R_P")
		)
		(pad "2" smd rect
			(at -0.40005 0 180)
			(size 0.4572 0.508)
			(layers "F.Cu" "F.Mask" "F.Paste")
			(net "P12V")
		)
	)
	(footprint ""
		(layer "F.Cu")
		(at 72.403716 -397.262604 90)
		(property "Reference" "C70"
			(at -1.662176 -5.059172 90)
			(unlocked yes)
			(layer "F.SilkS")
			(effects
				(font
					(size 0.7874 0.5842)
					(thickness 0.1524)
				)
				(justify left)
			)
		)
		(property "Value" ""
			(at 0 0 90)
			(layer "F.Fab")
			(effects
				(font
					(size 1.27 1.27)
				)
			)
		)
		(duplicate_pad_numbers_are_jumpers no)
		(fp_line
			(start 0.7874 -0.4064)
			(end 0.7874 0.4064)
			(stroke
				(width 0.1524)
				(type default)
			)
			(layer "F.SilkS")
		)
		(fp_line
			(start -0.7874 -0.4064)
			(end 0.7874 -0.4064)
			(stroke
				(width 0.1524)
				(type default)
			)
			(layer "F.SilkS")
		)
		(fp_line
			(start 0 0.381)
			(end 0 -0.381)
			(stroke
				(width 0.1524)
				(type default)
			)
			(layer "F.SilkS")
		)
		(fp_line
			(start 0.7874 0.4064)
			(end -0.7874 0.4064)
			(stroke
				(width 0.1524)
				(type default)
			)
			(layer "F.SilkS")
		)
		(fp_line
			(start -0.7874 0.4064)
			(end -0.7874 -0.4064)
			(stroke
				(width 0.1524)
				(type default)
			)
			(layer "F.SilkS")
		)
		(fp_poly
			(pts
				(xy -0.5334 0.254) (xy -0.635 0.254) (xy -0.635 0.2286) (xy -0.635 -0.254) (xy -0.5334 -0.254) (xy -0.5334 -0.2794)
				(xy 0.5334 -0.2794) (xy 0.5334 -0.254) (xy 0.635 -0.254) (xy 0.635 0.254) (xy 0.5334 0.254) (xy 0.5334 0.2794)
				(xy -0.508 0.2794) (xy -0.5334 0.2794)
			)
			(stroke
				(width 0)
				(type default)
			)
			(fill no)
			(layer "F.CrtYd")
		)
		(pad "1" smd rect
			(at 0.40005 0 90)
			(size 0.4572 0.508)
			(layers "F.Cu" "F.Mask" "F.Paste")
			(net "P12V")
		)
		(pad "2" smd rect
			(at -0.40005 0 90)
			(size 0.4572 0.508)
			(layers "F.Cu" "F.Mask" "F.Paste")
			(net "GND")
		)
	)
	(footprint ""
		(layer "F.Cu")
		(at 13.463778 -324.01002 180)
		(property "Reference" "R146"
			(at -1.034796 0.001778 0)
			(unlocked yes)
			(layer "F.SilkS")
			(effects
				(font
					(size 0.7874 0.5842)
					(thickness 0.1524)
				)
				(justify left)
			)
		)
		(property "Value" ""
			(at 0 0 180)
			(layer "F.Fab")
			(effects
				(font
					(size 1.27 1.27)
				)
			)
		)
		(duplicate_pad_numbers_are_jumpers no)
		(fp_line
			(start 0.7874 0.4064)
			(end -0.7874 0.4064)
			(stroke
				(width 0.1524)
				(type default)
			)
			(layer "F.SilkS")
		)
		(fp_line
			(start 0.7874 -0.4064)
			(end 0.7874 0.4064)
			(stroke
				(width 0.1524)
				(type default)
			)
			(layer "F.SilkS")
		)
		(fp_line
			(start -0.7874 0.4064)
			(end -0.7874 -0.4064)
			(stroke
				(width 0.1524)
				(type default)
			)
			(layer "F.SilkS")
		)
		(fp_line
			(start -0.7874 -0.4064)
			(end 0.7874 -0.4064)
			(stroke
				(width 0.1524)
				(type default)
			)
			(layer "F.SilkS")
		)
		(fp_poly
			(pts
				(xy -0.508 0.2794) (xy -0.508 0.2286) (xy -0.635 0.2286) (xy -0.635 -0.254) (xy -0.5334 -0.254)
				(xy -0.5334 -0.2794) (xy 0.5334 -0.2794) (xy 0.5334 -0.254) (xy 0.635 -0.254) (xy 0.635 0.254) (xy 0.5334 0.254)
				(xy 0.5334 0.2794)
			)
			(stroke
				(width 0)
				(type default)
			)
			(fill no)
			(layer "F.CrtYd")
		)
		(pad "1" smd rect
			(at 0.40005 0 180)
			(size 0.4572 0.508)
			(layers "F.Cu" "F.Mask" "F.Paste")
			(net "FAN5_TACH")
		)
		(pad "2" smd rect
			(at -0.40005 0 180)
			(size 0.4572 0.508)
			(layers "F.Cu" "F.Mask" "F.Paste")
			(net "P12V")
		)
	)
	(footprint ""
		(layer "F.Cu")
		(at 74.709782 -326.522588 -90)
		(property "Reference" "C52"
			(at -2.752344 0.057404 90)
			(unlocked yes)
			(layer "F.SilkS")
			(effects
				(font
					(size 0.7874 0.5842)
					(thickness 0.1524)
				)
				(justify left)
			)
		)
		(property "Value" ""
			(at 0 0 270)
			(layer "F.Fab")
			(effects
				(font
					(size 1.27 1.27)
				)
			)
		)
		(duplicate_pad_numbers_are_jumpers no)
		(fp_line
			(start -0.7874 0.4064)
			(end -0.7874 -0.4064)
			(stroke
				(width 0.1524)
				(type default)
			)
			(layer "F.SilkS")
		)
		(fp_line
			(start 0.7874 0.4064)
			(end -0.7874 0.4064)
			(stroke
				(width 0.1524)
				(type default)
			)
			(layer "F.SilkS")
		)
		(fp_line
			(start 0 0.381)
			(end 0 -0.381)
			(stroke
				(width 0.1524)
				(type default)
			)
			(layer "F.SilkS")
		)
		(fp_line
			(start -0.7874 -0.4064)
			(end 0.7874 -0.4064)
			(stroke
				(width 0.1524)
				(type default)
			)
			(layer "F.SilkS")
		)
		(fp_line
			(start 0.7874 -0.4064)
			(end 0.7874 0.4064)
			(stroke
				(width 0.1524)
				(type default)
			)
			(layer "F.SilkS")
		)
		(fp_poly
			(pts
				(xy -0.5334 0.254) (xy -0.635 0.254) (xy -0.635 0.2286) (xy -0.635 -0.254) (xy -0.5334 -0.254) (xy -0.5334 -0.2794)
				(xy 0.5334 -0.2794) (xy 0.5334 -0.254) (xy 0.635 -0.254) (xy 0.635 0.254) (xy 0.5334 0.254) (xy 0.5334 0.2794)
				(xy -0.508 0.2794) (xy -0.5334 0.2794)
			)
			(stroke
				(width 0)
				(type default)
			)
			(fill no)
			(layer "F.CrtYd")
		)
		(pad "1" smd rect
			(at 0.40005 0 270)
			(size 0.4572 0.508)
			(layers "F.Cu" "F.Mask" "F.Paste")
			(net "P12V")
		)
		(pad "2" smd rect
			(at -0.40005 0 270)
			(size 0.4572 0.508)
			(layers "F.Cu" "F.Mask" "F.Paste")
			(net "GND")
		)
	)
	(footprint ""
		(layer "F.Cu")
		(at 40.959024 -105.82148 -90)
		(property "Reference" "R8"
			(at 0.823722 -2.429256 90)
			(unlocked yes)
			(layer "F.SilkS")
			(effects
				(font
					(size 0.7874 0.5842)
					(thickness 0.1524)
				)
				(justify left)
			)
		)
		(property "Value" ""
			(at 0 0 270)
			(layer "F.Fab")
			(effects
				(font
					(size 1.27 1.27)
				)
			)
		)
		(duplicate_pad_numbers_are_jumpers no)
		(fp_line
			(start -0.7874 0.4064)
			(end -0.7874 -0.4064)
			(stroke
				(width 0.1524)
				(type default)
			)
			(layer "F.SilkS")
		)
		(fp_line
			(start 0.7874 0.4064)
			(end -0.7874 0.4064)
			(stroke
				(width 0.1524)
				(type default)
			)
			(layer "F.SilkS")
		)
		(fp_line
			(start -0.7874 -0.4064)
			(end 0.7874 -0.4064)
			(stroke
				(width 0.1524)
				(type default)
			)
			(layer "F.SilkS")
		)
		(fp_line
			(start 0.7874 -0.4064)
			(end 0.7874 0.4064)
			(stroke
				(width 0.1524)
				(type default)
			)
			(layer "F.SilkS")
		)
		(fp_poly
			(pts
				(xy -0.508 0.2794) (xy -0.508 0.2286) (xy -0.635 0.2286) (xy -0.635 -0.254) (xy -0.5334 -0.254)
				(xy -0.5334 -0.2794) (xy 0.5334 -0.2794) (xy 0.5334 -0.254) (xy 0.635 -0.254) (xy 0.635 0.254) (xy 0.5334 0.254)
				(xy 0.5334 0.2794)
			)
			(stroke
				(width 0)
				(type default)
			)
			(fill no)
			(layer "F.CrtYd")
		)
		(pad "1" smd rect
			(at 0.40005 0 270)
			(size 0.4572 0.508)
			(layers "F.Cu" "F.Mask" "F.Paste")
			(net "PSU2_AD0")
		)
		(pad "2" smd rect
			(at -0.40005 0 270)
			(size 0.4572 0.508)
			(layers "F.Cu" "F.Mask" "F.Paste")
			(net "GND")
		)
	)
	(footprint ""
		(layer "F.Cu")
		(at 39.705534 -105.822242 -90)
		(property "Reference" "R4"
			(at 0.830326 -2.570734 90)
			(unlocked yes)
			(layer "F.SilkS")
			(effects
				(font
					(size 0.7874 0.5842)
					(thickness 0.1524)
				)
				(justify left)
			)
		)
		(property "Value" ""
			(at 0 0 270)
			(layer "F.Fab")
			(effects
				(font
					(size 1.27 1.27)
				)
			)
		)
		(duplicate_pad_numbers_are_jumpers no)
		(fp_line
			(start -0.7874 0.4064)
			(end -0.7874 -0.4064)
			(stroke
				(width 0.1524)
				(type default)
			)
			(layer "F.SilkS")
		)
		(fp_line
			(start 0.7874 0.4064)
			(end -0.7874 0.4064)
			(stroke
				(width 0.1524)
				(type default)
			)
			(layer "F.SilkS")
		)
		(fp_line
			(start -0.7874 -0.4064)
			(end 0.7874 -0.4064)
			(stroke
				(width 0.1524)
				(type default)
			)
			(layer "F.SilkS")
		)
		(fp_line
			(start 0.7874 -0.4064)
			(end 0.7874 0.4064)
			(stroke
				(width 0.1524)
				(type default)
			)
			(layer "F.SilkS")
		)
		(fp_poly
			(pts
				(xy -0.508 0.2794) (xy -0.508 0.2286) (xy -0.635 0.2286) (xy -0.635 -0.254) (xy -0.5334 -0.254)
				(xy -0.5334 -0.2794) (xy 0.5334 -0.2794) (xy 0.5334 -0.254) (xy 0.635 -0.254) (xy 0.635 0.254) (xy 0.5334 0.254)
				(xy 0.5334 0.2794)
			)
			(stroke
				(width 0)
				(type default)
			)
			(fill no)
			(layer "F.CrtYd")
		)
		(pad "1" smd rect
			(at 0.40005 0 270)
			(size 0.4572 0.508)
			(layers "F.Cu" "F.Mask" "F.Paste")
			(net "PSU2_AD0")
		)
		(pad "2" smd rect
			(at -0.40005 0 270)
			(size 0.4572 0.508)
			(layers "F.Cu" "F.Mask" "F.Paste")
			(net "P12V_STBY")
		)
	)
	(footprint ""
		(layer "F.Cu")
		(at 26.102056 -272.345404)
		(property "Reference" "R57"
			(at -4.037838 -0.005334 0)
			(unlocked yes)
			(layer "F.SilkS")
			(effects
				(font
					(size 0.7874 0.5842)
					(thickness 0.1524)
				)
				(justify left)
			)
		)
		(property "Value" ""
			(at 0 0 0)
			(layer "F.Fab")
			(effects
				(font
					(size 1.27 1.27)
				)
			)
		)
		(duplicate_pad_numbers_are_jumpers no)
		(fp_line
			(start -0.7874 -0.4064)
			(end 0.7874 -0.4064)
			(stroke
				(width 0.1524)
				(type default)
			)
			(layer "F.SilkS")
		)
		(fp_line
			(start -0.7874 0.4064)
			(end -0.7874 -0.4064)
			(stroke
				(width 0.1524)
				(type default)
			)
			(layer "F.SilkS")
		)
		(fp_line
			(start 0.7874 -0.4064)
			(end 0.7874 0.4064)
			(stroke
				(width 0.1524)
				(type default)
			)
			(layer "F.SilkS")
		)
		(fp_line
			(start 0.7874 0.4064)
			(end -0.7874 0.4064)
			(stroke
				(width 0.1524)
				(type default)
			)
			(layer "F.SilkS")
		)
		(fp_poly
			(pts
				(xy -0.508 0.2794) (xy -0.508 0.2286) (xy -0.635 0.2286) (xy -0.635 -0.254) (xy -0.5334 -0.254)
				(xy -0.5334 -0.2794) (xy 0.5334 -0.2794) (xy 0.5334 -0.254) (xy 0.635 -0.254) (xy 0.635 0.254) (xy 0.5334 0.254)
				(xy 0.5334 0.2794)
			)
			(stroke
				(width 0)
				(type default)
			)
			(fill no)
			(layer "F.CrtYd")
		)
		(pad "1" smd rect
			(at 0.40005 0)
			(size 0.4572 0.508)
			(layers "F.Cu" "F.Mask" "F.Paste")
			(net "PSU4_RESET")
		)
		(pad "2" smd rect
			(at -0.40005 0)
			(size 0.4572 0.508)
			(layers "F.Cu" "F.Mask" "F.Paste")
			(net "GND")
		)
	)
	(footprint ""
		(layer "F.Cu")
		(at 39.858188 -287.573212 180)
		(property "Reference" "R15"
			(at -1.140714 0.062738 0)
			(unlocked yes)
			(layer "F.SilkS")
			(effects
				(font
					(size 0.7874 0.5842)
					(thickness 0.1524)
				)
				(justify left)
			)
		)
		(property "Value" ""
			(at 0 0 180)
			(layer "F.Fab")
			(effects
				(font
					(size 1.27 1.27)
				)
			)
		)
		(duplicate_pad_numbers_are_jumpers no)
		(fp_line
			(start 0.7874 0.4064)
			(end -0.7874 0.4064)
			(stroke
				(width 0.1524)
				(type default)
			)
			(layer "F.SilkS")
		)
		(fp_line
			(start 0.7874 -0.4064)
			(end 0.7874 0.4064)
			(stroke
				(width 0.1524)
				(type default)
			)
			(layer "F.SilkS")
		)
		(fp_line
			(start -0.7874 0.4064)
			(end -0.7874 -0.4064)
			(stroke
				(width 0.1524)
				(type default)
			)
			(layer "F.SilkS")
		)
		(fp_line
			(start -0.7874 -0.4064)
			(end 0.7874 -0.4064)
			(stroke
				(width 0.1524)
				(type default)
			)
			(layer "F.SilkS")
		)
		(fp_poly
			(pts
				(xy -0.508 0.2794) (xy -0.508 0.2286) (xy -0.635 0.2286) (xy -0.635 -0.254) (xy -0.5334 -0.254)
				(xy -0.5334 -0.2794) (xy 0.5334 -0.2794) (xy 0.5334 -0.254) (xy 0.635 -0.254) (xy 0.635 0.254) (xy 0.5334 0.254)
				(xy 0.5334 0.2794)
			)
			(stroke
				(width 0)
				(type default)
			)
			(fill no)
			(layer "F.CrtYd")
		)
		(pad "1" smd rect
			(at 0.40005 0 180)
			(size 0.4572 0.508)
			(layers "F.Cu" "F.Mask" "F.Paste")
			(net "PSU4_REMOTE_P")
		)
		(pad "2" smd rect
			(at -0.40005 0 180)
			(size 0.4572 0.508)
			(layers "F.Cu" "F.Mask" "F.Paste")
			(net "P12V")
		)
	)
	(footprint ""
		(layer "F.Cu")
		(at 12.784074 -330.48067 -90)
		(property "Reference" "R34"
			(at 3.685032 -0.234188 90)
			(unlocked yes)
			(layer "F.SilkS")
			(effects
				(font
					(size 0.7874 0.5842)
					(thickness 0.1524)
				)
				(justify left)
			)
		)
		(property "Value" ""
			(at 0 0 270)
			(layer "F.Fab")
			(effects
				(font
					(size 1.27 1.27)
				)
			)
		)
		(duplicate_pad_numbers_are_jumpers no)
		(fp_line
			(start -0.7874 0.4064)
			(end -0.7874 -0.4064)
			(stroke
				(width 0.1524)
				(type default)
			)
			(layer "F.SilkS")
		)
		(fp_line
			(start 0.7874 0.4064)
			(end -0.7874 0.4064)
			(stroke
				(width 0.1524)
				(type default)
			)
			(layer "F.SilkS")
		)
		(fp_line
			(start -0.7874 -0.4064)
			(end 0.7874 -0.4064)
			(stroke
				(width 0.1524)
				(type default)
			)
			(layer "F.SilkS")
		)
		(fp_line
			(start 0.7874 -0.4064)
			(end 0.7874 0.4064)
			(stroke
				(width 0.1524)
				(type default)
			)
			(layer "F.SilkS")
		)
		(fp_poly
			(pts
				(xy -0.508 0.2794) (xy -0.508 0.2286) (xy -0.635 0.2286) (xy -0.635 -0.254) (xy -0.5334 -0.254)
				(xy -0.5334 -0.2794) (xy 0.5334 -0.2794) (xy 0.5334 -0.254) (xy 0.635 -0.254) (xy 0.635 0.254) (xy 0.5334 0.254)
				(xy 0.5334 0.2794)
			)
			(stroke
				(width 0)
				(type default)
			)
			(fill no)
			(layer "F.CrtYd")
		)
		(pad "1" smd rect
			(at 0.40005 0 270)
			(size 0.4572 0.508)
			(layers "F.Cu" "F.Mask" "F.Paste")
			(net "P3V3")
		)
		(pad "2" smd rect
			(at -0.40005 0 270)
			(size 0.4572 0.508)
			(layers "F.Cu" "F.Mask" "F.Paste")
			(net "FRU_A0")
		)
	)
	(footprint ""
		(layer "F.Cu")
		(at 72.19696 -354.308918 90)
		(property "Reference" "C60"
			(at -3.926332 0.77978 90)
			(unlocked yes)
			(layer "F.SilkS")
			(effects
				(font
					(size 0.7874 0.5842)
					(thickness 0.1524)
				)
				(justify left)
			)
		)
		(property "Value" ""
			(at 0 0 90)
			(layer "F.Fab")
			(effects
				(font
					(size 1.27 1.27)
				)
			)
		)
		(duplicate_pad_numbers_are_jumpers no)
		(fp_line
			(start 0.7874 -0.4064)
			(end 0.7874 0.4064)
			(stroke
				(width 0.1524)
				(type default)
			)
			(layer "F.SilkS")
		)
		(fp_line
			(start -0.7874 -0.4064)
			(end 0.7874 -0.4064)
			(stroke
				(width 0.1524)
				(type default)
			)
			(layer "F.SilkS")
		)
		(fp_line
			(start 0 0.381)
			(end 0 -0.381)
			(stroke
				(width 0.1524)
				(type default)
			)
			(layer "F.SilkS")
		)
		(fp_line
			(start 0.7874 0.4064)
			(end -0.7874 0.4064)
			(stroke
				(width 0.1524)
				(type default)
			)
			(layer "F.SilkS")
		)
		(fp_line
			(start -0.7874 0.4064)
			(end -0.7874 -0.4064)
			(stroke
				(width 0.1524)
				(type default)
			)
			(layer "F.SilkS")
		)
		(fp_poly
			(pts
				(xy -0.5334 0.254) (xy -0.635 0.254) (xy -0.635 0.2286) (xy -0.635 -0.254) (xy -0.5334 -0.254) (xy -0.5334 -0.2794)
				(xy 0.5334 -0.2794) (xy 0.5334 -0.254) (xy 0.635 -0.254) (xy 0.635 0.254) (xy 0.5334 0.254) (xy 0.5334 0.2794)
				(xy -0.508 0.2794) (xy -0.5334 0.2794)
			)
			(stroke
				(width 0)
				(type default)
			)
			(fill no)
			(layer "F.CrtYd")
		)
		(pad "1" smd rect
			(at 0.40005 0 90)
			(size 0.4572 0.508)
			(layers "F.Cu" "F.Mask" "F.Paste")
			(net "P12V")
		)
		(pad "2" smd rect
			(at -0.40005 0 90)
			(size 0.4572 0.508)
			(layers "F.Cu" "F.Mask" "F.Paste")
			(net "GND")
		)
	)
	(footprint ""
		(layer "F.Cu")
		(at 13.853922 -330.480924 -90)
		(property "Reference" "R37"
			(at 3.685032 -0.234188 90)
			(unlocked yes)
			(layer "F.SilkS")
			(effects
				(font
					(size 0.7874 0.5842)
					(thickness 0.1524)
				)
				(justify left)
			)
		)
		(property "Value" ""
			(at 0 0 270)
			(layer "F.Fab")
			(effects
				(font
					(size 1.27 1.27)
				)
			)
		)
		(duplicate_pad_numbers_are_jumpers no)
		(fp_line
			(start -0.7874 0.4064)
			(end -0.7874 -0.4064)
			(stroke
				(width 0.1524)
				(type default)
			)
			(layer "F.SilkS")
		)
		(fp_line
			(start 0.7874 0.4064)
			(end -0.7874 0.4064)
			(stroke
				(width 0.1524)
				(type default)
			)
			(layer "F.SilkS")
		)
		(fp_line
			(start -0.7874 -0.4064)
			(end 0.7874 -0.4064)
			(stroke
				(width 0.1524)
				(type default)
			)
			(layer "F.SilkS")
		)
		(fp_line
			(start 0.7874 -0.4064)
			(end 0.7874 0.4064)
			(stroke
				(width 0.1524)
				(type default)
			)
			(layer "F.SilkS")
		)
		(fp_poly
			(pts
				(xy -0.508 0.2794) (xy -0.508 0.2286) (xy -0.635 0.2286) (xy -0.635 -0.254) (xy -0.5334 -0.254)
				(xy -0.5334 -0.2794) (xy 0.5334 -0.2794) (xy 0.5334 -0.254) (xy 0.635 -0.254) (xy 0.635 0.254) (xy 0.5334 0.254)
				(xy 0.5334 0.2794)
			)
			(stroke
				(width 0)
				(type default)
			)
			(fill no)
			(layer "F.CrtYd")
		)
		(pad "1" smd rect
			(at 0.40005 0 270)
			(size 0.4572 0.508)
			(layers "F.Cu" "F.Mask" "F.Paste")
			(net "GND")
		)
		(pad "2" smd rect
			(at -0.40005 0 270)
			(size 0.4572 0.508)
			(layers "F.Cu" "F.Mask" "F.Paste")
			(net "FRU_A0")
		)
	)
	(footprint ""
		(layer "F.Cu")
		(at 27.347672 -108.630466 -90)
		(property "Reference" "R93"
			(at -0.391414 1.160526 90)
			(unlocked yes)
			(layer "F.SilkS")
			(effects
				(font
					(size 0.7874 0.5842)
					(thickness 0.1524)
				)
				(justify left)
			)
		)
		(property "Value" ""
			(at 0 0 270)
			(layer "F.Fab")
			(effects
				(font
					(size 1.27 1.27)
				)
			)
		)
		(duplicate_pad_numbers_are_jumpers no)
		(fp_line
			(start -0.7874 0.4064)
			(end -0.7874 -0.4064)
			(stroke
				(width 0.1524)
				(type default)
			)
			(layer "F.SilkS")
		)
		(fp_line
			(start 0.7874 0.4064)
			(end -0.7874 0.4064)
			(stroke
				(width 0.1524)
				(type default)
			)
			(layer "F.SilkS")
		)
		(fp_line
			(start -0.7874 -0.4064)
			(end 0.7874 -0.4064)
			(stroke
				(width 0.1524)
				(type default)
			)
			(layer "F.SilkS")
		)
		(fp_line
			(start 0.7874 -0.4064)
			(end 0.7874 0.4064)
			(stroke
				(width 0.1524)
				(type default)
			)
			(layer "F.SilkS")
		)
		(fp_poly
			(pts
				(xy -0.508 0.2794) (xy -0.508 0.2286) (xy -0.635 0.2286) (xy -0.635 -0.254) (xy -0.5334 -0.254)
				(xy -0.5334 -0.2794) (xy 0.5334 -0.2794) (xy 0.5334 -0.254) (xy 0.635 -0.254) (xy 0.635 0.254) (xy 0.5334 0.254)
				(xy 0.5334 0.2794)
			)
			(stroke
				(width 0)
				(type default)
			)
			(fill no)
			(layer "F.CrtYd")
		)
		(pad "1" smd rect
			(at 0.40005 0 270)
			(size 0.4572 0.508)
			(layers "F.Cu" "F.Mask" "F.Paste")
			(net "PSU2_REMOTE_N")
		)
		(pad "2" smd rect
			(at -0.40005 0 270)
			(size 0.4572 0.508)
			(layers "F.Cu" "F.Mask" "F.Paste")
			(net "PSU2_REMOTE_R_N")
		)
	)
	(footprint ""
		(layer "F.Cu")
		(at 25.997662 -7.19328)
		(property "Reference" "R62"
			(at -3.764788 0.113792 0)
			(unlocked yes)
			(layer "F.SilkS")
			(effects
				(font
					(size 0.7874 0.5842)
					(thickness 0.1524)
				)
				(justify left)
			)
		)
		(property "Value" ""
			(at 0 0 0)
			(layer "F.Fab")
			(effects
				(font
					(size 1.27 1.27)
				)
			)
		)
		(duplicate_pad_numbers_are_jumpers no)
		(fp_line
			(start -0.7874 -0.4064)
			(end 0.7874 -0.4064)
			(stroke
				(width 0.1524)
				(type default)
			)
			(layer "F.SilkS")
		)
		(fp_line
			(start -0.7874 0.4064)
			(end -0.7874 -0.4064)
			(stroke
				(width 0.1524)
				(type default)
			)
			(layer "F.SilkS")
		)
		(fp_line
			(start 0.7874 -0.4064)
			(end 0.7874 0.4064)
			(stroke
				(width 0.1524)
				(type default)
			)
			(layer "F.SilkS")
		)
		(fp_line
			(start 0.7874 0.4064)
			(end -0.7874 0.4064)
			(stroke
				(width 0.1524)
				(type default)
			)
			(layer "F.SilkS")
		)
		(fp_poly
			(pts
				(xy -0.508 0.2794) (xy -0.508 0.2286) (xy -0.635 0.2286) (xy -0.635 -0.254) (xy -0.5334 -0.254)
				(xy -0.5334 -0.2794) (xy 0.5334 -0.2794) (xy 0.5334 -0.254) (xy 0.635 -0.254) (xy 0.635 0.254) (xy 0.5334 0.254)
				(xy 0.5334 0.2794)
			)
			(stroke
				(width 0)
				(type default)
			)
			(fill no)
			(layer "F.CrtYd")
		)
		(pad "1" smd rect
			(at 0.40005 0)
			(size 0.4572 0.508)
			(layers "F.Cu" "F.Mask" "F.Paste")
			(net "PSU1_PS_KILL")
		)
		(pad "2" smd rect
			(at -0.40005 0)
			(size 0.4572 0.508)
			(layers "F.Cu" "F.Mask" "F.Paste")
			(net "P12V_STBY")
		)
	)
	(footprint ""
		(layer "F.Cu")
		(at 27.334718 -196.234304 90)
		(property "Reference" "R121"
			(at -3.838194 0.013462 90)
			(unlocked yes)
			(layer "F.SilkS")
			(effects
				(font
					(size 0.7874 0.5842)
					(thickness 0.1524)
				)
				(justify left)
			)
		)
		(property "Value" ""
			(at 0 0 90)
			(layer "F.Fab")
			(effects
				(font
					(size 1.27 1.27)
				)
			)
		)
		(duplicate_pad_numbers_are_jumpers no)
		(fp_line
			(start 0.7874 -0.4064)
			(end 0.7874 0.4064)
			(stroke
				(width 0.1524)
				(type default)
			)
			(layer "F.SilkS")
		)
		(fp_line
			(start -0.7874 -0.4064)
			(end 0.7874 -0.4064)
			(stroke
				(width 0.1524)
				(type default)
			)
			(layer "F.SilkS")
		)
		(fp_line
			(start 0.7874 0.4064)
			(end -0.7874 0.4064)
			(stroke
				(width 0.1524)
				(type default)
			)
			(layer "F.SilkS")
		)
		(fp_line
			(start -0.7874 0.4064)
			(end -0.7874 -0.4064)
			(stroke
				(width 0.1524)
				(type default)
			)
			(layer "F.SilkS")
		)
		(fp_poly
			(pts
				(xy -0.508 0.2794) (xy -0.508 0.2286) (xy -0.635 0.2286) (xy -0.635 -0.254) (xy -0.5334 -0.254)
				(xy -0.5334 -0.2794) (xy 0.5334 -0.2794) (xy 0.5334 -0.254) (xy 0.635 -0.254) (xy 0.635 0.254) (xy 0.5334 0.254)
				(xy 0.5334 0.2794)
			)
			(stroke
				(width 0)
				(type default)
			)
			(fill no)
			(layer "F.CrtYd")
		)
		(pad "1" smd rect
			(at 0.40005 0 90)
			(size 0.4572 0.508)
			(layers "F.Cu" "F.Mask" "F.Paste")
			(net "PSU3_REMOTE_N")
		)
		(pad "2" smd rect
			(at -0.40005 0 90)
			(size 0.4572 0.508)
			(layers "F.Cu" "F.Mask" "F.Paste")
			(net "PSU3_REMOTE_R2_N")
		)
	)
	(footprint ""
		(layer "F.Cu")
		(at 25.857708 -366.710722)
		(property "Reference" "R58"
			(at -3.917442 -0.225298 0)
			(unlocked yes)
			(layer "F.SilkS")
			(effects
				(font
					(size 0.7874 0.5842)
					(thickness 0.1524)
				)
				(justify left)
			)
		)
		(property "Value" ""
			(at 0 0 0)
			(layer "F.Fab")
			(effects
				(font
					(size 1.27 1.27)
				)
			)
		)
		(duplicate_pad_numbers_are_jumpers no)
		(fp_line
			(start -0.7874 -0.4064)
			(end 0.7874 -0.4064)
			(stroke
				(width 0.1524)
				(type default)
			)
			(layer "F.SilkS")
		)
		(fp_line
			(start -0.7874 0.4064)
			(end -0.7874 -0.4064)
			(stroke
				(width 0.1524)
				(type default)
			)
			(layer "F.SilkS")
		)
		(fp_line
			(start 0.7874 -0.4064)
			(end 0.7874 0.4064)
			(stroke
				(width 0.1524)
				(type default)
			)
			(layer "F.SilkS")
		)
		(fp_line
			(start 0.7874 0.4064)
			(end -0.7874 0.4064)
			(stroke
				(width 0.1524)
				(type default)
			)
			(layer "F.SilkS")
		)
		(fp_poly
			(pts
				(xy -0.508 0.2794) (xy -0.508 0.2286) (xy -0.635 0.2286) (xy -0.635 -0.254) (xy -0.5334 -0.254)
				(xy -0.5334 -0.2794) (xy 0.5334 -0.2794) (xy 0.5334 -0.254) (xy 0.635 -0.254) (xy 0.635 0.254) (xy 0.5334 0.254)
				(xy 0.5334 0.2794)
			)
			(stroke
				(width 0)
				(type default)
			)
			(fill no)
			(layer "F.CrtYd")
		)
		(pad "1" smd rect
			(at 0.40005 0)
			(size 0.4572 0.508)
			(layers "F.Cu" "F.Mask" "F.Paste")
			(net "PSU5_PS_KILL")
		)
		(pad "2" smd rect
			(at -0.40005 0)
			(size 0.4572 0.508)
			(layers "F.Cu" "F.Mask" "F.Paste")
			(net "GND")
		)
	)
	(footprint ""
		(layer "F.Cu")
		(at 68.607686 -175.945546 90)
		(property "Reference" "C35"
			(at -4.082034 0.060706 90)
			(unlocked yes)
			(layer "F.SilkS")
			(effects
				(font
					(size 0.7874 0.5842)
					(thickness 0.1524)
				)
				(justify left)
			)
		)
		(property "Value" ""
			(at 0 0 90)
			(layer "F.Fab")
			(effects
				(font
					(size 1.27 1.27)
				)
			)
		)
		(duplicate_pad_numbers_are_jumpers no)
		(fp_line
			(start 0.7874 -0.4064)
			(end 0.7874 0.4064)
			(stroke
				(width 0.1524)
				(type default)
			)
			(layer "F.SilkS")
		)
		(fp_line
			(start -0.7874 -0.4064)
			(end 0.7874 -0.4064)
			(stroke
				(width 0.1524)
				(type default)
			)
			(layer "F.SilkS")
		)
		(fp_line
			(start 0 0.381)
			(end 0 -0.381)
			(stroke
				(width 0.1524)
				(type default)
			)
			(layer "F.SilkS")
		)
		(fp_line
			(start 0.7874 0.4064)
			(end -0.7874 0.4064)
			(stroke
				(width 0.1524)
				(type default)
			)
			(layer "F.SilkS")
		)
		(fp_line
			(start -0.7874 0.4064)
			(end -0.7874 -0.4064)
			(stroke
				(width 0.1524)
				(type default)
			)
			(layer "F.SilkS")
		)
		(fp_poly
			(pts
				(xy -0.5334 0.254) (xy -0.635 0.254) (xy -0.635 0.2286) (xy -0.635 -0.254) (xy -0.5334 -0.254) (xy -0.5334 -0.2794)
				(xy 0.5334 -0.2794) (xy 0.5334 -0.254) (xy 0.635 -0.254) (xy 0.635 0.254) (xy 0.5334 0.254) (xy 0.5334 0.2794)
				(xy -0.508 0.2794) (xy -0.5334 0.2794)
			)
			(stroke
				(width 0)
				(type default)
			)
			(fill no)
			(layer "F.CrtYd")
		)
		(pad "1" smd rect
			(at 0.40005 0 90)
			(size 0.4572 0.508)
			(layers "F.Cu" "F.Mask" "F.Paste")
			(net "P12V")
		)
		(pad "2" smd rect
			(at -0.40005 0 90)
			(size 0.4572 0.508)
			(layers "F.Cu" "F.Mask" "F.Paste")
			(net "GND")
		)
	)
	(footprint ""
		(layer "F.Cu")
		(at 26.732484 -456.748896)
		(property "Reference" "R139"
			(at -3.883914 0.13208 0)
			(unlocked yes)
			(layer "F.SilkS")
			(effects
				(font
					(size 0.7874 0.5842)
					(thickness 0.1524)
				)
				(justify left)
			)
		)
		(property "Value" ""
			(at 0 0 0)
			(layer "F.Fab")
			(effects
				(font
					(size 1.27 1.27)
				)
			)
		)
		(duplicate_pad_numbers_are_jumpers no)
		(fp_line
			(start -0.7874 -0.4064)
			(end 0.7874 -0.4064)
			(stroke
				(width 0.1524)
				(type default)
			)
			(layer "F.SilkS")
		)
		(fp_line
			(start -0.7874 0.4064)
			(end -0.7874 -0.4064)
			(stroke
				(width 0.1524)
				(type default)
			)
			(layer "F.SilkS")
		)
		(fp_line
			(start 0.7874 -0.4064)
			(end 0.7874 0.4064)
			(stroke
				(width 0.1524)
				(type default)
			)
			(layer "F.SilkS")
		)
		(fp_line
			(start 0.7874 0.4064)
			(end -0.7874 0.4064)
			(stroke
				(width 0.1524)
				(type default)
			)
			(layer "F.SilkS")
		)
		(fp_poly
			(pts
				(xy -0.508 0.2794) (xy -0.508 0.2286) (xy -0.635 0.2286) (xy -0.635 -0.254) (xy -0.5334 -0.254)
				(xy -0.5334 -0.2794) (xy 0.5334 -0.2794) (xy 0.5334 -0.254) (xy 0.635 -0.254) (xy 0.635 0.254) (xy 0.5334 0.254)
				(xy 0.5334 0.2794)
			)
			(stroke
				(width 0)
				(type default)
			)
			(fill no)
			(layer "F.CrtYd")
		)
		(pad "1" smd rect
			(at 0.40005 0)
			(size 0.4572 0.508)
			(layers "F.Cu" "F.Mask" "F.Paste")
			(net "PSU6_CSAHRE")
		)
		(pad "2" smd rect
			(at -0.40005 0)
			(size 0.4572 0.508)
			(layers "F.Cu" "F.Mask" "F.Paste")
			(net "PSU_CSAHRE")
		)
	)
	(footprint ""
		(layer "F.Cu")
		(at 91.399868 -331.16012)
		(property "Reference" "H26"
			(at -5.1308 -5.23113 0)
			(unlocked yes)
			(layer "F.SilkS")
			(effects
				(font
					(size 0.7874 0.5842)
					(thickness 0.1524)
				)
				(justify left)
			)
		)
		(property "Value" ""
			(at 0 0 0)
			(layer "F.Fab")
			(effects
				(font
					(size 1.27 1.27)
				)
			)
		)
		(duplicate_pad_numbers_are_jumpers no)
		(fp_circle
			(center 0 0)
			(end 4.826 0)
			(stroke
				(width 0.1524)
				(type default)
			)
			(fill no)
			(layer "F.SilkS")
		)
		(fp_circle
			(center 0 0)
			(end 4.826 0)
			(stroke
				(width 0.1524)
				(type default)
			)
			(fill no)
			(layer "B.SilkS")
		)
		(fp_poly
			(pts
				(arc
					(start 0 4.0132)
					(mid 0 -4.0132)
					(end 0 4.0132)
				)
			)
			(stroke
				(width 0)
				(type default)
			)
			(fill no)
			(layer "F.CrtYd")
		)
		(pad "" np_thru_hole circle
			(at 0 0)
			(size 8.001 8.001)
			(drill 8.001)
			(layers "*.Cu" "*.Mask")
			(clearance 0.381)
			(thermal_gap 0.381)
		)
		(zone
			(layers "F.Cu" "B.Cu" "In1.Cu" "In2.Cu" "In3.Cu" "In4.Cu" "In5.Cu" "In6.Cu")
			(hatch none 0.5)
			(connect_pads
				(clearance 0)
			)
			(min_thickness 0.25)
			(keepout
				(tracks not_allowed)
				(vias allowed)
				(pads allowed)
				(copperpour not_allowed)
				(footprints allowed)
			)
			(placement
				(enabled no)
				(sheetname "")
			)
			(fill
				(thermal_gap 0.5)
				(thermal_bridge_width 0.5)
				(island_removal_mode 0)
			)
			(polygon
				(pts
					(arc
						(start 91.399868 -326.63892)
						(mid 91.399868 -335.68132)
						(end 91.399868 -326.63892)
					)
				)
			)
		)
	)
	(footprint ""
		(layer "F.Cu")
		(at 26.068274 -187.950348)
		(property "Reference" "R71"
			(at -3.997198 0.128524 0)
			(unlocked yes)
			(layer "F.SilkS")
			(effects
				(font
					(size 0.7874 0.5842)
					(thickness 0.1524)
				)
				(justify left)
			)
		)
		(property "Value" ""
			(at 0 0 0)
			(layer "F.Fab")
			(effects
				(font
					(size 1.27 1.27)
				)
			)
		)
		(duplicate_pad_numbers_are_jumpers no)
		(fp_line
			(start -0.7874 -0.4064)
			(end 0.7874 -0.4064)
			(stroke
				(width 0.1524)
				(type default)
			)
			(layer "F.SilkS")
		)
		(fp_line
			(start -0.7874 0.4064)
			(end -0.7874 -0.4064)
			(stroke
				(width 0.1524)
				(type default)
			)
			(layer "F.SilkS")
		)
		(fp_line
			(start 0.7874 -0.4064)
			(end 0.7874 0.4064)
			(stroke
				(width 0.1524)
				(type default)
			)
			(layer "F.SilkS")
		)
		(fp_line
			(start 0.7874 0.4064)
			(end -0.7874 0.4064)
			(stroke
				(width 0.1524)
				(type default)
			)
			(layer "F.SilkS")
		)
		(fp_poly
			(pts
				(xy -0.508 0.2794) (xy -0.508 0.2286) (xy -0.635 0.2286) (xy -0.635 -0.254) (xy -0.5334 -0.254)
				(xy -0.5334 -0.2794) (xy 0.5334 -0.2794) (xy 0.5334 -0.254) (xy 0.635 -0.254) (xy 0.635 0.254) (xy 0.5334 0.254)
				(xy 0.5334 0.2794)
			)
			(stroke
				(width 0)
				(type default)
			)
			(fill no)
			(layer "F.CrtYd")
		)
		(pad "1" smd rect
			(at 0.40005 0)
			(size 0.4572 0.508)
			(layers "F.Cu" "F.Mask" "F.Paste")
			(net "PSU3_PS_KILL")
		)
		(pad "2" smd rect
			(at -0.40005 0)
			(size 0.4572 0.508)
			(layers "F.Cu" "F.Mask" "F.Paste")
			(net "GND")
		)
	)
	(footprint ""
		(layer "F.Cu")
		(at 68.727066 -354.308664 90)
		(property "Reference" "C63"
			(at -3.889502 0.089662 90)
			(unlocked yes)
			(layer "F.SilkS")
			(effects
				(font
					(size 0.7874 0.5842)
					(thickness 0.1524)
				)
				(justify left)
			)
		)
		(property "Value" ""
			(at 0 0 90)
			(layer "F.Fab")
			(effects
				(font
					(size 1.27 1.27)
				)
			)
		)
		(duplicate_pad_numbers_are_jumpers no)
		(fp_line
			(start 0.7874 -0.4064)
			(end 0.7874 0.4064)
			(stroke
				(width 0.1524)
				(type default)
			)
			(layer "F.SilkS")
		)
		(fp_line
			(start -0.7874 -0.4064)
			(end 0.7874 -0.4064)
			(stroke
				(width 0.1524)
				(type default)
			)
			(layer "F.SilkS")
		)
		(fp_line
			(start 0 0.381)
			(end 0 -0.381)
			(stroke
				(width 0.1524)
				(type default)
			)
			(layer "F.SilkS")
		)
		(fp_line
			(start 0.7874 0.4064)
			(end -0.7874 0.4064)
			(stroke
				(width 0.1524)
				(type default)
			)
			(layer "F.SilkS")
		)
		(fp_line
			(start -0.7874 0.4064)
			(end -0.7874 -0.4064)
			(stroke
				(width 0.1524)
				(type default)
			)
			(layer "F.SilkS")
		)
		(fp_poly
			(pts
				(xy -0.5334 0.254) (xy -0.635 0.254) (xy -0.635 0.2286) (xy -0.635 -0.254) (xy -0.5334 -0.254) (xy -0.5334 -0.2794)
				(xy 0.5334 -0.2794) (xy 0.5334 -0.254) (xy 0.635 -0.254) (xy 0.635 0.254) (xy 0.5334 0.254) (xy 0.5334 0.2794)
				(xy -0.508 0.2794) (xy -0.5334 0.2794)
			)
			(stroke
				(width 0)
				(type default)
			)
			(fill no)
			(layer "F.CrtYd")
		)
		(pad "1" smd rect
			(at 0.40005 0 90)
			(size 0.4572 0.508)
			(layers "F.Cu" "F.Mask" "F.Paste")
			(net "P12V")
		)
		(pad "2" smd rect
			(at -0.40005 0 90)
			(size 0.4572 0.508)
			(layers "F.Cu" "F.Mask" "F.Paste")
			(net "GND")
		)
	)
	(footprint ""
		(layer "F.Cu")
		(at 71.044562 -442.84646 90)
		(property "Reference" "C76"
			(at -3.873246 0.134112 90)
			(unlocked yes)
			(layer "F.SilkS")
			(effects
				(font
					(size 0.7874 0.5842)
					(thickness 0.1524)
				)
				(justify left)
			)
		)
		(property "Value" ""
			(at 0 0 90)
			(layer "F.Fab")
			(effects
				(font
					(size 1.27 1.27)
				)
			)
		)
		(duplicate_pad_numbers_are_jumpers no)
		(fp_line
			(start 0.7874 -0.4064)
			(end 0.7874 0.4064)
			(stroke
				(width 0.1524)
				(type default)
			)
			(layer "F.SilkS")
		)
		(fp_line
			(start -0.7874 -0.4064)
			(end 0.7874 -0.4064)
			(stroke
				(width 0.1524)
				(type default)
			)
			(layer "F.SilkS")
		)
		(fp_line
			(start 0 0.381)
			(end 0 -0.381)
			(stroke
				(width 0.1524)
				(type default)
			)
			(layer "F.SilkS")
		)
		(fp_line
			(start 0.7874 0.4064)
			(end -0.7874 0.4064)
			(stroke
				(width 0.1524)
				(type default)
			)
			(layer "F.SilkS")
		)
		(fp_line
			(start -0.7874 0.4064)
			(end -0.7874 -0.4064)
			(stroke
				(width 0.1524)
				(type default)
			)
			(layer "F.SilkS")
		)
		(fp_poly
			(pts
				(xy -0.5334 0.254) (xy -0.635 0.254) (xy -0.635 0.2286) (xy -0.635 -0.254) (xy -0.5334 -0.254) (xy -0.5334 -0.2794)
				(xy 0.5334 -0.2794) (xy 0.5334 -0.254) (xy 0.635 -0.254) (xy 0.635 0.254) (xy 0.5334 0.254) (xy 0.5334 0.2794)
				(xy -0.508 0.2794) (xy -0.5334 0.2794)
			)
			(stroke
				(width 0)
				(type default)
			)
			(fill no)
			(layer "F.CrtYd")
		)
		(pad "1" smd rect
			(at 0.40005 0 90)
			(size 0.4572 0.508)
			(layers "F.Cu" "F.Mask" "F.Paste")
			(net "P12V")
		)
		(pad "2" smd rect
			(at -0.40005 0 90)
			(size 0.4572 0.508)
			(layers "F.Cu" "F.Mask" "F.Paste")
			(net "GND")
		)
	)
	(footprint ""
		(layer "F.Cu")
		(at 39.936674 -464.36915 180)
		(property "Reference" "R17"
			(at -1.699514 0.166624 0)
			(unlocked yes)
			(layer "F.SilkS")
			(effects
				(font
					(size 0.7874 0.5842)
					(thickness 0.1524)
				)
				(justify left)
			)
		)
		(property "Value" ""
			(at 0 0 180)
			(layer "F.Fab")
			(effects
				(font
					(size 1.27 1.27)
				)
			)
		)
		(duplicate_pad_numbers_are_jumpers no)
		(fp_line
			(start 0.7874 0.4064)
			(end -0.7874 0.4064)
			(stroke
				(width 0.1524)
				(type default)
			)
			(layer "F.SilkS")
		)
		(fp_line
			(start 0.7874 -0.4064)
			(end 0.7874 0.4064)
			(stroke
				(width 0.1524)
				(type default)
			)
			(layer "F.SilkS")
		)
		(fp_line
			(start -0.7874 0.4064)
			(end -0.7874 -0.4064)
			(stroke
				(width 0.1524)
				(type default)
			)
			(layer "F.SilkS")
		)
		(fp_line
			(start -0.7874 -0.4064)
			(end 0.7874 -0.4064)
			(stroke
				(width 0.1524)
				(type default)
			)
			(layer "F.SilkS")
		)
		(fp_poly
			(pts
				(xy -0.508 0.2794) (xy -0.508 0.2286) (xy -0.635 0.2286) (xy -0.635 -0.254) (xy -0.5334 -0.254)
				(xy -0.5334 -0.2794) (xy 0.5334 -0.2794) (xy 0.5334 -0.254) (xy 0.635 -0.254) (xy 0.635 0.254) (xy 0.5334 0.254)
				(xy 0.5334 0.2794)
			)
			(stroke
				(width 0)
				(type default)
			)
			(fill no)
			(layer "F.CrtYd")
		)
		(pad "1" smd rect
			(at 0.40005 0 180)
			(size 0.4572 0.508)
			(layers "F.Cu" "F.Mask" "F.Paste")
			(net "PSU6_REMOTE_P")
		)
		(pad "2" smd rect
			(at -0.40005 0 180)
			(size 0.4572 0.508)
			(layers "F.Cu" "F.Mask" "F.Paste")
			(net "P12V")
		)
	)
	(footprint ""
		(layer "F.Cu")
		(at 49.873662 -374.437148 180)
		(property "Reference" "CE17"
			(at -5.288534 -1.081024 0)
			(unlocked yes)
			(layer "F.SilkS")
			(effects
				(font
					(size 0.7874 0.5842)
					(thickness 0.1524)
				)
				(justify left)
			)
		)
		(property "Value" ""
			(at 0 0 180)
			(layer "F.Fab")
			(effects
				(font
					(size 1.27 1.27)
				)
			)
		)
		(duplicate_pad_numbers_are_jumpers no)
		(fp_line
			(start 0 -4.2672)
			(end 0 4.2672)
			(stroke
				(width 0.1524)
				(type default)
			)
			(layer "F.SilkS")
		)
		(fp_circle
			(center 0 0)
			(end -4.2672 0)
			(stroke
				(width 0.1524)
				(type default)
			)
			(fill no)
			(layer "F.SilkS")
		)
		(fp_poly
			(pts
				(arc
					(start 0 -4.2672)
					(mid 4.2672 0)
					(end 0 4.2672)
				)
			)
			(stroke
				(width 0)
				(type default)
			)
			(fill yes)
			(layer "F.SilkS")
		)
		(fp_poly
			(pts
				(xy -2.5146 -0.762) (xy -0.9906 -0.762) (xy -0.9906 0.762) (xy -2.5146 0.762)
			)
			(stroke
				(width 0)
				(type default)
			)
			(fill no)
			(layer "B.CrtYd")
		)
		(fp_poly
			(pts
				(arc
					(start 1.7526 0.762)
					(mid 2.291415 -0.538815)
					(end 0.9906 0)
				)
				(arc
					(start 0.9906 0.0254)
					(mid 1.206345 0.546255)
					(end 1.7272 0.762)
				)
			)
			(stroke
				(width 0)
				(type default)
			)
			(fill no)
			(layer "B.CrtYd")
		)
		(fp_poly
			(pts
				(arc
					(start -4.2672 0)
					(mid 4.2672 0)
					(end -4.2672 0)
				)
			)
			(stroke
				(width 0)
				(type default)
			)
			(fill no)
			(layer "F.CrtYd")
		)
		(fp_circle
			(center 0 0)
			(end -4.2672 0)
			(stroke
				(width 0.1)
				(type default)
			)
			(fill no)
			(layer "F.Fab")
		)
		(fp_text user "+"
			(at -4.943602 1.518412 180)
			(unlocked yes)
			(layer "F.SilkS")
			(effects
				(font
					(size 0.7874 0.5842)
					(thickness 0.1524)
				)
				(justify left)
			)
		)
		(fp_text user "+"
			(at -5.6642 -0.34925 180)
			(unlocked yes)
			(layer "F.Fab")
			(effects
				(font
					(size 1.905 1.4224)
					(thickness 0.000001)
				)
				(justify left)
			)
		)
		(pad "1" thru_hole rect
			(at -1.75006 0 180)
			(size 1.397 1.397)
			(drill 0.9144)
			(layers "*.Cu" "*.Mask")
			(remove_unused_layers no)
			(net "P12V")
			(clearance 0.0127)
			(thermal_gap 0.0127)
			(padstack
				(mode front_inner_back)
				(layer "Inner"
					(shape circle)
					(size 1.397 1.397)
					(clearance 0.0127)
				)
				(layer "B.Cu"
					(shape rect)
					(size 1.397 1.397)
					(clearance 0.0127)
				)
			)
		)
		(pad "2" thru_hole circle
			(at 1.75006 0 180)
			(size 1.397 1.397)
			(drill 0.9144)
			(layers "*.Cu" "*.Mask")
			(remove_unused_layers no)
			(net "GND")
			(clearance 0.0127)
			(thermal_gap 0.0127)
		)
	)
	(footprint ""
		(layer "F.Cu")
		(at 13.39469 -8.878062 180)
		(property "Reference" "J19"
			(at 6.82117 14.260576 0)
			(unlocked yes)
			(layer "F.SilkS")
			(effects
				(font
					(size 0.7874 0.5842)
					(thickness 0.1524)
				)
				(justify left)
			)
		)
		(property "Value" ""
			(at 0 0 180)
			(layer "F.Fab")
			(effects
				(font
					(size 1.27 1.27)
				)
			)
		)
		(duplicate_pad_numbers_are_jumpers no)
		(fp_line
			(start 12.260072 12.830048)
			(end -3.370072 12.830048)
			(stroke
				(width 0.1524)
				(type default)
			)
			(layer "F.SilkS")
		)
		(fp_line
			(start 12.260072 -3.81)
			(end 12.260072 12.830048)
			(stroke
				(width 0.1524)
				(type default)
			)
			(layer "F.SilkS")
		)
		(fp_line
			(start -3.370072 12.830048)
			(end -3.370072 -3.81)
			(stroke
				(width 0.1524)
				(type default)
			)
			(layer "F.SilkS")
		)
		(fp_line
			(start -3.370072 -3.81)
			(end 12.260072 -3.81)
			(stroke
				(width 0.1524)
				(type default)
			)
			(layer "F.SilkS")
		)
		(fp_poly
			(pts
				(xy -3.576828 0) (xy -5.0038 0.713486) (xy -5.0038 -0.713486)
			)
			(stroke
				(width 0)
				(type default)
			)
			(fill yes)
			(layer "F.SilkS")
		)
		(fp_poly
			(pts
				(xy -0.762 0.762) (xy 8.382 0.762) (xy 8.382 -1.8034) (xy 9.652 -1.8034) (xy 9.652 -3.302) (xy 0.508 -3.302)
				(xy 0.508 -0.762) (xy -0.762 -0.762)
			)
			(stroke
				(width 0)
				(type default)
			)
			(fill no)
			(layer "B.CrtYd")
		)
		(fp_poly
			(pts
				(arc
					(start 8.2296 6.35)
					(mid 12.0904 6.35)
					(end 8.2296 6.35)
				)
			)
			(stroke
				(width 0)
				(type default)
			)
			(fill no)
			(layer "B.CrtYd")
		)
		(fp_poly
			(pts
				(arc
					(start -3.2004 6.35)
					(mid 0.6604 6.35)
					(end -3.2004 6.35)
				)
			)
			(stroke
				(width 0)
				(type default)
			)
			(fill no)
			(layer "B.CrtYd")
		)
		(fp_poly
			(pts
				(xy -3.370072 12.830048) (xy 12.260072 12.830048) (xy 12.260072 -3.81) (xy -3.370072 -3.81)
			)
			(stroke
				(width 0)
				(type default)
			)
			(fill no)
			(layer "F.CrtYd")
		)
		(fp_line
			(start 12.260072 12.830048)
			(end -3.370072 12.830048)
			(stroke
				(width 0.1)
				(type default)
			)
			(layer "F.Fab")
		)
		(fp_line
			(start 12.260072 -3.81)
			(end 12.260072 12.830048)
			(stroke
				(width 0.1)
				(type default)
			)
			(layer "F.Fab")
		)
		(fp_line
			(start -3.370072 12.830048)
			(end -3.370072 -3.81)
			(stroke
				(width 0.1)
				(type default)
			)
			(layer "F.Fab")
		)
		(fp_line
			(start -3.370072 -3.81)
			(end 12.260072 -3.81)
			(stroke
				(width 0.1)
				(type default)
			)
			(layer "F.Fab")
		)
		(fp_poly
			(pts
				(xy -3.576828 0) (xy -5.0038 0.713486) (xy -5.0038 -0.713486)
			)
			(stroke
				(width 0)
				(type default)
			)
			(fill yes)
			(layer "F.Fab")
		)
		(fp_text user "7"
			(at 12.7762 0.249174 0)
			(unlocked yes)
			(layer "F.SilkS")
			(effects
				(font
					(size 0.7874 0.5842)
					(thickness 0.1524)
				)
			)
		)
		(fp_text user "8"
			(at 12.7762 -2.214626 0)
			(unlocked yes)
			(layer "F.SilkS")
			(effects
				(font
					(size 0.7874 0.5842)
					(thickness 0.1524)
				)
			)
		)
		(fp_text user "1"
			(at -3.878072 -0.92329 0)
			(unlocked yes)
			(layer "F.SilkS")
			(effects
				(font
					(size 0.7874 0.5842)
					(thickness 0.1524)
				)
			)
		)
		(fp_text user "2"
			(at -3.928872 -2.42189 0)
			(unlocked yes)
			(layer "F.SilkS")
			(effects
				(font
					(size 0.7874 0.5842)
					(thickness 0.1524)
				)
			)
		)
		(fp_text user "8"
			(at 10.050526 -2.129028 0)
			(unlocked yes)
			(layer "B.SilkS")
			(effects
				(font
					(size 0.7874 0.5842)
					(thickness 0.1524)
				)
				(justify mirror)
			)
		)
		(fp_text user "7"
			(at 8.780526 0.512572 0)
			(unlocked yes)
			(layer "B.SilkS")
			(effects
				(font
					(size 0.7874 0.5842)
					(thickness 0.1524)
				)
				(justify mirror)
			)
		)
		(fp_text user "2"
			(at -0.033274 -2.306828 0)
			(unlocked yes)
			(layer "B.SilkS")
			(effects
				(font
					(size 0.7874 0.5842)
					(thickness 0.1524)
				)
				(justify mirror)
			)
		)
		(fp_text user "1"
			(at -1.328674 0.360172 0)
			(unlocked yes)
			(layer "B.SilkS")
			(effects
				(font
					(size 0.7874 0.5842)
					(thickness 0.1524)
				)
				(justify mirror)
			)
		)
		(fp_text user "8"
			(at 10.0838 -2.403348 180)
			(unlocked yes)
			(layer "B.Fab")
			(effects
				(font
					(size 0.7874 0.5842)
					(thickness 0.000001)
				)
				(justify mirror)
			)
		)
		(fp_text user "7"
			(at 8.8138 0.238252 180)
			(unlocked yes)
			(layer "B.Fab")
			(effects
				(font
					(size 0.7874 0.5842)
					(thickness 0.000001)
				)
				(justify mirror)
			)
		)
		(fp_text user "2"
			(at 0 -2.581148 180)
			(unlocked yes)
			(layer "B.Fab")
			(effects
				(font
					(size 0.7874 0.5842)
					(thickness 0.000001)
				)
				(justify mirror)
			)
		)
		(fp_text user "1"
			(at -1.2954 0.085852 180)
			(unlocked yes)
			(layer "B.Fab")
			(effects
				(font
					(size 0.7874 0.5842)
					(thickness 0.000001)
				)
				(justify mirror)
			)
		)
		(fp_text user "7"
			(at 12.7762 -0.091948 180)
			(unlocked yes)
			(layer "F.Fab")
			(effects
				(font
					(size 0.7874 0.5842)
					(thickness 0.000001)
				)
			)
		)
		(fp_text user "8"
			(at 12.7762 -2.555748 180)
			(unlocked yes)
			(layer "F.Fab")
			(effects
				(font
					(size 0.7874 0.5842)
					(thickness 0.000001)
				)
			)
		)
		(fp_text user "1"
			(at -3.9116 -0.930148 180)
			(unlocked yes)
			(layer "F.Fab")
			(effects
				(font
					(size 0.7874 0.5842)
					(thickness 0.000001)
				)
			)
		)
		(fp_text user "2"
			(at -3.9624 -2.428748 180)
			(unlocked yes)
			(layer "F.Fab")
			(effects
				(font
					(size 0.7874 0.5842)
					(thickness 0.000001)
				)
			)
		)
		(pad "" np_thru_hole circle
			(at -1.27 6.35 180)
			(size 3.3528 3.3528)
			(drill 3.3528)
			(layers "*.Cu" "*.Mask")
			(clearance 0.381)
			(thermal_gap 0.381)
		)
		(pad "" np_thru_hole circle
			(at 10.16 6.35 180)
			(size 3.3528 3.3528)
			(drill 3.3528)
			(layers "*.Cu" "*.Mask")
			(clearance 0.381)
			(thermal_gap 0.381)
		)
		(pad "1" thru_hole rect
			(at 0 0 180)
			(size 1.397 1.397)
			(drill 0.9906)
			(layers "*.Cu" "*.Mask")
			(remove_unused_layers no)
			(net "UART_RTS_P1_L_N")
			(clearance 0.0508)
			(thermal_gap 0.0508)
			(padstack
				(mode front_inner_back)
				(layer "Inner"
					(shape circle)
					(size 1.397 1.397)
					(clearance 0.0508)
				)
				(layer "B.Cu"
					(shape rect)
					(size 1.397 1.397)
					(clearance 0.0508)
				)
			)
		)
		(pad "2" thru_hole circle
			(at 1.27 -2.54 180)
			(size 1.397 1.397)
			(drill 0.9906)
			(layers "*.Cu" "*.Mask")
			(remove_unused_layers no)
			(net "UART_DSR_P1_L_N")
			(clearance 0.0508)
			(thermal_gap 0.0508)
		)
		(pad "3" thru_hole circle
			(at 2.54 0 180)
			(size 1.397 1.397)
			(drill 0.9906)
			(layers "*.Cu" "*.Mask")
			(remove_unused_layers no)
			(net "UART_RX_P1_L")
			(clearance 0.0508)
			(thermal_gap 0.0508)
		)
		(pad "4" thru_hole circle
			(at 3.81 -2.54 180)
			(size 1.397 1.397)
			(drill 0.9906)
			(layers "*.Cu" "*.Mask")
			(remove_unused_layers no)
			(net "GND")
			(clearance 0.0508)
			(thermal_gap 0.0508)
		)
		(pad "5" thru_hole circle
			(at 5.08 0 180)
			(size 1.397 1.397)
			(drill 0.9906)
			(layers "*.Cu" "*.Mask")
			(remove_unused_layers no)
			(net "GND")
			(clearance 0.0508)
			(thermal_gap 0.0508)
		)
		(pad "6" thru_hole circle
			(at 6.35 -2.54 180)
			(size 1.397 1.397)
			(drill 0.9906)
			(layers "*.Cu" "*.Mask")
			(remove_unused_layers no)
			(net "UART_TX_P1_L")
			(clearance 0.0508)
			(thermal_gap 0.0508)
		)
		(pad "7" thru_hole circle
			(at 7.62 0 180)
			(size 1.397 1.397)
			(drill 0.9906)
			(layers "*.Cu" "*.Mask")
			(remove_unused_layers no)
			(net "UART_DTR_P1_L_N")
			(clearance 0.0508)
			(thermal_gap 0.0508)
		)
		(pad "8" thru_hole circle
			(at 8.89 -2.54 180)
			(size 1.397 1.397)
			(drill 0.9906)
			(layers "*.Cu" "*.Mask")
			(remove_unused_layers no)
			(net "UART_CTS_P1_L_N")
			(clearance 0.0508)
			(thermal_gap 0.0508)
		)
		(zone
			(layers "F.Cu" "B.Cu" "In1.Cu" "In2.Cu" "In3.Cu" "In4.Cu" "In5.Cu" "In6.Cu")
			(hatch none 0.5)
			(connect_pads
				(clearance 0)
			)
			(min_thickness 0.25)
			(keepout
				(tracks not_allowed)
				(vias allowed)
				(pads allowed)
				(copperpour not_allowed)
				(footprints allowed)
			)
			(placement
				(enabled no)
				(sheetname "")
			)
			(fill
				(thermal_gap 0.5)
				(thermal_bridge_width 0.5)
				(island_removal_mode 0)
			)
			(polygon
				(pts
					(arc
						(start 5.31749 -15.228062)
						(mid 1.15189 -15.228062)
						(end 5.31749 -15.228062)
					)
				)
			)
		)
		(zone
			(layers "F.Cu" "B.Cu" "In1.Cu" "In2.Cu" "In3.Cu" "In4.Cu" "In5.Cu" "In6.Cu")
			(hatch none 0.5)
			(connect_pads
				(clearance 0)
			)
			(min_thickness 0.25)
			(keepout
				(tracks not_allowed)
				(vias allowed)
				(pads allowed)
				(copperpour not_allowed)
				(footprints allowed)
			)
			(placement
				(enabled no)
				(sheetname "")
			)
			(fill
				(thermal_gap 0.5)
				(thermal_bridge_width 0.5)
				(island_removal_mode 0)
			)
			(polygon
				(pts
					(arc
						(start 16.74749 -15.228062)
						(mid 12.58189 -15.228062)
						(end 16.74749 -15.228062)
					)
				)
			)
		)
	)
	(footprint ""
		(layer "F.Cu")
		(at 46.385734 -244.518434 180)
		(property "Reference" "R91"
			(at 4.322064 -0.051816 0)
			(unlocked yes)
			(layer "F.SilkS")
			(effects
				(font
					(size 0.7874 0.5842)
					(thickness 0.1524)
				)
				(justify left)
			)
		)
		(property "Value" ""
			(at 0 0 180)
			(layer "F.Fab")
			(effects
				(font
					(size 1.27 1.27)
				)
			)
		)
		(duplicate_pad_numbers_are_jumpers no)
		(fp_line
			(start 0.7874 0.4064)
			(end -0.7874 0.4064)
			(stroke
				(width 0.1524)
				(type default)
			)
			(layer "F.SilkS")
		)
		(fp_line
			(start 0.7874 -0.4064)
			(end 0.7874 0.4064)
			(stroke
				(width 0.1524)
				(type default)
			)
			(layer "F.SilkS")
		)
		(fp_line
			(start -0.7874 0.4064)
			(end -0.7874 -0.4064)
			(stroke
				(width 0.1524)
				(type default)
			)
			(layer "F.SilkS")
		)
		(fp_line
			(start -0.7874 -0.4064)
			(end 0.7874 -0.4064)
			(stroke
				(width 0.1524)
				(type default)
			)
			(layer "F.SilkS")
		)
		(fp_poly
			(pts
				(xy -0.508 0.2794) (xy -0.508 0.2286) (xy -0.635 0.2286) (xy -0.635 -0.254) (xy -0.5334 -0.254)
				(xy -0.5334 -0.2794) (xy 0.5334 -0.2794) (xy 0.5334 -0.254) (xy 0.635 -0.254) (xy 0.635 0.254) (xy 0.5334 0.254)
				(xy 0.5334 0.2794)
			)
			(stroke
				(width 0)
				(type default)
			)
			(fill no)
			(layer "F.CrtYd")
		)
		(pad "1" smd rect
			(at 0.40005 0 180)
			(size 0.4572 0.508)
			(layers "F.Cu" "F.Mask" "F.Paste")
			(net "PSU2_REMOTE_R_N")
		)
		(pad "2" smd rect
			(at -0.40005 0 180)
			(size 0.4572 0.508)
			(layers "F.Cu" "F.Mask" "F.Paste")
			(net "GND")
		)
	)
	(footprint ""
		(layer "F.Cu")
		(at 77.999844 -78.299818)
		(property "Reference" "H14"
			(at -3.678174 -4.056888 0)
			(unlocked yes)
			(layer "F.SilkS")
			(effects
				(font
					(size 0.7874 0.5842)
					(thickness 0.1524)
				)
				(justify left)
			)
		)
		(property "Value" ""
			(at 0 0 0)
			(layer "F.Fab")
			(effects
				(font
					(size 1.27 1.27)
				)
			)
		)
		(duplicate_pad_numbers_are_jumpers no)
		(fp_circle
			(center 0 0)
			(end 3.4163 0)
			(stroke
				(width 0.1524)
				(type default)
			)
			(fill no)
			(layer "F.SilkS")
		)
		(fp_circle
			(center 0 0)
			(end 3.41884 0)
			(stroke
				(width 0.1524)
				(type default)
			)
			(fill no)
			(layer "B.SilkS")
		)
		(fp_poly
			(pts
				(arc
					(start 2.8575 0)
					(mid -2.8575 0)
					(end 2.8575 0)
				)
			)
			(stroke
				(width 0)
				(type default)
			)
			(fill no)
			(layer "B.CrtYd")
		)
		(fp_poly
			(pts
				(arc
					(start 2.8575 0)
					(mid -2.8575 0)
					(end 2.8575 0)
				)
			)
			(stroke
				(width 0)
				(type default)
			)
			(fill no)
			(layer "F.CrtYd")
		)
		(pad "" np_thru_hole circle
			(at 0 0)
			(size 5.207 5.207)
			(drill 5.207)
			(layers "*.Cu" "*.Mask")
			(clearance 0.381)
			(thermal_gap 0.381)
		)
		(zone
			(layers "F.Cu" "B.Cu" "In1.Cu" "In2.Cu" "In3.Cu" "In4.Cu" "In5.Cu" "In6.Cu")
			(hatch none 0.5)
			(connect_pads
				(clearance 0)
			)
			(min_thickness 0.25)
			(keepout
				(tracks not_allowed)
				(vias allowed)
				(pads allowed)
				(copperpour not_allowed)
				(footprints allowed)
			)
			(placement
				(enabled no)
				(sheetname "")
			)
			(fill
				(thermal_gap 0.5)
				(thermal_bridge_width 0.5)
				(island_removal_mode 0)
			)
			(polygon
				(pts
					(arc
						(start 81.111344 -78.299818)
						(mid 74.888344 -78.299818)
						(end 81.111344 -78.299818)
					)
				)
			)
		)
	)
	(footprint ""
		(layer "F.Cu")
		(at 26.068274 -183.06923)
		(property "Reference" "R55"
			(at -3.997198 0.128524 0)
			(unlocked yes)
			(layer "F.SilkS")
			(effects
				(font
					(size 0.7874 0.5842)
					(thickness 0.1524)
				)
				(justify left)
			)
		)
		(property "Value" ""
			(at 0 0 0)
			(layer "F.Fab")
			(effects
				(font
					(size 1.27 1.27)
				)
			)
		)
		(duplicate_pad_numbers_are_jumpers no)
		(fp_line
			(start -0.7874 -0.4064)
			(end 0.7874 -0.4064)
			(stroke
				(width 0.1524)
				(type default)
			)
			(layer "F.SilkS")
		)
		(fp_line
			(start -0.7874 0.4064)
			(end -0.7874 -0.4064)
			(stroke
				(width 0.1524)
				(type default)
			)
			(layer "F.SilkS")
		)
		(fp_line
			(start 0.7874 -0.4064)
			(end 0.7874 0.4064)
			(stroke
				(width 0.1524)
				(type default)
			)
			(layer "F.SilkS")
		)
		(fp_line
			(start 0.7874 0.4064)
			(end -0.7874 0.4064)
			(stroke
				(width 0.1524)
				(type default)
			)
			(layer "F.SilkS")
		)
		(fp_poly
			(pts
				(xy -0.508 0.2794) (xy -0.508 0.2286) (xy -0.635 0.2286) (xy -0.635 -0.254) (xy -0.5334 -0.254)
				(xy -0.5334 -0.2794) (xy 0.5334 -0.2794) (xy 0.5334 -0.254) (xy 0.635 -0.254) (xy 0.635 0.254) (xy 0.5334 0.254)
				(xy 0.5334 0.2794)
			)
			(stroke
				(width 0)
				(type default)
			)
			(fill no)
			(layer "F.CrtYd")
		)
		(pad "1" smd rect
			(at 0.40005 0)
			(size 0.4572 0.508)
			(layers "F.Cu" "F.Mask" "F.Paste")
			(net "PSU3_RESET")
		)
		(pad "2" smd rect
			(at -0.40005 0)
			(size 0.4572 0.508)
			(layers "F.Cu" "F.Mask" "F.Paste")
			(net "GND")
		)
	)
	(footprint ""
		(layer "F.Cu")
		(at 50.39868 -519.020552 180)
		(property "Reference" "CE24"
			(at 0.751586 5.701792 0)
			(unlocked yes)
			(layer "F.SilkS")
			(effects
				(font
					(size 0.7874 0.5842)
					(thickness 0.1524)
				)
				(justify left)
			)
		)
		(property "Value" ""
			(at 0 0 180)
			(layer "F.Fab")
			(effects
				(font
					(size 1.27 1.27)
				)
			)
		)
		(duplicate_pad_numbers_are_jumpers no)
		(fp_line
			(start 0 -4.2672)
			(end 0 4.2672)
			(stroke
				(width 0.1524)
				(type default)
			)
			(layer "F.SilkS")
		)
		(fp_circle
			(center 0 0)
			(end -4.2672 0)
			(stroke
				(width 0.1524)
				(type default)
			)
			(fill no)
			(layer "F.SilkS")
		)
		(fp_poly
			(pts
				(arc
					(start 0 -4.2672)
					(mid 4.2672 0)
					(end 0 4.2672)
				)
			)
			(stroke
				(width 0)
				(type default)
			)
			(fill yes)
			(layer "F.SilkS")
		)
		(fp_poly
			(pts
				(xy -2.5146 -0.762) (xy -0.9906 -0.762) (xy -0.9906 0.762) (xy -2.5146 0.762)
			)
			(stroke
				(width 0)
				(type default)
			)
			(fill no)
			(layer "B.CrtYd")
		)
		(fp_poly
			(pts
				(arc
					(start 1.7526 0.762)
					(mid 2.291415 -0.538815)
					(end 0.9906 0)
				)
				(arc
					(start 0.9906 0.0254)
					(mid 1.206345 0.546255)
					(end 1.7272 0.762)
				)
			)
			(stroke
				(width 0)
				(type default)
			)
			(fill no)
			(layer "B.CrtYd")
		)
		(fp_poly
			(pts
				(arc
					(start -4.2672 0)
					(mid 4.2672 0)
					(end -4.2672 0)
				)
			)
			(stroke
				(width 0)
				(type default)
			)
			(fill no)
			(layer "F.CrtYd")
		)
		(fp_circle
			(center 0 0)
			(end -4.2672 0)
			(stroke
				(width 0.1)
				(type default)
			)
			(fill no)
			(layer "F.Fab")
		)
		(fp_text user "+"
			(at -5.892292 -1.07823 180)
			(unlocked yes)
			(layer "F.SilkS")
			(effects
				(font
					(size 0.7874 0.5842)
					(thickness 0.1524)
				)
				(justify left)
			)
		)
		(fp_text user "+"
			(at -5.6642 -0.34925 180)
			(unlocked yes)
			(layer "F.Fab")
			(effects
				(font
					(size 1.905 1.4224)
					(thickness 0.000001)
				)
				(justify left)
			)
		)
		(pad "1" thru_hole rect
			(at -1.75006 0 180)
			(size 1.397 1.397)
			(drill 0.9144)
			(layers "*.Cu" "*.Mask")
			(remove_unused_layers no)
			(net "P12V")
			(clearance 0.0127)
			(thermal_gap 0.0127)
			(padstack
				(mode front_inner_back)
				(layer "Inner"
					(shape circle)
					(size 1.397 1.397)
					(clearance 0.0127)
				)
				(layer "B.Cu"
					(shape rect)
					(size 1.397 1.397)
					(clearance 0.0127)
				)
			)
		)
		(pad "2" thru_hole circle
			(at 1.75006 0 180)
			(size 1.397 1.397)
			(drill 0.9144)
			(layers "*.Cu" "*.Mask")
			(remove_unused_layers no)
			(net "GND")
			(clearance 0.0127)
			(thermal_gap 0.0127)
		)
	)
	(footprint ""
		(layer "F.Cu")
		(at 69.863208 -354.308664 90)
		(property "Reference" "C62"
			(at -3.926078 0.348742 90)
			(unlocked yes)
			(layer "F.SilkS")
			(effects
				(font
					(size 0.7874 0.5842)
					(thickness 0.1524)
				)
				(justify left)
			)
		)
		(property "Value" ""
			(at 0 0 90)
			(layer "F.Fab")
			(effects
				(font
					(size 1.27 1.27)
				)
			)
		)
		(duplicate_pad_numbers_are_jumpers no)
		(fp_line
			(start 0.7874 -0.4064)
			(end 0.7874 0.4064)
			(stroke
				(width 0.1524)
				(type default)
			)
			(layer "F.SilkS")
		)
		(fp_line
			(start -0.7874 -0.4064)
			(end 0.7874 -0.4064)
			(stroke
				(width 0.1524)
				(type default)
			)
			(layer "F.SilkS")
		)
		(fp_line
			(start 0 0.381)
			(end 0 -0.381)
			(stroke
				(width 0.1524)
				(type default)
			)
			(layer "F.SilkS")
		)
		(fp_line
			(start 0.7874 0.4064)
			(end -0.7874 0.4064)
			(stroke
				(width 0.1524)
				(type default)
			)
			(layer "F.SilkS")
		)
		(fp_line
			(start -0.7874 0.4064)
			(end -0.7874 -0.4064)
			(stroke
				(width 0.1524)
				(type default)
			)
			(layer "F.SilkS")
		)
		(fp_poly
			(pts
				(xy -0.5334 0.254) (xy -0.635 0.254) (xy -0.635 0.2286) (xy -0.635 -0.254) (xy -0.5334 -0.254) (xy -0.5334 -0.2794)
				(xy 0.5334 -0.2794) (xy 0.5334 -0.254) (xy 0.635 -0.254) (xy 0.635 0.254) (xy 0.5334 0.254) (xy 0.5334 0.2794)
				(xy -0.508 0.2794) (xy -0.5334 0.2794)
			)
			(stroke
				(width 0)
				(type default)
			)
			(fill no)
			(layer "F.CrtYd")
		)
		(pad "1" smd rect
			(at 0.40005 0 90)
			(size 0.4572 0.508)
			(layers "F.Cu" "F.Mask" "F.Paste")
			(net "P12V")
		)
		(pad "2" smd rect
			(at -0.40005 0 90)
			(size 0.4572 0.508)
			(layers "F.Cu" "F.Mask" "F.Paste")
			(net "GND")
		)
	)
	(footprint ""
		(layer "F.Cu")
		(at 69.133974 -220.425772 90)
		(property "Reference" "C42"
			(at -3.891534 -0.291846 90)
			(unlocked yes)
			(layer "F.SilkS")
			(effects
				(font
					(size 0.7874 0.5842)
					(thickness 0.1524)
				)
				(justify left)
			)
		)
		(property "Value" ""
			(at 0 0 90)
			(layer "F.Fab")
			(effects
				(font
					(size 1.27 1.27)
				)
			)
		)
		(duplicate_pad_numbers_are_jumpers no)
		(fp_line
			(start 0.7874 -0.4064)
			(end 0.7874 0.4064)
			(stroke
				(width 0.1524)
				(type default)
			)
			(layer "F.SilkS")
		)
		(fp_line
			(start -0.7874 -0.4064)
			(end 0.7874 -0.4064)
			(stroke
				(width 0.1524)
				(type default)
			)
			(layer "F.SilkS")
		)
		(fp_line
			(start 0 0.381)
			(end 0 -0.381)
			(stroke
				(width 0.1524)
				(type default)
			)
			(layer "F.SilkS")
		)
		(fp_line
			(start 0.7874 0.4064)
			(end -0.7874 0.4064)
			(stroke
				(width 0.1524)
				(type default)
			)
			(layer "F.SilkS")
		)
		(fp_line
			(start -0.7874 0.4064)
			(end -0.7874 -0.4064)
			(stroke
				(width 0.1524)
				(type default)
			)
			(layer "F.SilkS")
		)
		(fp_poly
			(pts
				(xy -0.5334 0.254) (xy -0.635 0.254) (xy -0.635 0.2286) (xy -0.635 -0.254) (xy -0.5334 -0.254) (xy -0.5334 -0.2794)
				(xy 0.5334 -0.2794) (xy 0.5334 -0.254) (xy 0.635 -0.254) (xy 0.635 0.254) (xy 0.5334 0.254) (xy 0.5334 0.2794)
				(xy -0.508 0.2794) (xy -0.5334 0.2794)
			)
			(stroke
				(width 0)
				(type default)
			)
			(fill no)
			(layer "F.CrtYd")
		)
		(pad "1" smd rect
			(at 0.40005 0 90)
			(size 0.4572 0.508)
			(layers "F.Cu" "F.Mask" "F.Paste")
			(net "P12V")
		)
		(pad "2" smd rect
			(at -0.40005 0 90)
			(size 0.4572 0.508)
			(layers "F.Cu" "F.Mask" "F.Paste")
			(net "GND")
		)
	)
	(footprint ""
		(layer "F.Cu")
		(at 72.932798 -473.59951 180)
		(property "Reference" "R131"
			(at 0.900176 1.046988 0)
			(unlocked yes)
			(layer "F.SilkS")
			(effects
				(font
					(size 0.7874 0.5842)
					(thickness 0.1524)
				)
				(justify left)
			)
		)
		(property "Value" ""
			(at 0 0 180)
			(layer "F.Fab")
			(effects
				(font
					(size 1.27 1.27)
				)
			)
		)
		(duplicate_pad_numbers_are_jumpers no)
		(fp_line
			(start 0.7874 0.4064)
			(end -0.7874 0.4064)
			(stroke
				(width 0.1524)
				(type default)
			)
			(layer "F.SilkS")
		)
		(fp_line
			(start 0.7874 -0.4064)
			(end 0.7874 0.4064)
			(stroke
				(width 0.1524)
				(type default)
			)
			(layer "F.SilkS")
		)
		(fp_line
			(start -0.7874 0.4064)
			(end -0.7874 -0.4064)
			(stroke
				(width 0.1524)
				(type default)
			)
			(layer "F.SilkS")
		)
		(fp_line
			(start -0.7874 -0.4064)
			(end 0.7874 -0.4064)
			(stroke
				(width 0.1524)
				(type default)
			)
			(layer "F.SilkS")
		)
		(fp_poly
			(pts
				(xy -0.508 0.2794) (xy -0.508 0.2286) (xy -0.635 0.2286) (xy -0.635 -0.254) (xy -0.5334 -0.254)
				(xy -0.5334 -0.2794) (xy 0.5334 -0.2794) (xy 0.5334 -0.254) (xy 0.635 -0.254) (xy 0.635 0.254) (xy 0.5334 0.254)
				(xy 0.5334 0.2794)
			)
			(stroke
				(width 0)
				(type default)
			)
			(fill no)
			(layer "F.CrtYd")
		)
		(pad "1" smd rect
			(at 0.40005 0 180)
			(size 0.4572 0.508)
			(layers "F.Cu" "F.Mask" "F.Paste")
			(net "PSU6_REMOTE_R2_P")
		)
		(pad "2" smd rect
			(at -0.40005 0 180)
			(size 0.4572 0.508)
			(layers "F.Cu" "F.Mask" "F.Paste")
			(net "P12V")
		)
	)
	(footprint ""
		(layer "F.Cu")
		(at 75.91298 -397.262604 90)
		(property "Reference" "C67"
			(at -1.66243 -4.655312 90)
			(unlocked yes)
			(layer "F.SilkS")
			(effects
				(font
					(size 0.7874 0.5842)
					(thickness 0.1524)
				)
				(justify left)
			)
		)
		(property "Value" ""
			(at 0 0 90)
			(layer "F.Fab")
			(effects
				(font
					(size 1.27 1.27)
				)
			)
		)
		(duplicate_pad_numbers_are_jumpers no)
		(fp_line
			(start 0.7874 -0.4064)
			(end 0.7874 0.4064)
			(stroke
				(width 0.1524)
				(type default)
			)
			(layer "F.SilkS")
		)
		(fp_line
			(start -0.7874 -0.4064)
			(end 0.7874 -0.4064)
			(stroke
				(width 0.1524)
				(type default)
			)
			(layer "F.SilkS")
		)
		(fp_line
			(start 0 0.381)
			(end 0 -0.381)
			(stroke
				(width 0.1524)
				(type default)
			)
			(layer "F.SilkS")
		)
		(fp_line
			(start 0.7874 0.4064)
			(end -0.7874 0.4064)
			(stroke
				(width 0.1524)
				(type default)
			)
			(layer "F.SilkS")
		)
		(fp_line
			(start -0.7874 0.4064)
			(end -0.7874 -0.4064)
			(stroke
				(width 0.1524)
				(type default)
			)
			(layer "F.SilkS")
		)
		(fp_poly
			(pts
				(xy -0.5334 0.254) (xy -0.635 0.254) (xy -0.635 0.2286) (xy -0.635 -0.254) (xy -0.5334 -0.254) (xy -0.5334 -0.2794)
				(xy 0.5334 -0.2794) (xy 0.5334 -0.254) (xy 0.635 -0.254) (xy 0.635 0.254) (xy 0.5334 0.254) (xy 0.5334 0.2794)
				(xy -0.508 0.2794) (xy -0.5334 0.2794)
			)
			(stroke
				(width 0)
				(type default)
			)
			(fill no)
			(layer "F.CrtYd")
		)
		(pad "1" smd rect
			(at 0.40005 0 90)
			(size 0.4572 0.508)
			(layers "F.Cu" "F.Mask" "F.Paste")
			(net "P12V")
		)
		(pad "2" smd rect
			(at -0.40005 0 90)
			(size 0.4572 0.508)
			(layers "F.Cu" "F.Mask" "F.Paste")
			(net "GND")
		)
	)
	(footprint ""
		(layer "F.Cu")
		(at 14.309598 -223.205294)
		(property "Reference" ""
			(at 0 0 0)
			(layer "F.SilkS")
			(hide yes)
			(effects
				(font
					(size 1.27 1.27)
				)
			)
		)
		(property "Value" ""
			(at 0 0 0)
			(layer "F.Fab")
			(effects
				(font
					(size 1.27 1.27)
				)
			)
		)
		(duplicate_pad_numbers_are_jumpers no)
		(fp_poly
			(pts
				(arc
					(start 1.4986 0)
					(mid -1.4986 0)
					(end 1.4986 0)
				)
			)
			(stroke
				(width 0)
				(type default)
			)
			(fill no)
			(layer "F.CrtYd")
		)
		(pad "1" smd circle
			(at 0 0)
			(size 0.9906 0.9906)
			(layers "F.Cu" "F.Mask" "F.Paste")
			(net "Net_145")
		)
		(zone
			(layer "F.Cu")
			(hatch none 0.5)
			(connect_pads
				(clearance 0)
			)
			(min_thickness 0.25)
			(keepout
				(tracks not_allowed)
				(vias allowed)
				(pads allowed)
				(copperpour not_allowed)
				(footprints allowed)
			)
			(placement
				(enabled no)
				(sheetname "")
			)
			(fill
				(thermal_gap 0.5)
				(thermal_bridge_width 0.5)
				(island_removal_mode 0)
			)
			(polygon
				(pts
					(arc
						(start 15.935198 -223.205294)
						(mid 12.683998 -223.205294)
						(end 15.935198 -223.205294)
					)
				)
			)
		)
	)
	(footprint ""
		(layer "F.Cu")
		(at 4.50469 -105.621836)
		(property "Reference" "J27"
			(at -3.5179 -4.511548 0)
			(unlocked yes)
			(layer "F.SilkS")
			(effects
				(font
					(size 0.7874 0.5842)
					(thickness 0.1524)
				)
				(justify left)
			)
		)
		(property "Value" ""
			(at 0 0 0)
			(layer "F.Fab")
			(effects
				(font
					(size 1.27 1.27)
				)
			)
		)
		(duplicate_pad_numbers_are_jumpers no)
		(fp_line
			(start -3.370072 -3.81)
			(end 12.260072 -3.81)
			(stroke
				(width 0.1524)
				(type default)
			)
			(layer "F.SilkS")
		)
		(fp_line
			(start -3.370072 12.830048)
			(end -3.370072 -3.81)
			(stroke
				(width 0.1524)
				(type default)
			)
			(layer "F.SilkS")
		)
		(fp_line
			(start 12.260072 -3.81)
			(end 12.260072 12.830048)
			(stroke
				(width 0.1524)
				(type default)
			)
			(layer "F.SilkS")
		)
		(fp_line
			(start 12.260072 12.830048)
			(end -3.370072 12.830048)
			(stroke
				(width 0.1524)
				(type default)
			)
			(layer "F.SilkS")
		)
		(fp_poly
			(pts
				(xy -0.073914 -4.222496) (xy -0.7874 -5.649468) (xy 0.639572 -5.649468)
			)
			(stroke
				(width 0)
				(type default)
			)
			(fill yes)
			(layer "F.SilkS")
		)
		(fp_poly
			(pts
				(xy -0.762 0.762) (xy 8.382 0.762) (xy 8.382 -1.8034) (xy 9.652 -1.8034) (xy 9.652 -3.302) (xy 0.508 -3.302)
				(xy 0.508 -0.762) (xy -0.762 -0.762)
			)
			(stroke
				(width 0)
				(type default)
			)
			(fill no)
			(layer "B.CrtYd")
		)
		(fp_poly
			(pts
				(arc
					(start 0.6604 6.35)
					(mid -3.2004 6.35)
					(end 0.6604 6.35)
				)
			)
			(stroke
				(width 0)
				(type default)
			)
			(fill no)
			(layer "B.CrtYd")
		)
		(fp_poly
			(pts
				(arc
					(start 12.0904 6.35)
					(mid 8.2296 6.35)
					(end 12.0904 6.35)
				)
			)
			(stroke
				(width 0)
				(type default)
			)
			(fill no)
			(layer "B.CrtYd")
		)
		(fp_poly
			(pts
				(xy -3.370072 12.830048) (xy 12.260072 12.830048) (xy 12.260072 -3.81) (xy -3.370072 -3.81)
			)
			(stroke
				(width 0)
				(type default)
			)
			(fill no)
			(layer "F.CrtYd")
		)
		(fp_line
			(start -3.370072 -3.81)
			(end 12.260072 -3.81)
			(stroke
				(width 0.1)
				(type default)
			)
			(layer "F.Fab")
		)
		(fp_line
			(start -3.370072 12.830048)
			(end -3.370072 -3.81)
			(stroke
				(width 0.1)
				(type default)
			)
			(layer "F.Fab")
		)
		(fp_line
			(start 12.260072 -3.81)
			(end 12.260072 12.830048)
			(stroke
				(width 0.1)
				(type default)
			)
			(layer "F.Fab")
		)
		(fp_line
			(start 12.260072 12.830048)
			(end -3.370072 12.830048)
			(stroke
				(width 0.1)
				(type default)
			)
			(layer "F.Fab")
		)
		(fp_poly
			(pts
				(xy -3.576828 0) (xy -5.0038 0.713486) (xy -5.0038 -0.713486)
			)
			(stroke
				(width 0)
				(type default)
			)
			(fill yes)
			(layer "F.Fab")
		)
		(fp_text user "2"
			(at -3.9624 -2.428748 0)
			(unlocked yes)
			(layer "F.SilkS")
			(effects
				(font
					(size 0.7874 0.5842)
					(thickness 0.1524)
				)
			)
		)
		(fp_text user "1"
			(at -3.9116 -0.930148 0)
			(unlocked yes)
			(layer "F.SilkS")
			(effects
				(font
					(size 0.7874 0.5842)
					(thickness 0.1524)
				)
			)
		)
		(fp_text user "8"
			(at 12.7762 -2.555748 0)
			(unlocked yes)
			(layer "F.SilkS")
			(effects
				(font
					(size 0.7874 0.5842)
					(thickness 0.1524)
				)
			)
		)
		(fp_text user "7"
			(at 12.7762 -0.091948 0)
			(unlocked yes)
			(layer "F.SilkS")
			(effects
				(font
					(size 0.7874 0.5842)
					(thickness 0.1524)
				)
			)
		)
		(fp_text user "1"
			(at -1.2954 0.085852 0)
			(unlocked yes)
			(layer "B.SilkS")
			(effects
				(font
					(size 0.7874 0.5842)
					(thickness 0.1524)
				)
				(justify mirror)
			)
		)
		(fp_text user "2"
			(at 0 -2.581148 0)
			(unlocked yes)
			(layer "B.SilkS")
			(effects
				(font
					(size 0.7874 0.5842)
					(thickness 0.1524)
				)
				(justify mirror)
			)
		)
		(fp_text user "7"
			(at 8.8138 0.238252 0)
			(unlocked yes)
			(layer "B.SilkS")
			(effects
				(font
					(size 0.7874 0.5842)
					(thickness 0.1524)
				)
				(justify mirror)
			)
		)
		(fp_text user "8"
			(at 10.0838 -2.403348 0)
			(unlocked yes)
			(layer "B.SilkS")
			(effects
				(font
					(size 0.7874 0.5842)
					(thickness 0.1524)
				)
				(justify mirror)
			)
		)
		(fp_text user "1"
			(at -1.2954 0.085852 0)
			(unlocked yes)
			(layer "B.Fab")
			(effects
				(font
					(size 0.7874 0.5842)
					(thickness 0.000001)
				)
				(justify mirror)
			)
		)
		(fp_text user "2"
			(at 0 -2.581148 0)
			(unlocked yes)
			(layer "B.Fab")
			(effects
				(font
					(size 0.7874 0.5842)
					(thickness 0.000001)
				)
				(justify mirror)
			)
		)
		(fp_text user "7"
			(at 8.8138 0.238252 0)
			(unlocked yes)
			(layer "B.Fab")
			(effects
				(font
					(size 0.7874 0.5842)
					(thickness 0.000001)
				)
				(justify mirror)
			)
		)
		(fp_text user "8"
			(at 10.0838 -2.403348 0)
			(unlocked yes)
			(layer "B.Fab")
			(effects
				(font
					(size 0.7874 0.5842)
					(thickness 0.000001)
				)
				(justify mirror)
			)
		)
		(fp_text user "2"
			(at -3.9624 -2.428748 0)
			(unlocked yes)
			(layer "F.Fab")
			(effects
				(font
					(size 0.7874 0.5842)
					(thickness 0.000001)
				)
			)
		)
		(fp_text user "1"
			(at -3.9116 -0.930148 0)
			(unlocked yes)
			(layer "F.Fab")
			(effects
				(font
					(size 0.7874 0.5842)
					(thickness 0.000001)
				)
			)
		)
		(fp_text user "8"
			(at 12.7762 -2.555748 0)
			(unlocked yes)
			(layer "F.Fab")
			(effects
				(font
					(size 0.7874 0.5842)
					(thickness 0.000001)
				)
			)
		)
		(fp_text user "7"
			(at 12.7762 -0.091948 0)
			(unlocked yes)
			(layer "F.Fab")
			(effects
				(font
					(size 0.7874 0.5842)
					(thickness 0.000001)
				)
			)
		)
		(pad "" np_thru_hole circle
			(at -1.27 6.35)
			(size 3.3528 3.3528)
			(drill 3.3528)
			(layers "*.Cu" "*.Mask")
			(clearance 0.381)
			(thermal_gap 0.381)
		)
		(pad "" np_thru_hole circle
			(at 10.16 6.35)
			(size 3.3528 3.3528)
			(drill 3.3528)
			(layers "*.Cu" "*.Mask")
			(clearance 0.381)
			(thermal_gap 0.381)
		)
		(pad "1" thru_hole rect
			(at 0 0)
			(size 1.397 1.397)
			(drill 0.9906)
			(layers "*.Cu" "*.Mask")
			(remove_unused_layers no)
			(net "UART_RTS_P6_L_N")
			(clearance 0.0508)
			(thermal_gap 0.0508)
			(padstack
				(mode front_inner_back)
				(layer "Inner"
					(shape circle)
					(size 1.397 1.397)
					(clearance 0.0508)
				)
				(layer "B.Cu"
					(shape rect)
					(size 1.397 1.397)
					(clearance 0.0508)
				)
			)
		)
		(pad "2" thru_hole circle
			(at 1.27 -2.54)
			(size 1.397 1.397)
			(drill 0.9906)
			(layers "*.Cu" "*.Mask")
			(remove_unused_layers no)
			(net "UART_DSR_P6_L_N")
			(clearance 0.0508)
			(thermal_gap 0.0508)
		)
		(pad "3" thru_hole circle
			(at 2.54 0)
			(size 1.397 1.397)
			(drill 0.9906)
			(layers "*.Cu" "*.Mask")
			(remove_unused_layers no)
			(net "UART_RX_P6_L")
			(clearance 0.0508)
			(thermal_gap 0.0508)
		)
		(pad "4" thru_hole circle
			(at 3.81 -2.54)
			(size 1.397 1.397)
			(drill 0.9906)
			(layers "*.Cu" "*.Mask")
			(remove_unused_layers no)
			(net "UART_RI_P6_L_N")
			(clearance 0.0508)
			(thermal_gap 0.0508)
		)
		(pad "5" thru_hole circle
			(at 5.08 0)
			(size 1.397 1.397)
			(drill 0.9906)
			(layers "*.Cu" "*.Mask")
			(remove_unused_layers no)
			(net "GND")
			(clearance 0.0508)
			(thermal_gap 0.0508)
		)
		(pad "6" thru_hole circle
			(at 6.35 -2.54)
			(size 1.397 1.397)
			(drill 0.9906)
			(layers "*.Cu" "*.Mask")
			(remove_unused_layers no)
			(net "UART_TX_P6_L")
			(clearance 0.0508)
			(thermal_gap 0.0508)
		)
		(pad "7" thru_hole circle
			(at 7.62 0)
			(size 1.397 1.397)
			(drill 0.9906)
			(layers "*.Cu" "*.Mask")
			(remove_unused_layers no)
			(net "UART_DTR_P6_L_N")
			(clearance 0.0508)
			(thermal_gap 0.0508)
		)
		(pad "8" thru_hole circle
			(at 8.89 -2.54)
			(size 1.397 1.397)
			(drill 0.9906)
			(layers "*.Cu" "*.Mask")
			(remove_unused_layers no)
			(net "UART_CTS_P6_L_N")
			(clearance 0.0508)
			(thermal_gap 0.0508)
		)
		(zone
			(layers "F.Cu" "B.Cu" "In1.Cu" "In2.Cu" "In3.Cu" "In4.Cu" "In5.Cu" "In6.Cu")
			(hatch none 0.5)
			(connect_pads
				(clearance 0)
			)
			(min_thickness 0.25)
			(keepout
				(tracks not_allowed)
				(vias allowed)
				(pads allowed)
				(copperpour not_allowed)
				(footprints allowed)
			)
			(placement
				(enabled no)
				(sheetname "")
			)
			(fill
				(thermal_gap 0.5)
				(thermal_bridge_width 0.5)
				(island_removal_mode 0)
			)
			(polygon
				(pts
					(arc
						(start 5.31749 -99.271836)
						(mid 1.15189 -99.271836)
						(end 5.31749 -99.271836)
					)
				)
			)
		)
		(zone
			(layers "F.Cu" "B.Cu" "In1.Cu" "In2.Cu" "In3.Cu" "In4.Cu" "In5.Cu" "In6.Cu")
			(hatch none 0.5)
			(connect_pads
				(clearance 0)
			)
			(min_thickness 0.25)
			(keepout
				(tracks not_allowed)
				(vias allowed)
				(pads allowed)
				(copperpour not_allowed)
				(footprints allowed)
			)
			(placement
				(enabled no)
				(sheetname "")
			)
			(fill
				(thermal_gap 0.5)
				(thermal_bridge_width 0.5)
				(island_removal_mode 0)
			)
			(polygon
				(pts
					(arc
						(start 16.74749 -99.271836)
						(mid 12.58189 -99.271836)
						(end 16.74749 -99.271836)
					)
				)
			)
		)
	)
	(footprint ""
		(layer "F.Cu")
		(at 27.28468 -5.10032)
		(property "Reference" "R45"
			(at -1.676146 2.569972 0)
			(unlocked yes)
			(layer "F.SilkS")
			(effects
				(font
					(size 0.7874 0.5842)
					(thickness 0.1524)
				)
				(justify left)
			)
		)
		(property "Value" ""
			(at 0 0 0)
			(layer "F.Fab")
			(effects
				(font
					(size 1.27 1.27)
				)
			)
		)
		(duplicate_pad_numbers_are_jumpers no)
		(fp_line
			(start -0.7874 -0.4064)
			(end 0.7874 -0.4064)
			(stroke
				(width 0.1524)
				(type default)
			)
			(layer "F.SilkS")
		)
		(fp_line
			(start -0.7874 0.4064)
			(end -0.7874 -0.4064)
			(stroke
				(width 0.1524)
				(type default)
			)
			(layer "F.SilkS")
		)
		(fp_line
			(start 0.7874 -0.4064)
			(end 0.7874 0.4064)
			(stroke
				(width 0.1524)
				(type default)
			)
			(layer "F.SilkS")
		)
		(fp_line
			(start 0.7874 0.4064)
			(end -0.7874 0.4064)
			(stroke
				(width 0.1524)
				(type default)
			)
			(layer "F.SilkS")
		)
		(fp_poly
			(pts
				(xy -0.508 0.2794) (xy -0.508 0.2286) (xy -0.635 0.2286) (xy -0.635 -0.254) (xy -0.5334 -0.254)
				(xy -0.5334 -0.2794) (xy 0.5334 -0.2794) (xy 0.5334 -0.254) (xy 0.635 -0.254) (xy 0.635 0.254) (xy 0.5334 0.254)
				(xy 0.5334 0.2794)
			)
			(stroke
				(width 0)
				(type default)
			)
			(fill no)
			(layer "F.CrtYd")
		)
		(pad "1" smd rect
			(at 0.40005 0)
			(size 0.4572 0.508)
			(layers "F.Cu" "F.Mask" "F.Paste")
			(net "PSU1_RESET")
		)
		(pad "2" smd rect
			(at -0.40005 0)
			(size 0.4572 0.508)
			(layers "F.Cu" "F.Mask" "F.Paste")
			(net "GND")
		)
	)
	(footprint ""
		(layer "F.Cu")
		(at 4.186936 -395.410436 90)
		(property "Reference" "R151"
			(at -4.41071 0.023114 90)
			(unlocked yes)
			(layer "F.SilkS")
			(effects
				(font
					(size 0.7874 0.5842)
					(thickness 0.1524)
				)
				(justify left)
			)
		)
		(property "Value" ""
			(at 0 0 90)
			(layer "F.Fab")
			(effects
				(font
					(size 1.27 1.27)
				)
			)
		)
		(duplicate_pad_numbers_are_jumpers no)
		(fp_line
			(start 0.7874 -0.4064)
			(end 0.7874 0.4064)
			(stroke
				(width 0.1524)
				(type default)
			)
			(layer "F.SilkS")
		)
		(fp_line
			(start -0.7874 -0.4064)
			(end 0.7874 -0.4064)
			(stroke
				(width 0.1524)
				(type default)
			)
			(layer "F.SilkS")
		)
		(fp_line
			(start 0.7874 0.4064)
			(end -0.7874 0.4064)
			(stroke
				(width 0.1524)
				(type default)
			)
			(layer "F.SilkS")
		)
		(fp_line
			(start -0.7874 0.4064)
			(end -0.7874 -0.4064)
			(stroke
				(width 0.1524)
				(type default)
			)
			(layer "F.SilkS")
		)
		(fp_poly
			(pts
				(xy -0.508 0.2794) (xy -0.508 0.2286) (xy -0.635 0.2286) (xy -0.635 -0.254) (xy -0.5334 -0.254)
				(xy -0.5334 -0.2794) (xy 0.5334 -0.2794) (xy 0.5334 -0.254) (xy 0.635 -0.254) (xy 0.635 0.254) (xy 0.5334 0.254)
				(xy 0.5334 0.2794)
			)
			(stroke
				(width 0)
				(type default)
			)
			(fill no)
			(layer "F.CrtYd")
		)
		(pad "1" smd rect
			(at 0.40005 0 90)
			(size 0.4572 0.508)
			(layers "F.Cu" "F.Mask" "F.Paste")
			(net "N42132545")
		)
		(pad "2" smd rect
			(at -0.40005 0 90)
			(size 0.4572 0.508)
			(layers "F.Cu" "F.Mask" "F.Paste")
			(net "GND")
		)
	)
	(footprint ""
		(layer "F.Cu")
		(at 4.50469 -52.571904)
		(property "Reference" "J21"
			(at -3.5179 -4.511548 0)
			(unlocked yes)
			(layer "F.SilkS")
			(effects
				(font
					(size 0.7874 0.5842)
					(thickness 0.1524)
				)
				(justify left)
			)
		)
		(property "Value" ""
			(at 0 0 0)
			(layer "F.Fab")
			(effects
				(font
					(size 1.27 1.27)
				)
			)
		)
		(duplicate_pad_numbers_are_jumpers no)
		(fp_line
			(start -3.370072 -3.81)
			(end 12.260072 -3.81)
			(stroke
				(width 0.1524)
				(type default)
			)
			(layer "F.SilkS")
		)
		(fp_line
			(start -3.370072 12.830048)
			(end -3.370072 -3.81)
			(stroke
				(width 0.1524)
				(type default)
			)
			(layer "F.SilkS")
		)
		(fp_line
			(start 12.260072 -3.81)
			(end 12.260072 12.830048)
			(stroke
				(width 0.1524)
				(type default)
			)
			(layer "F.SilkS")
		)
		(fp_line
			(start 12.260072 12.830048)
			(end -3.370072 12.830048)
			(stroke
				(width 0.1524)
				(type default)
			)
			(layer "F.SilkS")
		)
		(fp_poly
			(pts
				(xy -3.576828 0) (xy -5.0038 0.713486) (xy -5.0038 -0.713486)
			)
			(stroke
				(width 0)
				(type default)
			)
			(fill yes)
			(layer "F.SilkS")
		)
		(fp_poly
			(pts
				(xy -0.762 0.762) (xy 8.382 0.762) (xy 8.382 -1.8034) (xy 9.652 -1.8034) (xy 9.652 -3.302) (xy 0.508 -3.302)
				(xy 0.508 -0.762) (xy -0.762 -0.762)
			)
			(stroke
				(width 0)
				(type default)
			)
			(fill no)
			(layer "B.CrtYd")
		)
		(fp_poly
			(pts
				(arc
					(start 0.6604 6.35)
					(mid -3.2004 6.35)
					(end 0.6604 6.35)
				)
			)
			(stroke
				(width 0)
				(type default)
			)
			(fill no)
			(layer "B.CrtYd")
		)
		(fp_poly
			(pts
				(arc
					(start 12.0904 6.35)
					(mid 8.2296 6.35)
					(end 12.0904 6.35)
				)
			)
			(stroke
				(width 0)
				(type default)
			)
			(fill no)
			(layer "B.CrtYd")
		)
		(fp_poly
			(pts
				(xy -3.370072 12.830048) (xy 12.260072 12.830048) (xy 12.260072 -3.81) (xy -3.370072 -3.81)
			)
			(stroke
				(width 0)
				(type default)
			)
			(fill no)
			(layer "F.CrtYd")
		)
		(fp_line
			(start -3.370072 -3.81)
			(end 12.260072 -3.81)
			(stroke
				(width 0.1)
				(type default)
			)
			(layer "F.Fab")
		)
		(fp_line
			(start -3.370072 12.830048)
			(end -3.370072 -3.81)
			(stroke
				(width 0.1)
				(type default)
			)
			(layer "F.Fab")
		)
		(fp_line
			(start 12.260072 -3.81)
			(end 12.260072 12.830048)
			(stroke
				(width 0.1)
				(type default)
			)
			(layer "F.Fab")
		)
		(fp_line
			(start 12.260072 12.830048)
			(end -3.370072 12.830048)
			(stroke
				(width 0.1)
				(type default)
			)
			(layer "F.Fab")
		)
		(fp_poly
			(pts
				(xy -3.576828 0) (xy -5.0038 0.713486) (xy -5.0038 -0.713486)
			)
			(stroke
				(width 0)
				(type default)
			)
			(fill yes)
			(layer "F.Fab")
		)
		(fp_text user "2"
			(at -3.9624 -2.428748 0)
			(unlocked yes)
			(layer "F.SilkS")
			(effects
				(font
					(size 0.7874 0.5842)
					(thickness 0.1524)
				)
			)
		)
		(fp_text user "1"
			(at -3.9116 -0.930148 0)
			(unlocked yes)
			(layer "F.SilkS")
			(effects
				(font
					(size 0.7874 0.5842)
					(thickness 0.1524)
				)
			)
		)
		(fp_text user "8"
			(at 12.7762 -2.555748 0)
			(unlocked yes)
			(layer "F.SilkS")
			(effects
				(font
					(size 0.7874 0.5842)
					(thickness 0.1524)
				)
			)
		)
		(fp_text user "7"
			(at 12.7762 -0.091948 0)
			(unlocked yes)
			(layer "F.SilkS")
			(effects
				(font
					(size 0.7874 0.5842)
					(thickness 0.1524)
				)
			)
		)
		(fp_text user "1"
			(at -1.2954 0.085852 0)
			(unlocked yes)
			(layer "B.SilkS")
			(effects
				(font
					(size 0.7874 0.5842)
					(thickness 0.1524)
				)
				(justify mirror)
			)
		)
		(fp_text user "2"
			(at 0 -2.581148 0)
			(unlocked yes)
			(layer "B.SilkS")
			(effects
				(font
					(size 0.7874 0.5842)
					(thickness 0.1524)
				)
				(justify mirror)
			)
		)
		(fp_text user "7"
			(at 8.8138 0.238252 0)
			(unlocked yes)
			(layer "B.SilkS")
			(effects
				(font
					(size 0.7874 0.5842)
					(thickness 0.1524)
				)
				(justify mirror)
			)
		)
		(fp_text user "8"
			(at 10.0838 -2.403348 0)
			(unlocked yes)
			(layer "B.SilkS")
			(effects
				(font
					(size 0.7874 0.5842)
					(thickness 0.1524)
				)
				(justify mirror)
			)
		)
		(fp_text user "1"
			(at -1.2954 0.085852 0)
			(unlocked yes)
			(layer "B.Fab")
			(effects
				(font
					(size 0.7874 0.5842)
					(thickness 0.000001)
				)
				(justify mirror)
			)
		)
		(fp_text user "2"
			(at 0 -2.581148 0)
			(unlocked yes)
			(layer "B.Fab")
			(effects
				(font
					(size 0.7874 0.5842)
					(thickness 0.000001)
				)
				(justify mirror)
			)
		)
		(fp_text user "7"
			(at 8.8138 0.238252 0)
			(unlocked yes)
			(layer "B.Fab")
			(effects
				(font
					(size 0.7874 0.5842)
					(thickness 0.000001)
				)
				(justify mirror)
			)
		)
		(fp_text user "8"
			(at 10.0838 -2.403348 0)
			(unlocked yes)
			(layer "B.Fab")
			(effects
				(font
					(size 0.7874 0.5842)
					(thickness 0.000001)
				)
				(justify mirror)
			)
		)
		(fp_text user "2"
			(at -3.9624 -2.428748 0)
			(unlocked yes)
			(layer "F.Fab")
			(effects
				(font
					(size 0.7874 0.5842)
					(thickness 0.000001)
				)
			)
		)
		(fp_text user "1"
			(at -3.9116 -0.930148 0)
			(unlocked yes)
			(layer "F.Fab")
			(effects
				(font
					(size 0.7874 0.5842)
					(thickness 0.000001)
				)
			)
		)
		(fp_text user "8"
			(at 12.7762 -2.555748 0)
			(unlocked yes)
			(layer "F.Fab")
			(effects
				(font
					(size 0.7874 0.5842)
					(thickness 0.000001)
				)
			)
		)
		(fp_text user "7"
			(at 12.7762 -0.091948 0)
			(unlocked yes)
			(layer "F.Fab")
			(effects
				(font
					(size 0.7874 0.5842)
					(thickness 0.000001)
				)
			)
		)
		(pad "" np_thru_hole circle
			(at -1.27 6.35)
			(size 3.3528 3.3528)
			(drill 3.3528)
			(layers "*.Cu" "*.Mask")
			(clearance 0.381)
			(thermal_gap 0.381)
		)
		(pad "" np_thru_hole circle
			(at 10.16 6.35)
			(size 3.3528 3.3528)
			(drill 3.3528)
			(layers "*.Cu" "*.Mask")
			(clearance 0.381)
			(thermal_gap 0.381)
		)
		(pad "1" thru_hole rect
			(at 0 0)
			(size 1.397 1.397)
			(drill 0.9906)
			(layers "*.Cu" "*.Mask")
			(remove_unused_layers no)
			(net "UART_RTS_P2_L_N")
			(clearance 0.0508)
			(thermal_gap 0.0508)
			(padstack
				(mode front_inner_back)
				(layer "Inner"
					(shape circle)
					(size 1.397 1.397)
					(clearance 0.0508)
				)
				(layer "B.Cu"
					(shape rect)
					(size 1.397 1.397)
					(clearance 0.0508)
				)
			)
		)
		(pad "2" thru_hole circle
			(at 1.27 -2.54)
			(size 1.397 1.397)
			(drill 0.9906)
			(layers "*.Cu" "*.Mask")
			(remove_unused_layers no)
			(net "UART_DSR_P2_L_N")
			(clearance 0.0508)
			(thermal_gap 0.0508)
		)
		(pad "3" thru_hole circle
			(at 2.54 0)
			(size 1.397 1.397)
			(drill 0.9906)
			(layers "*.Cu" "*.Mask")
			(remove_unused_layers no)
			(net "UART_RX_P2_L")
			(clearance 0.0508)
			(thermal_gap 0.0508)
		)
		(pad "4" thru_hole circle
			(at 3.81 -2.54)
			(size 1.397 1.397)
			(drill 0.9906)
			(layers "*.Cu" "*.Mask")
			(remove_unused_layers no)
			(net "GND")
			(clearance 0.0508)
			(thermal_gap 0.0508)
		)
		(pad "5" thru_hole circle
			(at 5.08 0)
			(size 1.397 1.397)
			(drill 0.9906)
			(layers "*.Cu" "*.Mask")
			(remove_unused_layers no)
			(net "GND")
			(clearance 0.0508)
			(thermal_gap 0.0508)
		)
		(pad "6" thru_hole circle
			(at 6.35 -2.54)
			(size 1.397 1.397)
			(drill 0.9906)
			(layers "*.Cu" "*.Mask")
			(remove_unused_layers no)
			(net "UART_TX_P2_L")
			(clearance 0.0508)
			(thermal_gap 0.0508)
		)
		(pad "7" thru_hole circle
			(at 7.62 0)
			(size 1.397 1.397)
			(drill 0.9906)
			(layers "*.Cu" "*.Mask")
			(remove_unused_layers no)
			(net "UART_DTR_P2_L_N")
			(clearance 0.0508)
			(thermal_gap 0.0508)
		)
		(pad "8" thru_hole circle
			(at 8.89 -2.54)
			(size 1.397 1.397)
			(drill 0.9906)
			(layers "*.Cu" "*.Mask")
			(remove_unused_layers no)
			(net "UART_CTS_P2_L_N")
			(clearance 0.0508)
			(thermal_gap 0.0508)
		)
		(zone
			(layers "F.Cu" "B.Cu" "In1.Cu" "In2.Cu" "In3.Cu" "In4.Cu" "In5.Cu" "In6.Cu")
			(hatch none 0.5)
			(connect_pads
				(clearance 0)
			)
			(min_thickness 0.25)
			(keepout
				(tracks not_allowed)
				(vias allowed)
				(pads allowed)
				(copperpour not_allowed)
				(footprints allowed)
			)
			(placement
				(enabled no)
				(sheetname "")
			)
			(fill
				(thermal_gap 0.5)
				(thermal_bridge_width 0.5)
				(island_removal_mode 0)
			)
			(polygon
				(pts
					(arc
						(start 5.31749 -46.221904)
						(mid 1.15189 -46.221904)
						(end 5.31749 -46.221904)
					)
				)
			)
		)
		(zone
			(layers "F.Cu" "B.Cu" "In1.Cu" "In2.Cu" "In3.Cu" "In4.Cu" "In5.Cu" "In6.Cu")
			(hatch none 0.5)
			(connect_pads
				(clearance 0)
			)
			(min_thickness 0.25)
			(keepout
				(tracks not_allowed)
				(vias allowed)
				(pads allowed)
				(copperpour not_allowed)
				(footprints allowed)
			)
			(placement
				(enabled no)
				(sheetname "")
			)
			(fill
				(thermal_gap 0.5)
				(thermal_bridge_width 0.5)
				(island_removal_mode 0)
			)
			(polygon
				(pts
					(arc
						(start 16.74749 -46.221904)
						(mid 12.58189 -46.221904)
						(end 16.74749 -46.221904)
					)
				)
			)
		)
	)
	(footprint ""
		(layer "F.Cu")
		(at 25.857708 -365.50092)
		(property "Reference" "R79"
			(at -3.917442 -0.225298 0)
			(unlocked yes)
			(layer "F.SilkS")
			(effects
				(font
					(size 0.7874 0.5842)
					(thickness 0.1524)
				)
				(justify left)
			)
		)
		(property "Value" ""
			(at 0 0 0)
			(layer "F.Fab")
			(effects
				(font
					(size 1.27 1.27)
				)
			)
		)
		(duplicate_pad_numbers_are_jumpers no)
		(fp_line
			(start -0.7874 -0.4064)
			(end 0.7874 -0.4064)
			(stroke
				(width 0.1524)
				(type default)
			)
			(layer "F.SilkS")
		)
		(fp_line
			(start -0.7874 0.4064)
			(end -0.7874 -0.4064)
			(stroke
				(width 0.1524)
				(type default)
			)
			(layer "F.SilkS")
		)
		(fp_line
			(start 0.7874 -0.4064)
			(end 0.7874 0.4064)
			(stroke
				(width 0.1524)
				(type default)
			)
			(layer "F.SilkS")
		)
		(fp_line
			(start 0.7874 0.4064)
			(end -0.7874 0.4064)
			(stroke
				(width 0.1524)
				(type default)
			)
			(layer "F.SilkS")
		)
		(fp_poly
			(pts
				(xy -0.508 0.2794) (xy -0.508 0.2286) (xy -0.635 0.2286) (xy -0.635 -0.254) (xy -0.5334 -0.254)
				(xy -0.5334 -0.2794) (xy 0.5334 -0.2794) (xy 0.5334 -0.254) (xy 0.635 -0.254) (xy 0.635 0.254) (xy 0.5334 0.254)
				(xy 0.5334 0.2794)
			)
			(stroke
				(width 0)
				(type default)
			)
			(fill no)
			(layer "F.CrtYd")
		)
		(pad "1" smd rect
			(at 0.40005 0)
			(size 0.4572 0.508)
			(layers "F.Cu" "F.Mask" "F.Paste")
			(net "PSU5_PS_KILL")
		)
		(pad "2" smd rect
			(at -0.40005 0)
			(size 0.4572 0.508)
			(layers "F.Cu" "F.Mask" "F.Paste")
			(net "GND")
		)
	)
	(footprint ""
		(layer "F.Cu")
		(at 74.775568 -397.262604 90)
		(property "Reference" "C68"
			(at -1.662176 -4.812538 90)
			(unlocked yes)
			(layer "F.SilkS")
			(effects
				(font
					(size 0.7874 0.5842)
					(thickness 0.1524)
				)
				(justify left)
			)
		)
		(property "Value" ""
			(at 0 0 90)
			(layer "F.Fab")
			(effects
				(font
					(size 1.27 1.27)
				)
			)
		)
		(duplicate_pad_numbers_are_jumpers no)
		(fp_line
			(start 0.7874 -0.4064)
			(end 0.7874 0.4064)
			(stroke
				(width 0.1524)
				(type default)
			)
			(layer "F.SilkS")
		)
		(fp_line
			(start -0.7874 -0.4064)
			(end 0.7874 -0.4064)
			(stroke
				(width 0.1524)
				(type default)
			)
			(layer "F.SilkS")
		)
		(fp_line
			(start 0 0.381)
			(end 0 -0.381)
			(stroke
				(width 0.1524)
				(type default)
			)
			(layer "F.SilkS")
		)
		(fp_line
			(start 0.7874 0.4064)
			(end -0.7874 0.4064)
			(stroke
				(width 0.1524)
				(type default)
			)
			(layer "F.SilkS")
		)
		(fp_line
			(start -0.7874 0.4064)
			(end -0.7874 -0.4064)
			(stroke
				(width 0.1524)
				(type default)
			)
			(layer "F.SilkS")
		)
		(fp_poly
			(pts
				(xy -0.5334 0.254) (xy -0.635 0.254) (xy -0.635 0.2286) (xy -0.635 -0.254) (xy -0.5334 -0.254) (xy -0.5334 -0.2794)
				(xy 0.5334 -0.2794) (xy 0.5334 -0.254) (xy 0.635 -0.254) (xy 0.635 0.254) (xy 0.5334 0.254) (xy 0.5334 0.2794)
				(xy -0.508 0.2794) (xy -0.5334 0.2794)
			)
			(stroke
				(width 0)
				(type default)
			)
			(fill no)
			(layer "F.CrtYd")
		)
		(pad "1" smd rect
			(at 0.40005 0 90)
			(size 0.4572 0.508)
			(layers "F.Cu" "F.Mask" "F.Paste")
			(net "P12V")
		)
		(pad "2" smd rect
			(at -0.40005 0 90)
			(size 0.4572 0.508)
			(layers "F.Cu" "F.Mask" "F.Paste")
			(net "GND")
		)
	)
	(footprint ""
		(layer "F.Cu")
		(at 4.82473 -409.699968)
		(property "Reference" "J28"
			(at -3.8608 -4.816348 0)
			(unlocked yes)
			(layer "F.SilkS")
			(effects
				(font
					(size 0.7874 0.5842)
					(thickness 0.1524)
				)
				(justify left)
			)
		)
		(property "Value" ""
			(at 0 0 0)
			(layer "F.Fab")
			(effects
				(font
					(size 1.27 1.27)
				)
			)
		)
		(duplicate_pad_numbers_are_jumpers no)
		(fp_line
			(start -3.754882 -3.800094)
			(end 12.644882 -3.800094)
			(stroke
				(width 0.1524)
				(type default)
			)
			(layer "F.SilkS")
		)
		(fp_line
			(start -3.754882 1.2192)
			(end -3.754882 -3.800094)
			(stroke
				(width 0.1524)
				(type default)
			)
			(layer "F.SilkS")
		)
		(fp_line
			(start -3.754882 12.899898)
			(end -3.754882 3.7846)
			(stroke
				(width 0.1524)
				(type default)
			)
			(layer "F.SilkS")
		)
		(fp_line
			(start 12.644882 -3.800094)
			(end 12.644882 1.2192)
			(stroke
				(width 0.1524)
				(type default)
			)
			(layer "F.SilkS")
		)
		(fp_line
			(start 12.644882 3.7846)
			(end 12.644882 12.899898)
			(stroke
				(width 0.1524)
				(type default)
			)
			(layer "F.SilkS")
		)
		(fp_line
			(start 12.644882 12.899898)
			(end -3.754882 12.899898)
			(stroke
				(width 0.1524)
				(type default)
			)
			(layer "F.SilkS")
		)
		(fp_poly
			(pts
				(xy -3.807714 -0.117094) (xy -4.479544 0.218948) (xy -4.479544 -0.453136)
			)
			(stroke
				(width 0)
				(type default)
			)
			(fill yes)
			(layer "F.SilkS")
		)
		(fp_poly
			(pts
				(xy -2.591562 11.176) (xy 1.370838 11.176) (xy 1.370838 9.7282) (xy -2.591562 9.7282)
			)
			(stroke
				(width 0)
				(type default)
			)
			(fill no)
			(layer "B.CrtYd")
		)
		(fp_poly
			(pts
				(xy 7.5184 11.176) (xy 11.4808 11.176) (xy 11.4808 9.7282) (xy 7.5184 9.7282)
			)
			(stroke
				(width 0)
				(type default)
			)
			(fill no)
			(layer "B.CrtYd")
		)
		(fp_poly
			(pts
				(xy 9.627362 -3.256026) (xy 9.627362 -1.808226) (xy 8.357362 -1.808226) (xy 8.357362 0.731774) (xy -0.735838 0.731774)
				(xy -0.735838 -0.741426) (xy 0.534162 -0.741426) (xy 0.534162 -3.256026)
			)
			(stroke
				(width 0)
				(type default)
			)
			(fill no)
			(layer "B.CrtYd")
		)
		(fp_poly
			(pts
				(arc
					(start -2.198116 2.500122)
					(mid -4.661916 2.500122)
					(end -2.198116 2.500122)
				)
			)
			(stroke
				(width 0)
				(type default)
			)
			(fill no)
			(layer "B.CrtYd")
		)
		(fp_poly
			(pts
				(arc
					(start 13.551916 2.500122)
					(mid 11.088116 2.500122)
					(end 13.551916 2.500122)
				)
			)
			(stroke
				(width 0)
				(type default)
			)
			(fill no)
			(layer "B.CrtYd")
		)
		(fp_poly
			(pts
				(arc
					(start 0.5842 6.35)
					(mid -3.1242 6.35)
					(end 0.5842 6.35)
				)
			)
			(stroke
				(width 0)
				(type default)
			)
			(fill no)
			(layer "B.CrtYd")
		)
		(fp_poly
			(pts
				(arc
					(start 12.0142 6.35)
					(mid 8.3058 6.35)
					(end 12.0142 6.35)
				)
			)
			(stroke
				(width 0)
				(type default)
			)
			(fill no)
			(layer "B.CrtYd")
		)
		(fp_poly
			(pts
				(xy -3.754882 12.899898)
				(arc
					(start -3.754882 3.688334)
					(mid -4.662083 2.499901)
					(end -3.754882 1.311656)
				)
				(xy -3.754882 -3.800094) (xy 12.644882 -3.800094)
				(arc
					(start 12.644882 1.311656)
					(mid 13.551838 2.499901)
					(end 12.644882 3.688334)
				)
				(xy 12.644882 12.899898)
			)
			(stroke
				(width 0)
				(type default)
			)
			(fill no)
			(layer "F.CrtYd")
		)
		(fp_line
			(start -3.754882 -3.800094)
			(end 12.644882 -3.800094)
			(stroke
				(width 0.1)
				(type default)
			)
			(layer "F.Fab")
		)
		(fp_line
			(start -3.754882 12.899898)
			(end -3.754882 -3.800094)
			(stroke
				(width 0.1)
				(type default)
			)
			(layer "F.Fab")
		)
		(fp_line
			(start 12.644882 -3.800094)
			(end 12.644882 12.899898)
			(stroke
				(width 0.1)
				(type default)
			)
			(layer "F.Fab")
		)
		(fp_line
			(start 12.644882 12.899898)
			(end -3.754882 12.899898)
			(stroke
				(width 0.1)
				(type default)
			)
			(layer "F.Fab")
		)
		(fp_poly
			(pts
				(xy -4.125214 0) (xy -5.806186 0.840486) (xy -5.806186 -0.840486)
			)
			(stroke
				(width 0)
				(type default)
			)
			(fill yes)
			(layer "F.Fab")
		)
		(fp_text user "2"
			(at -4.136136 -2.597912 0)
			(unlocked yes)
			(layer "F.SilkS")
			(effects
				(font
					(size 0.7874 0.5842)
					(thickness 0.1524)
				)
			)
		)
		(fp_text user "1"
			(at -4.098036 -1.035812 0)
			(unlocked yes)
			(layer "F.SilkS")
			(effects
				(font
					(size 0.7874 0.5842)
					(thickness 0.1524)
				)
			)
		)
		(fp_text user "7"
			(at 13.2334 -0.079248 0)
			(unlocked yes)
			(layer "F.SilkS")
			(effects
				(font
					(size 0.7874 0.5842)
					(thickness 0.1524)
				)
			)
		)
		(fp_text user "8"
			(at 13.2715 -2.593848 0)
			(unlocked yes)
			(layer "F.SilkS")
			(effects
				(font
					(size 0.7874 0.5842)
					(thickness 0.1524)
				)
			)
		)
		(fp_text user "1"
			(at -1.1811 -0.053848 0)
			(unlocked yes)
			(layer "B.SilkS")
			(effects
				(font
					(size 0.7874 0.5842)
					(thickness 0.1524)
				)
				(justify mirror)
			)
		)
		(fp_text user "2"
			(at -0.0635 -2.631948 0)
			(unlocked yes)
			(layer "B.SilkS")
			(effects
				(font
					(size 0.7874 0.5842)
					(thickness 0.1524)
				)
				(justify mirror)
			)
		)
		(fp_text user "7"
			(at 8.8646 0.085852 0)
			(unlocked yes)
			(layer "B.SilkS")
			(effects
				(font
					(size 0.7874 0.5842)
					(thickness 0.1524)
				)
				(justify mirror)
			)
		)
		(fp_text user "8"
			(at 10.1219 -2.479548 0)
			(unlocked yes)
			(layer "B.SilkS")
			(effects
				(font
					(size 0.7874 0.5842)
					(thickness 0.1524)
				)
				(justify mirror)
			)
		)
		(fp_text user "1"
			(at -1.1811 -0.053848 0)
			(unlocked yes)
			(layer "B.Fab")
			(effects
				(font
					(size 0.7874 0.5842)
					(thickness 0.000001)
				)
				(justify mirror)
			)
		)
		(fp_text user "2"
			(at -0.0635 -2.631948 0)
			(unlocked yes)
			(layer "B.Fab")
			(effects
				(font
					(size 0.7874 0.5842)
					(thickness 0.000001)
				)
				(justify mirror)
			)
		)
		(fp_text user "7"
			(at 8.8646 0.085852 0)
			(unlocked yes)
			(layer "B.Fab")
			(effects
				(font
					(size 0.7874 0.5842)
					(thickness 0.000001)
				)
				(justify mirror)
			)
		)
		(fp_text user "8"
			(at 10.1219 -2.479548 0)
			(unlocked yes)
			(layer "B.Fab")
			(effects
				(font
					(size 0.7874 0.5842)
					(thickness 0.000001)
				)
				(justify mirror)
			)
		)
		(fp_text user "2"
			(at -4.4704 -2.581148 0)
			(unlocked yes)
			(layer "F.Fab")
			(effects
				(font
					(size 0.7874 0.5842)
					(thickness 0.000001)
				)
			)
		)
		(fp_text user "1"
			(at -4.4323 -1.019048 0)
			(unlocked yes)
			(layer "F.Fab")
			(effects
				(font
					(size 0.7874 0.5842)
					(thickness 0.000001)
				)
			)
		)
		(fp_text user "7"
			(at 13.2334 -0.079248 0)
			(unlocked yes)
			(layer "F.Fab")
			(effects
				(font
					(size 0.7874 0.5842)
					(thickness 0.000001)
				)
			)
		)
		(fp_text user "8"
			(at 13.2715 -2.593848 0)
			(unlocked yes)
			(layer "F.Fab")
			(effects
				(font
					(size 0.7874 0.5842)
					(thickness 0.000001)
				)
			)
		)
		(pad "" np_thru_hole circle
			(at -1.27 6.35)
			(size 3.2004 3.2004)
			(drill 3.2004)
			(layers "*.Cu" "*.Mask")
			(clearance 0.381)
			(thermal_gap 0.381)
		)
		(pad "" np_thru_hole circle
			(at 10.16 6.35)
			(size 3.2004 3.2004)
			(drill 3.2004)
			(layers "*.Cu" "*.Mask")
			(clearance 0.381)
			(thermal_gap 0.381)
		)
		(pad "1" thru_hole rect
			(at 0 0)
			(size 1.3208 1.3208)
			(drill 0.9144)
			(layers "*.Cu" "*.Mask")
			(remove_unused_layers no)
			(net "LAN2_P1_P")
			(clearance 0.0508)
			(thermal_gap 0.0508)
			(padstack
				(mode front_inner_back)
				(layer "Inner"
					(shape circle)
					(size 1.3208 1.3208)
					(clearance 0.0508)
				)
				(layer "B.Cu"
					(shape rect)
					(size 1.3208 1.3208)
					(clearance 0.0508)
				)
			)
		)
		(pad "2" thru_hole circle
			(at 1.27 -2.54)
			(size 1.3208 1.3208)
			(drill 0.9144)
			(layers "*.Cu" "*.Mask")
			(remove_unused_layers no)
			(net "LAN2_P1_N")
			(clearance 0.0508)
			(thermal_gap 0.0508)
		)
		(pad "3" thru_hole circle
			(at 2.54 0)
			(size 1.3208 1.3208)
			(drill 0.9144)
			(layers "*.Cu" "*.Mask")
			(remove_unused_layers no)
			(net "LAN2_P2_P")
			(clearance 0.0508)
			(thermal_gap 0.0508)
		)
		(pad "4" thru_hole circle
			(at 3.81 -2.54)
			(size 1.3208 1.3208)
			(drill 0.9144)
			(layers "*.Cu" "*.Mask")
			(remove_unused_layers no)
			(net "LAN2_P3_P")
			(clearance 0.0508)
			(thermal_gap 0.0508)
		)
		(pad "5" thru_hole circle
			(at 5.08 0)
			(size 1.3208 1.3208)
			(drill 0.9144)
			(layers "*.Cu" "*.Mask")
			(remove_unused_layers no)
			(net "LAN2_P3_N")
			(clearance 0.0508)
			(thermal_gap 0.0508)
		)
		(pad "6" thru_hole circle
			(at 6.35 -2.54)
			(size 1.3208 1.3208)
			(drill 0.9144)
			(layers "*.Cu" "*.Mask")
			(remove_unused_layers no)
			(net "LAN2_P2_N")
			(clearance 0.0508)
			(thermal_gap 0.0508)
		)
		(pad "7" thru_hole circle
			(at 7.62 0)
			(size 1.3208 1.3208)
			(drill 0.9144)
			(layers "*.Cu" "*.Mask")
			(remove_unused_layers no)
			(net "LAN2_P4_P")
			(clearance 0.0508)
			(thermal_gap 0.0508)
		)
		(pad "8" thru_hole circle
			(at 8.89 -2.54)
			(size 1.3208 1.3208)
			(drill 0.9144)
			(layers "*.Cu" "*.Mask")
			(remove_unused_layers no)
			(net "LAN2_P4_N")
			(clearance 0.0508)
			(thermal_gap 0.0508)
		)
		(pad "9" thru_hole circle
			(at -1.854962 10.459974)
			(size 1.3208 1.3208)
			(drill 0.9144)
			(layers "*.Cu" "*.Mask")
			(remove_unused_layers no)
			(net "N42132933")
			(clearance 0.0508)
			(thermal_gap 0.0508)
		)
		(pad "10" thru_hole circle
			(at 0.635 10.459974)
			(size 1.3208 1.3208)
			(drill 0.9144)
			(layers "*.Cu" "*.Mask")
			(remove_unused_layers no)
			(net "N42132545")
			(clearance 0.0508)
			(thermal_gap 0.0508)
		)
		(pad "11" thru_hole circle
			(at 8.255 10.459974)
			(size 1.3208 1.3208)
			(drill 0.9144)
			(layers "*.Cu" "*.Mask")
			(remove_unused_layers no)
			(net "Net_54")
			(clearance 0.0508)
			(thermal_gap 0.0508)
		)
		(pad "12" thru_hole circle
			(at 10.744962 10.459974)
			(size 1.3208 1.3208)
			(drill 0.9144)
			(layers "*.Cu" "*.Mask")
			(remove_unused_layers no)
			(net "N42132358")
			(clearance 0.0508)
			(thermal_gap 0.0508)
		)
		(pad "G1" thru_hole circle
			(at -3.430016 2.500122)
			(size 2.3622 2.3622)
			(drill 1.6002)
			(layers "*.Cu" "*.Mask")
			(remove_unused_layers no)
			(net "GND")
			(clearance -0.127)
		)
		(pad "G2" thru_hole circle
			(at 12.320016 2.500122)
			(size 2.3622 2.3622)
			(drill 1.6002)
			(layers "*.Cu" "*.Mask")
			(remove_unused_layers no)
			(net "GND")
			(clearance -0.127)
		)
		(zone
			(layers "F.Cu" "B.Cu" "In1.Cu" "In2.Cu" "In3.Cu" "In4.Cu" "In5.Cu" "In6.Cu")
			(hatch none 0.5)
			(connect_pads
				(clearance 0)
			)
			(min_thickness 0.25)
			(keepout
				(tracks not_allowed)
				(vias allowed)
				(pads allowed)
				(copperpour not_allowed)
				(footprints allowed)
			)
			(placement
				(enabled no)
				(sheetname "")
			)
			(fill
				(thermal_gap 0.5)
				(thermal_bridge_width 0.5)
				(island_removal_mode 0)
			)
			(polygon
				(pts
					(arc
						(start 5.56133 -403.349968)
						(mid 1.54813 -403.349968)
						(end 5.56133 -403.349968)
					)
				)
			)
		)
		(zone
			(layers "F.Cu" "B.Cu" "In1.Cu" "In2.Cu" "In3.Cu" "In4.Cu" "In5.Cu" "In6.Cu")
			(hatch none 0.5)
			(connect_pads
				(clearance 0)
			)
			(min_thickness 0.25)
			(keepout
				(tracks not_allowed)
				(vias allowed)
				(pads allowed)
				(copperpour not_allowed)
				(footprints allowed)
			)
			(placement
				(enabled no)
				(sheetname "")
			)
			(fill
				(thermal_gap 0.5)
				(thermal_bridge_width 0.5)
				(island_removal_mode 0)
			)
			(polygon
				(pts
					(arc
						(start 16.99133 -403.349968)
						(mid 12.97813 -403.349968)
						(end 16.99133 -403.349968)
					)
				)
			)
		)
	)
	(footprint ""
		(layer "F.Cu")
		(at 27.33421 -197.033896 -90)
		(property "Reference" "R97"
			(at -1.141222 0.065278 90)
			(unlocked yes)
			(layer "F.SilkS")
			(effects
				(font
					(size 0.7874 0.5842)
					(thickness 0.1524)
				)
				(justify left)
			)
		)
		(property "Value" ""
			(at 0 0 270)
			(layer "F.Fab")
			(effects
				(font
					(size 1.27 1.27)
				)
			)
		)
		(duplicate_pad_numbers_are_jumpers no)
		(fp_line
			(start -0.7874 0.4064)
			(end -0.7874 -0.4064)
			(stroke
				(width 0.1524)
				(type default)
			)
			(layer "F.SilkS")
		)
		(fp_line
			(start 0.7874 0.4064)
			(end -0.7874 0.4064)
			(stroke
				(width 0.1524)
				(type default)
			)
			(layer "F.SilkS")
		)
		(fp_line
			(start -0.7874 -0.4064)
			(end 0.7874 -0.4064)
			(stroke
				(width 0.1524)
				(type default)
			)
			(layer "F.SilkS")
		)
		(fp_line
			(start 0.7874 -0.4064)
			(end 0.7874 0.4064)
			(stroke
				(width 0.1524)
				(type default)
			)
			(layer "F.SilkS")
		)
		(fp_poly
			(pts
				(xy -0.508 0.2794) (xy -0.508 0.2286) (xy -0.635 0.2286) (xy -0.635 -0.254) (xy -0.5334 -0.254)
				(xy -0.5334 -0.2794) (xy 0.5334 -0.2794) (xy 0.5334 -0.254) (xy 0.635 -0.254) (xy 0.635 0.254) (xy 0.5334 0.254)
				(xy 0.5334 0.2794)
			)
			(stroke
				(width 0)
				(type default)
			)
			(fill no)
			(layer "F.CrtYd")
		)
		(pad "1" smd rect
			(at 0.40005 0 270)
			(size 0.4572 0.508)
			(layers "F.Cu" "F.Mask" "F.Paste")
			(net "PSU3_REMOTE_N")
		)
		(pad "2" smd rect
			(at -0.40005 0 270)
			(size 0.4572 0.508)
			(layers "F.Cu" "F.Mask" "F.Paste")
			(net "PSU3_REMOTE_R_N")
		)
	)
	(footprint ""
		(layer "F.Cu")
		(at 70.658736 -193.582544 -90)
		(property "Reference" "C30"
			(at 0.978662 -4.1656 90)
			(unlocked yes)
			(layer "F.SilkS")
			(effects
				(font
					(size 0.7874 0.5842)
					(thickness 0.1524)
				)
				(justify left)
			)
		)
		(property "Value" ""
			(at 0 0 270)
			(layer "F.Fab")
			(effects
				(font
					(size 1.27 1.27)
				)
			)
		)
		(duplicate_pad_numbers_are_jumpers no)
		(fp_line
			(start -0.7874 0.4064)
			(end -0.7874 -0.4064)
			(stroke
				(width 0.1524)
				(type default)
			)
			(layer "F.SilkS")
		)
		(fp_line
			(start 0.7874 0.4064)
			(end -0.7874 0.4064)
			(stroke
				(width 0.1524)
				(type default)
			)
			(layer "F.SilkS")
		)
		(fp_line
			(start 0 0.381)
			(end 0 -0.381)
			(stroke
				(width 0.1524)
				(type default)
			)
			(layer "F.SilkS")
		)
		(fp_line
			(start -0.7874 -0.4064)
			(end 0.7874 -0.4064)
			(stroke
				(width 0.1524)
				(type default)
			)
			(layer "F.SilkS")
		)
		(fp_line
			(start 0.7874 -0.4064)
			(end 0.7874 0.4064)
			(stroke
				(width 0.1524)
				(type default)
			)
			(layer "F.SilkS")
		)
		(fp_poly
			(pts
				(xy -0.5334 0.254) (xy -0.635 0.254) (xy -0.635 0.2286) (xy -0.635 -0.254) (xy -0.5334 -0.254) (xy -0.5334 -0.2794)
				(xy 0.5334 -0.2794) (xy 0.5334 -0.254) (xy 0.635 -0.254) (xy 0.635 0.254) (xy 0.5334 0.254) (xy 0.5334 0.2794)
				(xy -0.508 0.2794) (xy -0.5334 0.2794)
			)
			(stroke
				(width 0)
				(type default)
			)
			(fill no)
			(layer "F.CrtYd")
		)
		(pad "1" smd rect
			(at 0.40005 0 270)
			(size 0.4572 0.508)
			(layers "F.Cu" "F.Mask" "F.Paste")
			(net "P12V")
		)
		(pad "2" smd rect
			(at -0.40005 0 270)
			(size 0.4572 0.508)
			(layers "F.Cu" "F.Mask" "F.Paste")
			(net "GND")
		)
	)
	(footprint ""
		(layer "F.Cu")
		(at 73.512934 -415.478722 -90)
		(property "Reference" "C65"
			(at -3.000502 0.051816 90)
			(unlocked yes)
			(layer "F.SilkS")
			(effects
				(font
					(size 0.7874 0.5842)
					(thickness 0.1524)
				)
				(justify left)
			)
		)
		(property "Value" ""
			(at 0 0 270)
			(layer "F.Fab")
			(effects
				(font
					(size 1.27 1.27)
				)
			)
		)
		(duplicate_pad_numbers_are_jumpers no)
		(fp_line
			(start -0.7874 0.4064)
			(end -0.7874 -0.4064)
			(stroke
				(width 0.1524)
				(type default)
			)
			(layer "F.SilkS")
		)
		(fp_line
			(start 0.7874 0.4064)
			(end -0.7874 0.4064)
			(stroke
				(width 0.1524)
				(type default)
			)
			(layer "F.SilkS")
		)
		(fp_line
			(start 0 0.381)
			(end 0 -0.381)
			(stroke
				(width 0.1524)
				(type default)
			)
			(layer "F.SilkS")
		)
		(fp_line
			(start -0.7874 -0.4064)
			(end 0.7874 -0.4064)
			(stroke
				(width 0.1524)
				(type default)
			)
			(layer "F.SilkS")
		)
		(fp_line
			(start 0.7874 -0.4064)
			(end 0.7874 0.4064)
			(stroke
				(width 0.1524)
				(type default)
			)
			(layer "F.SilkS")
		)
		(fp_poly
			(pts
				(xy -0.5334 0.254) (xy -0.635 0.254) (xy -0.635 0.2286) (xy -0.635 -0.254) (xy -0.5334 -0.254) (xy -0.5334 -0.2794)
				(xy 0.5334 -0.2794) (xy 0.5334 -0.254) (xy 0.635 -0.254) (xy 0.635 0.254) (xy 0.5334 0.254) (xy 0.5334 0.2794)
				(xy -0.508 0.2794) (xy -0.5334 0.2794)
			)
			(stroke
				(width 0)
				(type default)
			)
			(fill no)
			(layer "F.CrtYd")
		)
		(pad "1" smd rect
			(at 0.40005 0 270)
			(size 0.4572 0.508)
			(layers "F.Cu" "F.Mask" "F.Paste")
			(net "P12V")
		)
		(pad "2" smd rect
			(at -0.40005 0 270)
			(size 0.4572 0.508)
			(layers "F.Cu" "F.Mask" "F.Paste")
			(net "GND")
		)
	)
	(footprint ""
		(layer "F.Cu")
		(at 26.226008 -449.713858)
		(property "Reference" "R84"
			(at -3.597402 -0.121666 0)
			(unlocked yes)
			(layer "F.SilkS")
			(effects
				(font
					(size 0.7874 0.5842)
					(thickness 0.1524)
				)
				(justify left)
			)
		)
		(property "Value" ""
			(at 0 0 0)
			(layer "F.Fab")
			(effects
				(font
					(size 1.27 1.27)
				)
			)
		)
		(duplicate_pad_numbers_are_jumpers no)
		(fp_line
			(start -0.7874 -0.4064)
			(end 0.7874 -0.4064)
			(stroke
				(width 0.1524)
				(type default)
			)
			(layer "F.SilkS")
		)
		(fp_line
			(start -0.7874 0.4064)
			(end -0.7874 -0.4064)
			(stroke
				(width 0.1524)
				(type default)
			)
			(layer "F.SilkS")
		)
		(fp_line
			(start 0.7874 -0.4064)
			(end 0.7874 0.4064)
			(stroke
				(width 0.1524)
				(type default)
			)
			(layer "F.SilkS")
		)
		(fp_line
			(start 0.7874 0.4064)
			(end -0.7874 0.4064)
			(stroke
				(width 0.1524)
				(type default)
			)
			(layer "F.SilkS")
		)
		(fp_poly
			(pts
				(xy -0.508 0.2794) (xy -0.508 0.2286) (xy -0.635 0.2286) (xy -0.635 -0.254) (xy -0.5334 -0.254)
				(xy -0.5334 -0.2794) (xy 0.5334 -0.2794) (xy 0.5334 -0.254) (xy 0.635 -0.254) (xy 0.635 0.254) (xy 0.5334 0.254)
				(xy 0.5334 0.2794)
			)
			(stroke
				(width 0)
				(type default)
			)
			(fill no)
			(layer "F.CrtYd")
		)
		(pad "1" smd rect
			(at 0.40005 0)
			(size 0.4572 0.508)
			(layers "F.Cu" "F.Mask" "F.Paste")
			(net "PSU6_RESET")
		)
		(pad "2" smd rect
			(at -0.40005 0)
			(size 0.4572 0.508)
			(layers "F.Cu" "F.Mask" "F.Paste")
			(net "P12V_STBY")
		)
	)
	(footprint ""
		(layer "F.Cu")
		(at 26.947622 -108.230416)
		(property "Reference" "R7"
			(at -2.66192 0.007112 0)
			(unlocked yes)
			(layer "F.SilkS")
			(effects
				(font
					(size 0.7874 0.5842)
					(thickness 0.1524)
				)
				(justify left)
			)
		)
		(property "Value" ""
			(at 0 0 0)
			(layer "F.Fab")
			(effects
				(font
					(size 1.27 1.27)
				)
			)
		)
		(duplicate_pad_numbers_are_jumpers no)
		(fp_line
			(start -0.7874 -0.4064)
			(end 0.7874 -0.4064)
			(stroke
				(width 0.1524)
				(type default)
			)
			(layer "F.SilkS")
		)
		(fp_line
			(start -0.7874 0.4064)
			(end -0.7874 -0.4064)
			(stroke
				(width 0.1524)
				(type default)
			)
			(layer "F.SilkS")
		)
		(fp_line
			(start 0.7874 -0.4064)
			(end 0.7874 0.4064)
			(stroke
				(width 0.1524)
				(type default)
			)
			(layer "F.SilkS")
		)
		(fp_line
			(start 0.7874 0.4064)
			(end -0.7874 0.4064)
			(stroke
				(width 0.1524)
				(type default)
			)
			(layer "F.SilkS")
		)
		(fp_poly
			(pts
				(xy -0.508 0.2794) (xy -0.508 0.2286) (xy -0.635 0.2286) (xy -0.635 -0.254) (xy -0.5334 -0.254)
				(xy -0.5334 -0.2794) (xy 0.5334 -0.2794) (xy 0.5334 -0.254) (xy 0.635 -0.254) (xy 0.635 0.254) (xy 0.5334 0.254)
				(xy 0.5334 0.2794)
			)
			(stroke
				(width 0)
				(type default)
			)
			(fill no)
			(layer "F.CrtYd")
		)
		(pad "1" smd rect
			(at 0.40005 0)
			(size 0.4572 0.508)
			(layers "F.Cu" "F.Mask" "F.Paste")
			(net "PSU2_REMOTE_N")
		)
		(pad "2" smd rect
			(at -0.40005 0)
			(size 0.4572 0.508)
			(layers "F.Cu" "F.Mask" "F.Paste")
			(net "GND")
		)
	)
	(footprint ""
		(layer "F.Cu")
		(at 30.45968 -260.130036)
		(property "Reference" "J3"
			(at -4.153662 5.745988 0)
			(unlocked yes)
			(layer "F.SilkS")
			(effects
				(font
					(size 0.7874 0.5842)
					(thickness 0.1524)
				)
				(justify left)
			)
		)
		(property "Value" ""
			(at 0 0 0)
			(layer "F.Fab")
			(effects
				(font
					(size 1.27 1.27)
				)
			)
		)
		(duplicate_pad_numbers_are_jumpers no)
		(fp_line
			(start -2.135124 -4.560062)
			(end -2.135124 83.300062)
			(stroke
				(width 0.1524)
				(type default)
			)
			(layer "F.SilkS")
		)
		(fp_line
			(start -2.135124 83.300062)
			(end 7.215124 83.300062)
			(stroke
				(width 0.1524)
				(type default)
			)
			(layer "F.SilkS")
		)
		(fp_line
			(start 7.215124 -4.560062)
			(end -2.135124 -4.560062)
			(stroke
				(width 0.1524)
				(type default)
			)
			(layer "F.SilkS")
		)
		(fp_line
			(start 7.215124 83.300062)
			(end 7.215124 -4.560062)
			(stroke
				(width 0.1524)
				(type default)
			)
			(layer "F.SilkS")
		)
		(fp_poly
			(pts
				(xy -2.758694 -0.014732) (xy -5.458714 -0.714756) (xy -5.458714 0.685292)
			)
			(stroke
				(width 0)
				(type default)
			)
			(fill yes)
			(layer "F.SilkS")
		)
		(fp_poly
			(pts
				(xy -2.28219 -0.127) (xy -4.98221 -0.827024) (xy -4.98221 0.573024)
			)
			(stroke
				(width 0)
				(type default)
			)
			(fill yes)
			(layer "B.SilkS")
		)
		(fp_poly
			(pts
				(xy -0.8636 -0.8636) (xy -0.8636 79.6036) (xy -0.8636 79.629) (xy 5.9436 79.629) (xy 5.9436 79.6036)
				(xy 5.9436 -0.8636) (xy 5.9436 -0.889) (xy -0.8636 -0.889)
			)
			(stroke
				(width 0)
				(type default)
			)
			(fill no)
			(layer "B.CrtYd")
		)
		(fp_rect
			(start -2.135124 -4.560062)
			(end 7.21487 83.300062)
			(stroke
				(width 0)
				(type default)
			)
			(fill no)
			(layer "F.CrtYd")
		)
		(fp_line
			(start -2.135124 -4.560062)
			(end 7.215124 -4.560062)
			(stroke
				(width 0.1)
				(type default)
			)
			(layer "F.Fab")
		)
		(fp_line
			(start -2.135124 83.300062)
			(end -2.135124 -4.560062)
			(stroke
				(width 0.1)
				(type default)
			)
			(layer "F.Fab")
		)
		(fp_line
			(start 7.215124 -4.560062)
			(end 7.215124 83.300062)
			(stroke
				(width 0.1)
				(type default)
			)
			(layer "F.Fab")
		)
		(fp_line
			(start 7.215124 83.300062)
			(end -2.135124 83.300062)
			(stroke
				(width 0.1)
				(type default)
			)
			(layer "F.Fab")
		)
		(fp_text user "32"
			(at -3.66268 79.554324 0)
			(unlocked yes)
			(layer "F.SilkS")
			(effects
				(font
					(size 0.7874 0.5842)
					(thickness 0.1524)
				)
				(justify left)
			)
		)
		(fp_text user "1"
			(at -3.093974 -0.810768 0)
			(unlocked yes)
			(layer "F.SilkS")
			(effects
				(font
					(size 0.7874 0.5842)
					(thickness 0.1524)
				)
				(justify left)
			)
		)
		(fp_text user "64"
			(at 7.495794 -0.366014 0)
			(unlocked yes)
			(layer "F.SilkS")
			(effects
				(font
					(size 0.7874 0.5842)
					(thickness 0.1524)
				)
				(justify left)
			)
		)
		(fp_text user "33"
			(at 7.680706 82.813906 0)
			(unlocked yes)
			(layer "F.SilkS")
			(effects
				(font
					(size 0.7874 0.5842)
					(thickness 0.1524)
				)
				(justify left)
			)
		)
		(fp_text user "1"
			(at -1.689608 -0.958596 0)
			(unlocked yes)
			(layer "B.SilkS")
			(effects
				(font
					(size 0.7874 0.5842)
					(thickness 0.1524)
				)
				(justify left mirror)
			)
		)
		(fp_text user "32"
			(at -0.73152 79.809086 0)
			(unlocked yes)
			(layer "B.SilkS")
			(effects
				(font
					(size 0.7874 0.5842)
					(thickness 0.1524)
				)
				(justify left mirror)
			)
		)
		(fp_text user "64"
			(at 5.89153 -1.71323 0)
			(unlocked yes)
			(layer "B.SilkS")
			(effects
				(font
					(size 0.7874 0.5842)
					(thickness 0.1524)
				)
				(justify left mirror)
			)
		)
		(fp_text user "33"
			(at 6.095238 82.893154 0)
			(unlocked yes)
			(layer "B.SilkS")
			(effects
				(font
					(size 0.7874 0.5842)
					(thickness 0.1524)
				)
				(justify left mirror)
			)
		)
		(pad "1" thru_hole rect
			(at 0 0 270)
			(size 1.6256 1.6256)
			(drill 1.1176)
			(layers "*.Cu" "*.Mask")
			(remove_unused_layers no)
			(net "P12V")
			(clearance 0)
			(padstack
				(mode front_inner_back)
				(layer "Inner"
					(shape circle)
					(size 1.6256 1.6256)
					(clearance 0)
				)
				(layer "B.Cu"
					(shape rect)
					(size 1.6256 1.6256)
					(clearance 0)
				)
			)
		)
		(pad "2" thru_hole circle
			(at 0 2.54 270)
			(size 1.6256 1.6256)
			(drill 1.1176)
			(layers "*.Cu" "*.Mask")
			(remove_unused_layers no)
			(net "P12V")
			(clearance 0)
		)
		(pad "3" thru_hole circle
			(at 0 5.08 270)
			(size 1.6256 1.6256)
			(drill 1.1176)
			(layers "*.Cu" "*.Mask")
			(remove_unused_layers no)
			(net "P12V")
			(clearance 0)
		)
		(pad "4" thru_hole circle
			(at 0 7.62 270)
			(size 1.6256 1.6256)
			(drill 1.1176)
			(layers "*.Cu" "*.Mask")
			(remove_unused_layers no)
			(net "P12V")
			(clearance 0)
		)
		(pad "5" thru_hole circle
			(at 0 10.16 270)
			(size 1.6256 1.6256)
			(drill 1.1176)
			(layers "*.Cu" "*.Mask")
			(remove_unused_layers no)
			(net "P12V")
			(clearance 0)
		)
		(pad "6" thru_hole circle
			(at 0 12.7 270)
			(size 1.6256 1.6256)
			(drill 1.1176)
			(layers "*.Cu" "*.Mask")
			(remove_unused_layers no)
			(net "P12V")
			(clearance 0)
		)
		(pad "7" thru_hole circle
			(at 0 15.24 270)
			(size 1.6256 1.6256)
			(drill 1.1176)
			(layers "*.Cu" "*.Mask")
			(remove_unused_layers no)
			(net "P12V")
			(clearance 0)
		)
		(pad "8" thru_hole circle
			(at 0 17.78 270)
			(size 1.6256 1.6256)
			(drill 1.1176)
			(layers "*.Cu" "*.Mask")
			(remove_unused_layers no)
			(net "P12V")
			(clearance 0)
		)
		(pad "9" thru_hole circle
			(at 0 20.32 270)
			(size 1.6256 1.6256)
			(drill 1.1176)
			(layers "*.Cu" "*.Mask")
			(remove_unused_layers no)
			(net "P12V")
			(clearance 0)
		)
		(pad "10" thru_hole circle
			(at 0 22.86 270)
			(size 1.6256 1.6256)
			(drill 1.1176)
			(layers "*.Cu" "*.Mask")
			(remove_unused_layers no)
			(net "P12V")
			(clearance 0)
		)
		(pad "11" thru_hole circle
			(at 0 25.4 270)
			(size 1.6256 1.6256)
			(drill 1.1176)
			(layers "*.Cu" "*.Mask")
			(remove_unused_layers no)
			(net "P12V")
			(clearance 0)
		)
		(pad "12" thru_hole circle
			(at 0 27.94 270)
			(size 1.6256 1.6256)
			(drill 1.1176)
			(layers "*.Cu" "*.Mask")
			(remove_unused_layers no)
			(net "P12V")
			(clearance 0)
		)
		(pad "13" thru_hole circle
			(at 0 30.48 270)
			(size 1.6256 1.6256)
			(drill 1.1176)
			(layers "*.Cu" "*.Mask")
			(remove_unused_layers no)
			(net "GND")
			(clearance 0)
		)
		(pad "14" thru_hole circle
			(at 0 33.02 270)
			(size 1.6256 1.6256)
			(drill 1.1176)
			(layers "*.Cu" "*.Mask")
			(remove_unused_layers no)
			(net "GND")
			(clearance 0)
		)
		(pad "15" thru_hole circle
			(at 0 35.56 270)
			(size 1.6256 1.6256)
			(drill 1.1176)
			(layers "*.Cu" "*.Mask")
			(remove_unused_layers no)
			(net "GND")
			(clearance 0)
		)
		(pad "16" thru_hole circle
			(at 0 38.1 270)
			(size 1.6256 1.6256)
			(drill 1.1176)
			(layers "*.Cu" "*.Mask")
			(remove_unused_layers no)
			(net "GND")
			(clearance 0)
		)
		(pad "17" thru_hole circle
			(at 0 40.64 270)
			(size 1.6256 1.6256)
			(drill 1.1176)
			(layers "*.Cu" "*.Mask")
			(remove_unused_layers no)
			(net "GND")
			(clearance 0)
		)
		(pad "18" thru_hole circle
			(at 0 43.18 270)
			(size 1.6256 1.6256)
			(drill 1.1176)
			(layers "*.Cu" "*.Mask")
			(remove_unused_layers no)
			(net "GND")
			(clearance 0)
		)
		(pad "19" thru_hole circle
			(at 0 45.72 270)
			(size 1.6256 1.6256)
			(drill 1.1176)
			(layers "*.Cu" "*.Mask")
			(remove_unused_layers no)
			(net "GND")
			(clearance 0)
		)
		(pad "20" thru_hole circle
			(at 0 48.26 270)
			(size 1.6256 1.6256)
			(drill 1.1176)
			(layers "*.Cu" "*.Mask")
			(remove_unused_layers no)
			(net "GND")
			(clearance 0)
		)
		(pad "21" thru_hole circle
			(at 0 50.8 270)
			(size 1.6256 1.6256)
			(drill 1.1176)
			(layers "*.Cu" "*.Mask")
			(remove_unused_layers no)
			(net "GND")
			(clearance 0)
		)
		(pad "22" thru_hole circle
			(at 0 53.34 270)
			(size 1.6256 1.6256)
			(drill 1.1176)
			(layers "*.Cu" "*.Mask")
			(remove_unused_layers no)
			(net "GND")
			(clearance 0)
		)
		(pad "23" thru_hole circle
			(at 0 55.88 270)
			(size 1.6256 1.6256)
			(drill 1.1176)
			(layers "*.Cu" "*.Mask")
			(remove_unused_layers no)
			(net "GND")
			(clearance 0)
		)
		(pad "24" thru_hole circle
			(at 0 58.42 270)
			(size 1.6256 1.6256)
			(drill 1.1176)
			(layers "*.Cu" "*.Mask")
			(remove_unused_layers no)
			(net "GND")
			(clearance 0)
		)
		(pad "25" thru_hole circle
			(at 0 60.96 270)
			(size 1.6256 1.6256)
			(drill 1.1176)
			(layers "*.Cu" "*.Mask")
			(remove_unused_layers no)
			(net "Net_403")
			(clearance 0)
		)
		(pad "26" thru_hole circle
			(at 0 63.5 270)
			(size 1.6256 1.6256)
			(drill 1.1176)
			(layers "*.Cu" "*.Mask")
			(remove_unused_layers no)
			(net "PSU3_REMOTE_N")
			(clearance 0)
		)
		(pad "27" thru_hole circle
			(at 0 66.04 270)
			(size 1.6256 1.6256)
			(drill 1.1176)
			(layers "*.Cu" "*.Mask")
			(remove_unused_layers no)
			(net "PSU3_AC_OK")
			(clearance 0)
		)
		(pad "28" thru_hole circle
			(at 0 68.58 270)
			(size 1.6256 1.6256)
			(drill 1.1176)
			(layers "*.Cu" "*.Mask")
			(remove_unused_layers no)
			(net "PSU3_CSAHRE")
			(clearance 0)
		)
		(pad "29" thru_hole circle
			(at 0 71.12 270)
			(size 1.6256 1.6256)
			(drill 1.1176)
			(layers "*.Cu" "*.Mask")
			(remove_unused_layers no)
			(net "PSU3_PS_ON_N")
			(clearance 0)
		)
		(pad "30" thru_hole circle
			(at 0 73.66 270)
			(size 1.6256 1.6256)
			(drill 1.1176)
			(layers "*.Cu" "*.Mask")
			(remove_unused_layers no)
			(net "PSU3_PS_KILL")
			(clearance 0)
		)
		(pad "31" thru_hole circle
			(at 0 76.2 270)
			(size 1.6256 1.6256)
			(drill 1.1176)
			(layers "*.Cu" "*.Mask")
			(remove_unused_layers no)
			(net "PSU3_RESET")
			(clearance 0)
		)
		(pad "32" thru_hole circle
			(at 0 78.74 270)
			(size 1.6256 1.6256)
			(drill 1.1176)
			(layers "*.Cu" "*.Mask")
			(remove_unused_layers no)
			(net "PSU_ALERT_N")
			(clearance 0)
		)
		(pad "33" thru_hole circle
			(at 5.08 78.74 270)
			(size 1.6256 1.6256)
			(drill 1.1176)
			(layers "*.Cu" "*.Mask")
			(remove_unused_layers no)
			(net "I2C_PSU2_SDA")
			(clearance 0)
		)
		(pad "34" thru_hole circle
			(at 5.08 76.2 270)
			(size 1.6256 1.6256)
			(drill 1.1176)
			(layers "*.Cu" "*.Mask")
			(remove_unused_layers no)
			(net "Net_404")
			(clearance 0)
		)
		(pad "35" thru_hole circle
			(at 5.08 73.66 270)
			(size 1.6256 1.6256)
			(drill 1.1176)
			(layers "*.Cu" "*.Mask")
			(remove_unused_layers no)
			(net "I2C_PSU2_SCL")
			(clearance 0)
		)
		(pad "36" thru_hole circle
			(at 5.08 71.12 270)
			(size 1.6256 1.6256)
			(drill 1.1176)
			(layers "*.Cu" "*.Mask")
			(remove_unused_layers no)
			(net "PSU3_RETURN")
			(clearance 0)
		)
		(pad "37" thru_hole circle
			(at 5.08 68.58 270)
			(size 1.6256 1.6256)
			(drill 1.1176)
			(layers "*.Cu" "*.Mask")
			(remove_unused_layers no)
			(net "PSU3_DC_OK")
			(clearance 0)
		)
		(pad "38" thru_hole circle
			(at 5.08 66.04 270)
			(size 1.6256 1.6256)
			(drill 1.1176)
			(layers "*.Cu" "*.Mask")
			(remove_unused_layers no)
			(net "PSU3_AD0")
			(clearance 0)
		)
		(pad "39" thru_hole circle
			(at 5.08 63.5 270)
			(size 1.6256 1.6256)
			(drill 1.1176)
			(layers "*.Cu" "*.Mask")
			(remove_unused_layers no)
			(net "P12V_STBY")
			(clearance 0)
		)
		(pad "40" thru_hole circle
			(at 5.08 60.96 270)
			(size 1.6256 1.6256)
			(drill 1.1176)
			(layers "*.Cu" "*.Mask")
			(remove_unused_layers no)
			(net "PSU3_REMOTE_P")
			(clearance 0)
		)
		(pad "41" thru_hole circle
			(at 5.08 58.42 270)
			(size 1.6256 1.6256)
			(drill 1.1176)
			(layers "*.Cu" "*.Mask")
			(remove_unused_layers no)
			(net "GND")
			(clearance 0)
		)
		(pad "42" thru_hole circle
			(at 5.08 55.88 270)
			(size 1.6256 1.6256)
			(drill 1.1176)
			(layers "*.Cu" "*.Mask")
			(remove_unused_layers no)
			(net "GND")
			(clearance 0)
		)
		(pad "43" thru_hole circle
			(at 5.08 53.34 270)
			(size 1.6256 1.6256)
			(drill 1.1176)
			(layers "*.Cu" "*.Mask")
			(remove_unused_layers no)
			(net "GND")
			(clearance 0)
		)
		(pad "44" thru_hole circle
			(at 5.08 50.8 270)
			(size 1.6256 1.6256)
			(drill 1.1176)
			(layers "*.Cu" "*.Mask")
			(remove_unused_layers no)
			(net "GND")
			(clearance 0)
		)
		(pad "45" thru_hole circle
			(at 5.08 48.26 270)
			(size 1.6256 1.6256)
			(drill 1.1176)
			(layers "*.Cu" "*.Mask")
			(remove_unused_layers no)
			(net "GND")
			(clearance 0)
		)
		(pad "46" thru_hole circle
			(at 5.08 45.72 270)
			(size 1.6256 1.6256)
			(drill 1.1176)
			(layers "*.Cu" "*.Mask")
			(remove_unused_layers no)
			(net "GND")
			(clearance 0)
		)
		(pad "47" thru_hole circle
			(at 5.08 43.18 270)
			(size 1.6256 1.6256)
			(drill 1.1176)
			(layers "*.Cu" "*.Mask")
			(remove_unused_layers no)
			(net "GND")
			(clearance 0)
		)
		(pad "48" thru_hole circle
			(at 5.08 40.64 270)
			(size 1.6256 1.6256)
			(drill 1.1176)
			(layers "*.Cu" "*.Mask")
			(remove_unused_layers no)
			(net "GND")
			(clearance 0)
		)
		(pad "49" thru_hole circle
			(at 5.08 38.1 270)
			(size 1.6256 1.6256)
			(drill 1.1176)
			(layers "*.Cu" "*.Mask")
			(remove_unused_layers no)
			(net "GND")
			(clearance 0)
		)
		(pad "50" thru_hole circle
			(at 5.08 35.56 270)
			(size 1.6256 1.6256)
			(drill 1.1176)
			(layers "*.Cu" "*.Mask")
			(remove_unused_layers no)
			(net "GND")
			(clearance 0)
		)
		(pad "51" thru_hole circle
			(at 5.08 33.02 270)
			(size 1.6256 1.6256)
			(drill 1.1176)
			(layers "*.Cu" "*.Mask")
			(remove_unused_layers no)
			(net "GND")
			(clearance 0)
		)
		(pad "52" thru_hole circle
			(at 5.08 30.48 270)
			(size 1.6256 1.6256)
			(drill 1.1176)
			(layers "*.Cu" "*.Mask")
			(remove_unused_layers no)
			(net "GND")
			(clearance 0)
		)
		(pad "53" thru_hole circle
			(at 5.08 27.94 270)
			(size 1.6256 1.6256)
			(drill 1.1176)
			(layers "*.Cu" "*.Mask")
			(remove_unused_layers no)
			(net "P12V")
			(clearance 0)
		)
		(pad "54" thru_hole circle
			(at 5.08 25.4 270)
			(size 1.6256 1.6256)
			(drill 1.1176)
			(layers "*.Cu" "*.Mask")
			(remove_unused_layers no)
			(net "P12V")
			(clearance 0)
		)
		(pad "55" thru_hole circle
			(at 5.08 22.86 270)
			(size 1.6256 1.6256)
			(drill 1.1176)
			(layers "*.Cu" "*.Mask")
			(remove_unused_layers no)
			(net "P12V")
			(clearance 0)
		)
		(pad "56" thru_hole circle
			(at 5.08 20.32 270)
			(size 1.6256 1.6256)
			(drill 1.1176)
			(layers "*.Cu" "*.Mask")
			(remove_unused_layers no)
			(net "P12V")
			(clearance 0)
		)
		(pad "57" thru_hole circle
			(at 5.08 17.78 270)
			(size 1.6256 1.6256)
			(drill 1.1176)
			(layers "*.Cu" "*.Mask")
			(remove_unused_layers no)
			(net "P12V")
			(clearance 0)
		)
		(pad "58" thru_hole circle
			(at 5.08 15.24 270)
			(size 1.6256 1.6256)
			(drill 1.1176)
			(layers "*.Cu" "*.Mask")
			(remove_unused_layers no)
			(net "P12V")
			(clearance 0)
		)
		(pad "59" thru_hole circle
			(at 5.08 12.7 270)
			(size 1.6256 1.6256)
			(drill 1.1176)
			(layers "*.Cu" "*.Mask")
			(remove_unused_layers no)
			(net "P12V")
			(clearance 0)
		)
		(pad "60" thru_hole circle
			(at 5.08 10.16 270)
			(size 1.6256 1.6256)
			(drill 1.1176)
			(layers "*.Cu" "*.Mask")
			(remove_unused_layers no)
			(net "P12V")
			(clearance 0)
		)
		(pad "61" thru_hole circle
			(at 5.08 7.62 270)
			(size 1.6256 1.6256)
			(drill 1.1176)
			(layers "*.Cu" "*.Mask")
			(remove_unused_layers no)
			(net "P12V")
			(clearance 0)
		)
		(pad "62" thru_hole circle
			(at 5.08 5.08 270)
			(size 1.6256 1.6256)
			(drill 1.1176)
			(layers "*.Cu" "*.Mask")
			(remove_unused_layers no)
			(net "P12V")
			(clearance 0)
		)
		(pad "63" thru_hole circle
			(at 5.08 2.54 270)
			(size 1.6256 1.6256)
			(drill 1.1176)
			(layers "*.Cu" "*.Mask")
			(remove_unused_layers no)
			(net "P12V")
			(clearance 0)
		)
		(pad "64" thru_hole circle
			(at 5.08 0 270)
			(size 1.6256 1.6256)
			(drill 1.1176)
			(layers "*.Cu" "*.Mask")
			(remove_unused_layers no)
			(net "P12V")
			(clearance 0)
		)
	)
	(footprint ""
		(layer "F.Cu")
		(at 16.599916 -295.89984)
		(property "Reference" "H4"
			(at -1.466596 -9.400032 0)
			(unlocked yes)
			(layer "F.SilkS")
			(effects
				(font
					(size 0.7874 0.5842)
					(thickness 0.1524)
				)
				(justify left)
			)
		)
		(property "Value" ""
			(at 0 0 0)
			(layer "F.Fab")
			(effects
				(font
					(size 1.27 1.27)
				)
			)
		)
		(duplicate_pad_numbers_are_jumpers no)
		(fp_circle
			(center 0 0)
			(end 7.999984 0)
			(stroke
				(width 0.1524)
				(type default)
			)
			(fill no)
			(layer "F.SilkS")
		)
		(fp_circle
			(center 0 0)
			(end 14.7066 0)
			(stroke
				(width 0.1524)
				(type default)
			)
			(fill no)
			(layer "B.SilkS")
		)
		(fp_poly
			(pts
				(arc
					(start 0 5.0038)
					(mid 0 -5.0038)
					(end 0 5.0038)
				)
			)
			(stroke
				(width 0)
				(type default)
			)
			(fill no)
			(layer "F.CrtYd")
		)
		(pad "" np_thru_hole circle
			(at 0 0)
			(size 4.0132 4.0132)
			(drill 4.0132)
			(layers "*.Cu" "*.Mask")
			(clearance 0.381)
			(thermal_gap 0.381)
		)
		(pad "2" thru_hole circle
			(at 0 -3.50012)
			(size 0.762 0.762)
			(drill 0.5588)
			(layers "*.Cu" "*.Mask")
			(remove_unused_layers no)
			(net "GND")
			(clearance 0.1524)
			(thermal_gap 0.1524)
		)
		(pad "3" thru_hole circle
			(at -2.500122 -2.500122)
			(size 0.762 0.762)
			(drill 0.5588)
			(layers "*.Cu" "*.Mask")
			(remove_unused_layers no)
			(net "GND")
			(clearance 0.1524)
			(thermal_gap 0.1524)
		)
		(pad "4" thru_hole circle
			(at -3.50012 0)
			(size 0.762 0.762)
			(drill 0.5588)
			(layers "*.Cu" "*.Mask")
			(remove_unused_layers no)
			(net "GND")
			(clearance 0.1524)
			(thermal_gap 0.1524)
		)
		(pad "5" thru_hole circle
			(at -2.500122 2.500122)
			(size 0.762 0.762)
			(drill 0.5588)
			(layers "*.Cu" "*.Mask")
			(remove_unused_layers no)
			(net "GND")
			(clearance 0.1524)
			(thermal_gap 0.1524)
		)
		(pad "6" thru_hole circle
			(at 0 3.50012)
			(size 0.762 0.762)
			(drill 0.5588)
			(layers "*.Cu" "*.Mask")
			(remove_unused_layers no)
			(net "GND")
			(clearance 0.1524)
			(thermal_gap 0.1524)
		)
		(pad "7" thru_hole circle
			(at 2.500122 2.500122)
			(size 0.762 0.762)
			(drill 0.5588)
			(layers "*.Cu" "*.Mask")
			(remove_unused_layers no)
			(net "GND")
			(clearance 0.1524)
			(thermal_gap 0.1524)
		)
		(pad "8" thru_hole circle
			(at 3.50012 0)
			(size 0.762 0.762)
			(drill 0.5588)
			(layers "*.Cu" "*.Mask")
			(remove_unused_layers no)
			(net "GND")
			(clearance 0.1524)
			(thermal_gap 0.1524)
		)
		(pad "9" thru_hole circle
			(at 2.500122 -2.500122)
			(size 0.762 0.762)
			(drill 0.5588)
			(layers "*.Cu" "*.Mask")
			(remove_unused_layers no)
			(net "GND")
			(clearance 0.1524)
			(thermal_gap 0.1524)
		)
		(zone
			(layer "F.Cu")
			(hatch none 0.5)
			(connect_pads
				(clearance 0)
			)
			(min_thickness 0.25)
			(keepout
				(tracks not_allowed)
				(vias allowed)
				(pads allowed)
				(copperpour not_allowed)
				(footprints allowed)
			)
			(placement
				(enabled no)
				(sheetname "")
			)
			(fill
				(thermal_gap 0.5)
				(thermal_bridge_width 0.5)
				(island_removal_mode 0)
			)
			(polygon
				(pts
					(arc
						(start 16.599916 -303.90084)
						(mid 8.598916 -295.89984)
						(end 16.599916 -287.89884)
					)
					(arc
						(start 16.599916 -287.89884)
						(mid 18.035016 -289.33394)
						(end 16.599916 -290.76904)
					)
					(arc
						(start 16.599916 -290.76904)
						(mid 11.469116 -295.89984)
						(end 16.599916 -301.03064)
					)
					(arc
						(start 16.599916 -301.03064)
						(mid 18.035016 -302.46574)
						(end 16.599916 -303.90084)
					)
				)
			)
		)
		(zone
			(layer "F.Cu")
			(hatch none 0.5)
			(connect_pads
				(clearance 0)
			)
			(min_thickness 0.25)
			(keepout
				(tracks not_allowed)
				(vias allowed)
				(pads allowed)
				(copperpour not_allowed)
				(footprints allowed)
			)
			(placement
				(enabled no)
				(sheetname "")
			)
			(fill
				(thermal_gap 0.5)
				(thermal_bridge_width 0.5)
				(island_removal_mode 0)
			)
			(polygon
				(pts
					(arc
						(start 16.599916 -303.90084)
						(mid 24.600916 -295.89984)
						(end 16.599916 -287.89884)
					)
					(arc
						(start 16.599916 -287.89884)
						(mid 15.164816 -289.33394)
						(end 16.599916 -290.76904)
					)
					(arc
						(start 16.599916 -290.76904)
						(mid 21.730716 -295.89984)
						(end 16.599916 -301.03064)
					)
					(arc
						(start 16.599916 -301.03064)
						(mid 15.164816 -302.46574)
						(end 16.599916 -303.90084)
					)
				)
			)
		)
		(zone
			(layers "F.Cu" "B.Cu" "In1.Cu" "In2.Cu" "In3.Cu" "In4.Cu" "In5.Cu" "In6.Cu")
			(hatch none 0.5)
			(connect_pads
				(clearance 0)
			)
			(min_thickness 0.25)
			(keepout
				(tracks not_allowed)
				(vias allowed)
				(pads allowed)
				(copperpour not_allowed)
				(footprints allowed)
			)
			(placement
				(enabled no)
				(sheetname "")
			)
			(fill
				(thermal_gap 0.5)
				(thermal_bridge_width 0.5)
				(island_removal_mode 0)
			)
			(polygon
				(pts
					(arc
						(start 16.599916 -293.38778)
						(mid 16.599916 -298.4119)
						(end 16.599916 -293.38778)
					)
				)
			)
		)
	)
	(footprint ""
		(layer "F.Cu")
		(at 16.599916 -118.09984)
		(property "Reference" "H10"
			(at -7.888224 -6.127242 0)
			(unlocked yes)
			(layer "F.SilkS")
			(effects
				(font
					(size 0.7874 0.5842)
					(thickness 0.1524)
				)
				(justify left)
			)
		)
		(property "Value" ""
			(at 0 0 0)
			(layer "F.Fab")
			(effects
				(font
					(size 1.27 1.27)
				)
			)
		)
		(duplicate_pad_numbers_are_jumpers no)
		(fp_circle
			(center 0 0)
			(end 7.999984 0)
			(stroke
				(width 0.1524)
				(type default)
			)
			(fill no)
			(layer "F.SilkS")
		)
		(fp_circle
			(center 0 0)
			(end 14.7066 0)
			(stroke
				(width 0.1524)
				(type default)
			)
			(fill no)
			(layer "B.SilkS")
		)
		(fp_poly
			(pts
				(arc
					(start 0 5.0038)
					(mid 0 -5.0038)
					(end 0 5.0038)
				)
			)
			(stroke
				(width 0)
				(type default)
			)
			(fill no)
			(layer "F.CrtYd")
		)
		(pad "" np_thru_hole circle
			(at 0 0)
			(size 4.0132 4.0132)
			(drill 4.0132)
			(layers "*.Cu" "*.Mask")
			(clearance 0.381)
			(thermal_gap 0.381)
		)
		(pad "2" thru_hole circle
			(at 0 -3.50012)
			(size 0.762 0.762)
			(drill 0.5588)
			(layers "*.Cu" "*.Mask")
			(remove_unused_layers no)
			(net "GND")
			(clearance 0.1524)
			(thermal_gap 0.1524)
		)
		(pad "3" thru_hole circle
			(at -2.500122 -2.500122)
			(size 0.762 0.762)
			(drill 0.5588)
			(layers "*.Cu" "*.Mask")
			(remove_unused_layers no)
			(net "GND")
			(clearance 0.1524)
			(thermal_gap 0.1524)
		)
		(pad "4" thru_hole circle
			(at -3.50012 0)
			(size 0.762 0.762)
			(drill 0.5588)
			(layers "*.Cu" "*.Mask")
			(remove_unused_layers no)
			(net "GND")
			(clearance 0.1524)
			(thermal_gap 0.1524)
		)
		(pad "5" thru_hole circle
			(at -2.500122 2.500122)
			(size 0.762 0.762)
			(drill 0.5588)
			(layers "*.Cu" "*.Mask")
			(remove_unused_layers no)
			(net "GND")
			(clearance 0.1524)
			(thermal_gap 0.1524)
		)
		(pad "6" thru_hole circle
			(at 0 3.50012)
			(size 0.762 0.762)
			(drill 0.5588)
			(layers "*.Cu" "*.Mask")
			(remove_unused_layers no)
			(net "GND")
			(clearance 0.1524)
			(thermal_gap 0.1524)
		)
		(pad "7" thru_hole circle
			(at 2.500122 2.500122)
			(size 0.762 0.762)
			(drill 0.5588)
			(layers "*.Cu" "*.Mask")
			(remove_unused_layers no)
			(net "GND")
			(clearance 0.1524)
			(thermal_gap 0.1524)
		)
		(pad "8" thru_hole circle
			(at 3.50012 0)
			(size 0.762 0.762)
			(drill 0.5588)
			(layers "*.Cu" "*.Mask")
			(remove_unused_layers no)
			(net "GND")
			(clearance 0.1524)
			(thermal_gap 0.1524)
		)
		(pad "9" thru_hole circle
			(at 2.500122 -2.500122)
			(size 0.762 0.762)
			(drill 0.5588)
			(layers "*.Cu" "*.Mask")
			(remove_unused_layers no)
			(net "GND")
			(clearance 0.1524)
			(thermal_gap 0.1524)
		)
		(zone
			(layer "F.Cu")
			(hatch none 0.5)
			(connect_pads
				(clearance 0)
			)
			(min_thickness 0.25)
			(keepout
				(tracks not_allowed)
				(vias allowed)
				(pads allowed)
				(copperpour not_allowed)
				(footprints allowed)
			)
			(placement
				(enabled no)
				(sheetname "")
			)
			(fill
				(thermal_gap 0.5)
				(thermal_bridge_width 0.5)
				(island_removal_mode 0)
			)
			(polygon
				(pts
					(arc
						(start 16.599916 -126.10084)
						(mid 8.598916 -118.09984)
						(end 16.599916 -110.09884)
					)
					(arc
						(start 16.599916 -110.09884)
						(mid 18.035016 -111.53394)
						(end 16.599916 -112.96904)
					)
					(arc
						(start 16.599916 -112.96904)
						(mid 11.469116 -118.09984)
						(end 16.599916 -123.23064)
					)
					(arc
						(start 16.599916 -123.23064)
						(mid 18.035016 -124.66574)
						(end 16.599916 -126.10084)
					)
				)
			)
		)
		(zone
			(layer "F.Cu")
			(hatch none 0.5)
			(connect_pads
				(clearance 0)
			)
			(min_thickness 0.25)
			(keepout
				(tracks not_allowed)
				(vias allowed)
				(pads allowed)
				(copperpour not_allowed)
				(footprints allowed)
			)
			(placement
				(enabled no)
				(sheetname "")
			)
			(fill
				(thermal_gap 0.5)
				(thermal_bridge_width 0.5)
				(island_removal_mode 0)
			)
			(polygon
				(pts
					(arc
						(start 16.599916 -126.10084)
						(mid 24.600916 -118.09984)
						(end 16.599916 -110.09884)
					)
					(arc
						(start 16.599916 -110.09884)
						(mid 15.164816 -111.53394)
						(end 16.599916 -112.96904)
					)
					(arc
						(start 16.599916 -112.96904)
						(mid 21.730716 -118.09984)
						(end 16.599916 -123.23064)
					)
					(arc
						(start 16.599916 -123.23064)
						(mid 15.164816 -124.66574)
						(end 16.599916 -126.10084)
					)
				)
			)
		)
		(zone
			(layers "F.Cu" "B.Cu" "In1.Cu" "In2.Cu" "In3.Cu" "In4.Cu" "In5.Cu" "In6.Cu")
			(hatch none 0.5)
			(connect_pads
				(clearance 0)
			)
			(min_thickness 0.25)
			(keepout
				(tracks not_allowed)
				(vias allowed)
				(pads allowed)
				(copperpour not_allowed)
				(footprints allowed)
			)
			(placement
				(enabled no)
				(sheetname "")
			)
			(fill
				(thermal_gap 0.5)
				(thermal_bridge_width 0.5)
				(island_removal_mode 0)
			)
			(polygon
				(pts
					(arc
						(start 16.599916 -115.58778)
						(mid 16.599916 -120.6119)
						(end 16.599916 -115.58778)
					)
				)
			)
		)
	)
	(footprint ""
		(layer "F.Cu")
		(at 30.45968 -83.330034)
		(property "Reference" "J1"
			(at 7.517892 2.350516 0)
			(unlocked yes)
			(layer "F.SilkS")
			(effects
				(font
					(size 0.7874 0.5842)
					(thickness 0.1524)
				)
				(justify left)
			)
		)
		(property "Value" ""
			(at 0 0 0)
			(layer "F.Fab")
			(effects
				(font
					(size 1.27 1.27)
				)
			)
		)
		(duplicate_pad_numbers_are_jumpers no)
		(fp_line
			(start -2.135124 -4.560062)
			(end -2.135124 83.300062)
			(stroke
				(width 0.1524)
				(type default)
			)
			(layer "F.SilkS")
		)
		(fp_line
			(start -2.135124 83.300062)
			(end 7.215124 83.300062)
			(stroke
				(width 0.1524)
				(type default)
			)
			(layer "F.SilkS")
		)
		(fp_line
			(start 7.215124 -4.560062)
			(end -2.135124 -4.560062)
			(stroke
				(width 0.1524)
				(type default)
			)
			(layer "F.SilkS")
		)
		(fp_line
			(start 7.215124 83.300062)
			(end 7.215124 -4.560062)
			(stroke
				(width 0.1524)
				(type default)
			)
			(layer "F.SilkS")
		)
		(fp_poly
			(pts
				(xy -2.467864 0.208026) (xy -5.167884 -0.491998) (xy -5.167884 0.90805)
			)
			(stroke
				(width 0)
				(type default)
			)
			(fill yes)
			(layer "F.SilkS")
		)
		(fp_poly
			(pts
				(xy -2.28219 -0.127) (xy -4.98221 -0.827024) (xy -4.98221 0.573024)
			)
			(stroke
				(width 0)
				(type default)
			)
			(fill yes)
			(layer "B.SilkS")
		)
		(fp_poly
			(pts
				(xy -0.8636 -0.8636) (xy -0.8636 79.6036) (xy -0.8636 79.629) (xy 5.9436 79.629) (xy 5.9436 79.6036)
				(xy 5.9436 -0.8636) (xy 5.9436 -0.889) (xy -0.8636 -0.889)
			)
			(stroke
				(width 0)
				(type default)
			)
			(fill no)
			(layer "B.CrtYd")
		)
		(fp_rect
			(start -2.135124 -4.560062)
			(end 7.21487 83.300062)
			(stroke
				(width 0)
				(type default)
			)
			(fill no)
			(layer "F.CrtYd")
		)
		(fp_line
			(start -2.135124 -4.560062)
			(end 7.215124 -4.560062)
			(stroke
				(width 0.1)
				(type default)
			)
			(layer "F.Fab")
		)
		(fp_line
			(start -2.135124 83.300062)
			(end -2.135124 -4.560062)
			(stroke
				(width 0.1)
				(type default)
			)
			(layer "F.Fab")
		)
		(fp_line
			(start 7.215124 -4.560062)
			(end 7.215124 83.300062)
			(stroke
				(width 0.1)
				(type default)
			)
			(layer "F.Fab")
		)
		(fp_line
			(start 7.215124 83.300062)
			(end -2.135124 83.300062)
			(stroke
				(width 0.1)
				(type default)
			)
			(layer "F.Fab")
		)
		(fp_text user "1"
			(at -3.01625 -0.658368 0)
			(unlocked yes)
			(layer "F.SilkS")
			(effects
				(font
					(size 0.7874 0.5842)
					(thickness 0.1524)
				)
				(justify left)
			)
		)
		(fp_text user "32"
			(at -1.971802 79.99095 0)
			(unlocked yes)
			(layer "F.SilkS")
			(effects
				(font
					(size 0.7874 0.5842)
					(thickness 0.1524)
				)
				(justify left)
			)
		)
		(fp_text user "33"
			(at 7.57428 78.22184 0)
			(unlocked yes)
			(layer "F.SilkS")
			(effects
				(font
					(size 0.7874 0.5842)
					(thickness 0.1524)
				)
				(justify left)
			)
		)
		(fp_text user "64"
			(at 7.666736 -0.128016 0)
			(unlocked yes)
			(layer "F.SilkS")
			(effects
				(font
					(size 0.7874 0.5842)
					(thickness 0.1524)
				)
				(justify left)
			)
		)
		(fp_text user "32"
			(at -1.060958 79.574644 0)
			(unlocked yes)
			(layer "B.SilkS")
			(effects
				(font
					(size 0.7874 0.5842)
					(thickness 0.1524)
				)
				(justify left mirror)
			)
		)
		(fp_text user "1"
			(at -1.044448 -0.912622 0)
			(unlocked yes)
			(layer "B.SilkS")
			(effects
				(font
					(size 0.7874 0.5842)
					(thickness 0.1524)
				)
				(justify left mirror)
			)
		)
		(fp_text user "64"
			(at 5.82168 -1.531112 0)
			(unlocked yes)
			(layer "B.SilkS")
			(effects
				(font
					(size 0.7874 0.5842)
					(thickness 0.1524)
				)
				(justify left mirror)
			)
		)
		(fp_text user "33"
			(at 6.15696 80.823308 0)
			(unlocked yes)
			(layer "B.SilkS")
			(effects
				(font
					(size 0.7874 0.5842)
					(thickness 0.1524)
				)
				(justify left mirror)
			)
		)
		(pad "1" thru_hole rect
			(at 0 0 270)
			(size 1.6256 1.6256)
			(drill 1.1176)
			(layers "*.Cu" "*.Mask")
			(remove_unused_layers no)
			(net "P12V")
			(clearance 0)
			(padstack
				(mode front_inner_back)
				(layer "Inner"
					(shape circle)
					(size 1.6256 1.6256)
					(clearance 0)
				)
				(layer "B.Cu"
					(shape rect)
					(size 1.6256 1.6256)
					(clearance 0)
				)
			)
		)
		(pad "2" thru_hole circle
			(at 0 2.54 270)
			(size 1.6256 1.6256)
			(drill 1.1176)
			(layers "*.Cu" "*.Mask")
			(remove_unused_layers no)
			(net "P12V")
			(clearance 0)
		)
		(pad "3" thru_hole circle
			(at 0 5.08 270)
			(size 1.6256 1.6256)
			(drill 1.1176)
			(layers "*.Cu" "*.Mask")
			(remove_unused_layers no)
			(net "P12V")
			(clearance 0)
		)
		(pad "4" thru_hole circle
			(at 0 7.62 270)
			(size 1.6256 1.6256)
			(drill 1.1176)
			(layers "*.Cu" "*.Mask")
			(remove_unused_layers no)
			(net "P12V")
			(clearance 0)
		)
		(pad "5" thru_hole circle
			(at 0 10.16 270)
			(size 1.6256 1.6256)
			(drill 1.1176)
			(layers "*.Cu" "*.Mask")
			(remove_unused_layers no)
			(net "P12V")
			(clearance 0)
		)
		(pad "6" thru_hole circle
			(at 0 12.7 270)
			(size 1.6256 1.6256)
			(drill 1.1176)
			(layers "*.Cu" "*.Mask")
			(remove_unused_layers no)
			(net "P12V")
			(clearance 0)
		)
		(pad "7" thru_hole circle
			(at 0 15.24 270)
			(size 1.6256 1.6256)
			(drill 1.1176)
			(layers "*.Cu" "*.Mask")
			(remove_unused_layers no)
			(net "P12V")
			(clearance 0)
		)
		(pad "8" thru_hole circle
			(at 0 17.78 270)
			(size 1.6256 1.6256)
			(drill 1.1176)
			(layers "*.Cu" "*.Mask")
			(remove_unused_layers no)
			(net "P12V")
			(clearance 0)
		)
		(pad "9" thru_hole circle
			(at 0 20.32 270)
			(size 1.6256 1.6256)
			(drill 1.1176)
			(layers "*.Cu" "*.Mask")
			(remove_unused_layers no)
			(net "P12V")
			(clearance 0)
		)
		(pad "10" thru_hole circle
			(at 0 22.86 270)
			(size 1.6256 1.6256)
			(drill 1.1176)
			(layers "*.Cu" "*.Mask")
			(remove_unused_layers no)
			(net "P12V")
			(clearance 0)
		)
		(pad "11" thru_hole circle
			(at 0 25.4 270)
			(size 1.6256 1.6256)
			(drill 1.1176)
			(layers "*.Cu" "*.Mask")
			(remove_unused_layers no)
			(net "P12V")
			(clearance 0)
		)
		(pad "12" thru_hole circle
			(at 0 27.94 270)
			(size 1.6256 1.6256)
			(drill 1.1176)
			(layers "*.Cu" "*.Mask")
			(remove_unused_layers no)
			(net "P12V")
			(clearance 0)
		)
		(pad "13" thru_hole circle
			(at 0 30.48 270)
			(size 1.6256 1.6256)
			(drill 1.1176)
			(layers "*.Cu" "*.Mask")
			(remove_unused_layers no)
			(net "GND")
			(clearance 0)
		)
		(pad "14" thru_hole circle
			(at 0 33.02 270)
			(size 1.6256 1.6256)
			(drill 1.1176)
			(layers "*.Cu" "*.Mask")
			(remove_unused_layers no)
			(net "GND")
			(clearance 0)
		)
		(pad "15" thru_hole circle
			(at 0 35.56 270)
			(size 1.6256 1.6256)
			(drill 1.1176)
			(layers "*.Cu" "*.Mask")
			(remove_unused_layers no)
			(net "GND")
			(clearance 0)
		)
		(pad "16" thru_hole circle
			(at 0 38.1 270)
			(size 1.6256 1.6256)
			(drill 1.1176)
			(layers "*.Cu" "*.Mask")
			(remove_unused_layers no)
			(net "GND")
			(clearance 0)
		)
		(pad "17" thru_hole circle
			(at 0 40.64 270)
			(size 1.6256 1.6256)
			(drill 1.1176)
			(layers "*.Cu" "*.Mask")
			(remove_unused_layers no)
			(net "GND")
			(clearance 0)
		)
		(pad "18" thru_hole circle
			(at 0 43.18 270)
			(size 1.6256 1.6256)
			(drill 1.1176)
			(layers "*.Cu" "*.Mask")
			(remove_unused_layers no)
			(net "GND")
			(clearance 0)
		)
		(pad "19" thru_hole circle
			(at 0 45.72 270)
			(size 1.6256 1.6256)
			(drill 1.1176)
			(layers "*.Cu" "*.Mask")
			(remove_unused_layers no)
			(net "GND")
			(clearance 0)
		)
		(pad "20" thru_hole circle
			(at 0 48.26 270)
			(size 1.6256 1.6256)
			(drill 1.1176)
			(layers "*.Cu" "*.Mask")
			(remove_unused_layers no)
			(net "GND")
			(clearance 0)
		)
		(pad "21" thru_hole circle
			(at 0 50.8 270)
			(size 1.6256 1.6256)
			(drill 1.1176)
			(layers "*.Cu" "*.Mask")
			(remove_unused_layers no)
			(net "GND")
			(clearance 0)
		)
		(pad "22" thru_hole circle
			(at 0 53.34 270)
			(size 1.6256 1.6256)
			(drill 1.1176)
			(layers "*.Cu" "*.Mask")
			(remove_unused_layers no)
			(net "GND")
			(clearance 0)
		)
		(pad "23" thru_hole circle
			(at 0 55.88 270)
			(size 1.6256 1.6256)
			(drill 1.1176)
			(layers "*.Cu" "*.Mask")
			(remove_unused_layers no)
			(net "GND")
			(clearance 0)
		)
		(pad "24" thru_hole circle
			(at 0 58.42 270)
			(size 1.6256 1.6256)
			(drill 1.1176)
			(layers "*.Cu" "*.Mask")
			(remove_unused_layers no)
			(net "GND")
			(clearance 0)
		)
		(pad "25" thru_hole circle
			(at 0 60.96 270)
			(size 1.6256 1.6256)
			(drill 1.1176)
			(layers "*.Cu" "*.Mask")
			(remove_unused_layers no)
			(net "Net_407")
			(clearance 0)
		)
		(pad "26" thru_hole circle
			(at 0 63.5 270)
			(size 1.6256 1.6256)
			(drill 1.1176)
			(layers "*.Cu" "*.Mask")
			(remove_unused_layers no)
			(net "PSU1_REMOTE_N")
			(clearance 0)
		)
		(pad "27" thru_hole circle
			(at 0 66.04 270)
			(size 1.6256 1.6256)
			(drill 1.1176)
			(layers "*.Cu" "*.Mask")
			(remove_unused_layers no)
			(net "PSU1_AC_OK")
			(clearance 0)
		)
		(pad "28" thru_hole circle
			(at 0 68.58 270)
			(size 1.6256 1.6256)
			(drill 1.1176)
			(layers "*.Cu" "*.Mask")
			(remove_unused_layers no)
			(net "PSU1_CSAHRE")
			(clearance 0)
		)
		(pad "29" thru_hole circle
			(at 0 71.12 270)
			(size 1.6256 1.6256)
			(drill 1.1176)
			(layers "*.Cu" "*.Mask")
			(remove_unused_layers no)
			(net "PSU1_PS_ON_N")
			(clearance 0)
		)
		(pad "30" thru_hole circle
			(at 0 73.66 270)
			(size 1.6256 1.6256)
			(drill 1.1176)
			(layers "*.Cu" "*.Mask")
			(remove_unused_layers no)
			(net "PSU1_PS_KILL")
			(clearance 0)
		)
		(pad "31" thru_hole circle
			(at 0 76.2 270)
			(size 1.6256 1.6256)
			(drill 1.1176)
			(layers "*.Cu" "*.Mask")
			(remove_unused_layers no)
			(net "PSU1_RESET")
			(clearance 0)
		)
		(pad "32" thru_hole circle
			(at 0 78.74 270)
			(size 1.6256 1.6256)
			(drill 1.1176)
			(layers "*.Cu" "*.Mask")
			(remove_unused_layers no)
			(net "PSU_ALERT_N")
			(clearance 0)
		)
		(pad "33" thru_hole circle
			(at 5.08 78.74 270)
			(size 1.6256 1.6256)
			(drill 1.1176)
			(layers "*.Cu" "*.Mask")
			(remove_unused_layers no)
			(net "I2C_PSU1_SDA")
			(clearance 0)
		)
		(pad "34" thru_hole circle
			(at 5.08 76.2 270)
			(size 1.6256 1.6256)
			(drill 1.1176)
			(layers "*.Cu" "*.Mask")
			(remove_unused_layers no)
			(net "Net_408")
			(clearance 0)
		)
		(pad "35" thru_hole circle
			(at 5.08 73.66 270)
			(size 1.6256 1.6256)
			(drill 1.1176)
			(layers "*.Cu" "*.Mask")
			(remove_unused_layers no)
			(net "I2C_PSU1_SCL")
			(clearance 0)
		)
		(pad "36" thru_hole circle
			(at 5.08 71.12 270)
			(size 1.6256 1.6256)
			(drill 1.1176)
			(layers "*.Cu" "*.Mask")
			(remove_unused_layers no)
			(net "PSU1_RETURN")
			(clearance 0)
		)
		(pad "37" thru_hole circle
			(at 5.08 68.58 270)
			(size 1.6256 1.6256)
			(drill 1.1176)
			(layers "*.Cu" "*.Mask")
			(remove_unused_layers no)
			(net "PSU1_DC_OK")
			(clearance 0)
		)
		(pad "38" thru_hole circle
			(at 5.08 66.04 270)
			(size 1.6256 1.6256)
			(drill 1.1176)
			(layers "*.Cu" "*.Mask")
			(remove_unused_layers no)
			(net "PSU1_AD0")
			(clearance 0)
		)
		(pad "39" thru_hole circle
			(at 5.08 63.5 270)
			(size 1.6256 1.6256)
			(drill 1.1176)
			(layers "*.Cu" "*.Mask")
			(remove_unused_layers no)
			(net "P12V_STBY")
			(clearance 0)
		)
		(pad "40" thru_hole circle
			(at 5.08 60.96 270)
			(size 1.6256 1.6256)
			(drill 1.1176)
			(layers "*.Cu" "*.Mask")
			(remove_unused_layers no)
			(net "PSU1_REMOTE_P")
			(clearance 0)
		)
		(pad "41" thru_hole circle
			(at 5.08 58.42 270)
			(size 1.6256 1.6256)
			(drill 1.1176)
			(layers "*.Cu" "*.Mask")
			(remove_unused_layers no)
			(net "GND")
			(clearance 0)
		)
		(pad "42" thru_hole circle
			(at 5.08 55.88 270)
			(size 1.6256 1.6256)
			(drill 1.1176)
			(layers "*.Cu" "*.Mask")
			(remove_unused_layers no)
			(net "GND")
			(clearance 0)
		)
		(pad "43" thru_hole circle
			(at 5.08 53.34 270)
			(size 1.6256 1.6256)
			(drill 1.1176)
			(layers "*.Cu" "*.Mask")
			(remove_unused_layers no)
			(net "GND")
			(clearance 0)
		)
		(pad "44" thru_hole circle
			(at 5.08 50.8 270)
			(size 1.6256 1.6256)
			(drill 1.1176)
			(layers "*.Cu" "*.Mask")
			(remove_unused_layers no)
			(net "GND")
			(clearance 0)
		)
		(pad "45" thru_hole circle
			(at 5.08 48.26 270)
			(size 1.6256 1.6256)
			(drill 1.1176)
			(layers "*.Cu" "*.Mask")
			(remove_unused_layers no)
			(net "GND")
			(clearance 0)
		)
		(pad "46" thru_hole circle
			(at 5.08 45.72 270)
			(size 1.6256 1.6256)
			(drill 1.1176)
			(layers "*.Cu" "*.Mask")
			(remove_unused_layers no)
			(net "GND")
			(clearance 0)
		)
		(pad "47" thru_hole circle
			(at 5.08 43.18 270)
			(size 1.6256 1.6256)
			(drill 1.1176)
			(layers "*.Cu" "*.Mask")
			(remove_unused_layers no)
			(net "GND")
			(clearance 0)
		)
		(pad "48" thru_hole circle
			(at 5.08 40.64 270)
			(size 1.6256 1.6256)
			(drill 1.1176)
			(layers "*.Cu" "*.Mask")
			(remove_unused_layers no)
			(net "GND")
			(clearance 0)
		)
		(pad "49" thru_hole circle
			(at 5.08 38.1 270)
			(size 1.6256 1.6256)
			(drill 1.1176)
			(layers "*.Cu" "*.Mask")
			(remove_unused_layers no)
			(net "GND")
			(clearance 0)
		)
		(pad "50" thru_hole circle
			(at 5.08 35.56 270)
			(size 1.6256 1.6256)
			(drill 1.1176)
			(layers "*.Cu" "*.Mask")
			(remove_unused_layers no)
			(net "GND")
			(clearance 0)
		)
		(pad "51" thru_hole circle
			(at 5.08 33.02 270)
			(size 1.6256 1.6256)
			(drill 1.1176)
			(layers "*.Cu" "*.Mask")
			(remove_unused_layers no)
			(net "GND")
			(clearance 0)
		)
		(pad "52" thru_hole circle
			(at 5.08 30.48 270)
			(size 1.6256 1.6256)
			(drill 1.1176)
			(layers "*.Cu" "*.Mask")
			(remove_unused_layers no)
			(net "GND")
			(clearance 0)
		)
		(pad "53" thru_hole circle
			(at 5.08 27.94 270)
			(size 1.6256 1.6256)
			(drill 1.1176)
			(layers "*.Cu" "*.Mask")
			(remove_unused_layers no)
			(net "P12V")
			(clearance 0)
		)
		(pad "54" thru_hole circle
			(at 5.08 25.4 270)
			(size 1.6256 1.6256)
			(drill 1.1176)
			(layers "*.Cu" "*.Mask")
			(remove_unused_layers no)
			(net "P12V")
			(clearance 0)
		)
		(pad "55" thru_hole circle
			(at 5.08 22.86 270)
			(size 1.6256 1.6256)
			(drill 1.1176)
			(layers "*.Cu" "*.Mask")
			(remove_unused_layers no)
			(net "P12V")
			(clearance 0)
		)
		(pad "56" thru_hole circle
			(at 5.08 20.32 270)
			(size 1.6256 1.6256)
			(drill 1.1176)
			(layers "*.Cu" "*.Mask")
			(remove_unused_layers no)
			(net "P12V")
			(clearance 0)
		)
		(pad "57" thru_hole circle
			(at 5.08 17.78 270)
			(size 1.6256 1.6256)
			(drill 1.1176)
			(layers "*.Cu" "*.Mask")
			(remove_unused_layers no)
			(net "P12V")
			(clearance 0)
		)
		(pad "58" thru_hole circle
			(at 5.08 15.24 270)
			(size 1.6256 1.6256)
			(drill 1.1176)
			(layers "*.Cu" "*.Mask")
			(remove_unused_layers no)
			(net "P12V")
			(clearance 0)
		)
		(pad "59" thru_hole circle
			(at 5.08 12.7 270)
			(size 1.6256 1.6256)
			(drill 1.1176)
			(layers "*.Cu" "*.Mask")
			(remove_unused_layers no)
			(net "P12V")
			(clearance 0)
		)
		(pad "60" thru_hole circle
			(at 5.08 10.16 270)
			(size 1.6256 1.6256)
			(drill 1.1176)
			(layers "*.Cu" "*.Mask")
			(remove_unused_layers no)
			(net "P12V")
			(clearance 0)
		)
		(pad "61" thru_hole circle
			(at 5.08 7.62 270)
			(size 1.6256 1.6256)
			(drill 1.1176)
			(layers "*.Cu" "*.Mask")
			(remove_unused_layers no)
			(net "P12V")
			(clearance 0)
		)
		(pad "62" thru_hole circle
			(at 5.08 5.08 270)
			(size 1.6256 1.6256)
			(drill 1.1176)
			(layers "*.Cu" "*.Mask")
			(remove_unused_layers no)
			(net "P12V")
			(clearance 0)
		)
		(pad "63" thru_hole circle
			(at 5.08 2.54 270)
			(size 1.6256 1.6256)
			(drill 1.1176)
			(layers "*.Cu" "*.Mask")
			(remove_unused_layers no)
			(net "P12V")
			(clearance 0)
		)
		(pad "64" thru_hole circle
			(at 5.08 0 270)
			(size 1.6256 1.6256)
			(drill 1.1176)
			(layers "*.Cu" "*.Mask")
			(remove_unused_layers no)
			(net "P12V")
			(clearance 0)
		)
	)
	(footprint ""
		(layer "F.Cu")
		(at 27.239976 -461.829912)
		(property "Reference" "R22"
			(at -3.353816 -0.093726 0)
			(unlocked yes)
			(layer "F.SilkS")
			(effects
				(font
					(size 0.7874 0.5842)
					(thickness 0.1524)
				)
				(justify left)
			)
		)
		(property "Value" ""
			(at 0 0 0)
			(layer "F.Fab")
			(effects
				(font
					(size 1.27 1.27)
				)
			)
		)
		(duplicate_pad_numbers_are_jumpers no)
		(fp_line
			(start -0.7874 -0.4064)
			(end 0.7874 -0.4064)
			(stroke
				(width 0.1524)
				(type default)
			)
			(layer "F.SilkS")
		)
		(fp_line
			(start -0.7874 0.4064)
			(end -0.7874 -0.4064)
			(stroke
				(width 0.1524)
				(type default)
			)
			(layer "F.SilkS")
		)
		(fp_line
			(start 0.7874 -0.4064)
			(end 0.7874 0.4064)
			(stroke
				(width 0.1524)
				(type default)
			)
			(layer "F.SilkS")
		)
		(fp_line
			(start 0.7874 0.4064)
			(end -0.7874 0.4064)
			(stroke
				(width 0.1524)
				(type default)
			)
			(layer "F.SilkS")
		)
		(fp_poly
			(pts
				(xy -0.508 0.2794) (xy -0.508 0.2286) (xy -0.635 0.2286) (xy -0.635 -0.254) (xy -0.5334 -0.254)
				(xy -0.5334 -0.2794) (xy 0.5334 -0.2794) (xy 0.5334 -0.254) (xy 0.635 -0.254) (xy 0.635 0.254) (xy 0.5334 0.254)
				(xy 0.5334 0.2794)
			)
			(stroke
				(width 0)
				(type default)
			)
			(fill no)
			(layer "F.CrtYd")
		)
		(pad "1" smd rect
			(at 0.40005 0)
			(size 0.4572 0.508)
			(layers "F.Cu" "F.Mask" "F.Paste")
			(net "PSU6_REMOTE_N")
		)
		(pad "2" smd rect
			(at -0.40005 0)
			(size 0.4572 0.508)
			(layers "F.Cu" "F.Mask" "F.Paste")
			(net "GND")
		)
	)
	(footprint ""
		(layer "F.Cu")
		(at 39.512494 -463.972148 90)
		(property "Reference" "R130"
			(at -0.669544 1.862074 0)
			(unlocked yes)
			(layer "F.SilkS")
			(effects
				(font
					(size 0.7874 0.5842)
					(thickness 0.1524)
				)
				(justify left)
			)
		)
		(property "Value" ""
			(at 0 0 90)
			(layer "F.Fab")
			(effects
				(font
					(size 1.27 1.27)
				)
			)
		)
		(duplicate_pad_numbers_are_jumpers no)
		(fp_line
			(start 0.7874 -0.4064)
			(end 0.7874 0.4064)
			(stroke
				(width 0.1524)
				(type default)
			)
			(layer "F.SilkS")
		)
		(fp_line
			(start -0.7874 -0.4064)
			(end 0.7874 -0.4064)
			(stroke
				(width 0.1524)
				(type default)
			)
			(layer "F.SilkS")
		)
		(fp_line
			(start 0.7874 0.4064)
			(end -0.7874 0.4064)
			(stroke
				(width 0.1524)
				(type default)
			)
			(layer "F.SilkS")
		)
		(fp_line
			(start -0.7874 0.4064)
			(end -0.7874 -0.4064)
			(stroke
				(width 0.1524)
				(type default)
			)
			(layer "F.SilkS")
		)
		(fp_poly
			(pts
				(xy -0.508 0.2794) (xy -0.508 0.2286) (xy -0.635 0.2286) (xy -0.635 -0.254) (xy -0.5334 -0.254)
				(xy -0.5334 -0.2794) (xy 0.5334 -0.2794) (xy 0.5334 -0.254) (xy 0.635 -0.254) (xy 0.635 0.254) (xy 0.5334 0.254)
				(xy 0.5334 0.2794)
			)
			(stroke
				(width 0)
				(type default)
			)
			(fill no)
			(layer "F.CrtYd")
		)
		(pad "1" smd rect
			(at 0.40005 0 90)
			(size 0.4572 0.508)
			(layers "F.Cu" "F.Mask" "F.Paste")
			(net "PSU6_REMOTE_P")
		)
		(pad "2" smd rect
			(at -0.40005 0 90)
			(size 0.4572 0.508)
			(layers "F.Cu" "F.Mask" "F.Paste")
			(net "PSU6_REMOTE_R2_P")
		)
	)
	(footprint ""
		(layer "F.Cu")
		(at 39.51478 -464.77047 -90)
		(property "Reference" "R98"
			(at -1.157224 -0.122428 90)
			(unlocked yes)
			(layer "F.SilkS")
			(effects
				(font
					(size 0.7874 0.5842)
					(thickness 0.1524)
				)
				(justify left)
			)
		)
		(property "Value" ""
			(at 0 0 270)
			(layer "F.Fab")
			(effects
				(font
					(size 1.27 1.27)
				)
			)
		)
		(duplicate_pad_numbers_are_jumpers no)
		(fp_line
			(start -0.7874 0.4064)
			(end -0.7874 -0.4064)
			(stroke
				(width 0.1524)
				(type default)
			)
			(layer "F.SilkS")
		)
		(fp_line
			(start 0.7874 0.4064)
			(end -0.7874 0.4064)
			(stroke
				(width 0.1524)
				(type default)
			)
			(layer "F.SilkS")
		)
		(fp_line
			(start -0.7874 -0.4064)
			(end 0.7874 -0.4064)
			(stroke
				(width 0.1524)
				(type default)
			)
			(layer "F.SilkS")
		)
		(fp_line
			(start 0.7874 -0.4064)
			(end 0.7874 0.4064)
			(stroke
				(width 0.1524)
				(type default)
			)
			(layer "F.SilkS")
		)
		(fp_poly
			(pts
				(xy -0.508 0.2794) (xy -0.508 0.2286) (xy -0.635 0.2286) (xy -0.635 -0.254) (xy -0.5334 -0.254)
				(xy -0.5334 -0.2794) (xy 0.5334 -0.2794) (xy 0.5334 -0.254) (xy 0.635 -0.254) (xy 0.635 0.254) (xy 0.5334 0.254)
				(xy 0.5334 0.2794)
			)
			(stroke
				(width 0)
				(type default)
			)
			(fill no)
			(layer "F.CrtYd")
		)
		(pad "1" smd rect
			(at 0.40005 0 270)
			(size 0.4572 0.508)
			(layers "F.Cu" "F.Mask" "F.Paste")
			(net "PSU6_REMOTE_P")
		)
		(pad "2" smd rect
			(at -0.40005 0 270)
			(size 0.4572 0.508)
			(layers "F.Cu" "F.Mask" "F.Paste")
			(net "PSU6_REMOTE_R_P")
		)
	)
	(footprint ""
		(layer "F.Cu")
		(at 50.150268 -350.765364 180)
		(property "Reference" "CE16"
			(at -4.708906 1.983994 0)
			(unlocked yes)
			(layer "F.SilkS")
			(effects
				(font
					(size 0.7874 0.5842)
					(thickness 0.1524)
				)
				(justify left)
			)
		)
		(property "Value" ""
			(at 0 0 180)
			(layer "F.Fab")
			(effects
				(font
					(size 1.27 1.27)
				)
			)
		)
		(duplicate_pad_numbers_are_jumpers no)
		(fp_line
			(start 0 -4.2672)
			(end 0 4.2672)
			(stroke
				(width 0.1524)
				(type default)
			)
			(layer "F.SilkS")
		)
		(fp_circle
			(center 0 0)
			(end -4.2672 0)
			(stroke
				(width 0.1524)
				(type default)
			)
			(fill no)
			(layer "F.SilkS")
		)
		(fp_poly
			(pts
				(arc
					(start 0 -4.2672)
					(mid 4.2672 0)
					(end 0 4.2672)
				)
			)
			(stroke
				(width 0)
				(type default)
			)
			(fill yes)
			(layer "F.SilkS")
		)
		(fp_poly
			(pts
				(xy -2.5146 -0.762) (xy -0.9906 -0.762) (xy -0.9906 0.762) (xy -2.5146 0.762)
			)
			(stroke
				(width 0)
				(type default)
			)
			(fill no)
			(layer "B.CrtYd")
		)
		(fp_poly
			(pts
				(arc
					(start 1.7526 0.762)
					(mid 2.291415 -0.538815)
					(end 0.9906 0)
				)
				(arc
					(start 0.9906 0.0254)
					(mid 1.206345 0.546255)
					(end 1.7272 0.762)
				)
			)
			(stroke
				(width 0)
				(type default)
			)
			(fill no)
			(layer "B.CrtYd")
		)
		(fp_poly
			(pts
				(arc
					(start -4.2672 0)
					(mid 4.2672 0)
					(end -4.2672 0)
				)
			)
			(stroke
				(width 0)
				(type default)
			)
			(fill no)
			(layer "F.CrtYd")
		)
		(fp_circle
			(center 0 0)
			(end -4.2672 0)
			(stroke
				(width 0.1)
				(type default)
			)
			(fill no)
			(layer "F.Fab")
		)
		(fp_text user "+"
			(at -5.00888 -0.427228 180)
			(unlocked yes)
			(layer "F.SilkS")
			(effects
				(font
					(size 0.7874 0.5842)
					(thickness 0.1524)
				)
				(justify left)
			)
		)
		(fp_text user "+"
			(at -5.6642 -0.34925 180)
			(unlocked yes)
			(layer "F.Fab")
			(effects
				(font
					(size 1.905 1.4224)
					(thickness 0.000001)
				)
				(justify left)
			)
		)
		(pad "1" thru_hole rect
			(at -1.75006 0 180)
			(size 1.397 1.397)
			(drill 0.9144)
			(layers "*.Cu" "*.Mask")
			(remove_unused_layers no)
			(net "P12V")
			(clearance 0.0127)
			(thermal_gap 0.0127)
			(padstack
				(mode front_inner_back)
				(layer "Inner"
					(shape circle)
					(size 1.397 1.397)
					(clearance 0.0127)
				)
				(layer "B.Cu"
					(shape rect)
					(size 1.397 1.397)
					(clearance 0.0127)
				)
			)
		)
		(pad "2" thru_hole circle
			(at 1.75006 0 180)
			(size 1.397 1.397)
			(drill 0.9144)
			(layers "*.Cu" "*.Mask")
			(remove_unused_layers no)
			(net "GND")
			(clearance 0.0127)
			(thermal_gap 0.0127)
		)
	)
	(footprint ""
		(layer "F.Cu")
		(at 26.928318 -196.6214)
		(property "Reference" "R6"
			(at -3.177032 0.103886 0)
			(unlocked yes)
			(layer "F.SilkS")
			(effects
				(font
					(size 0.7874 0.5842)
					(thickness 0.1524)
				)
				(justify left)
			)
		)
		(property "Value" ""
			(at 0 0 0)
			(layer "F.Fab")
			(effects
				(font
					(size 1.27 1.27)
				)
			)
		)
		(duplicate_pad_numbers_are_jumpers no)
		(fp_line
			(start -0.7874 -0.4064)
			(end 0.7874 -0.4064)
			(stroke
				(width 0.1524)
				(type default)
			)
			(layer "F.SilkS")
		)
		(fp_line
			(start -0.7874 0.4064)
			(end -0.7874 -0.4064)
			(stroke
				(width 0.1524)
				(type default)
			)
			(layer "F.SilkS")
		)
		(fp_line
			(start 0.7874 -0.4064)
			(end 0.7874 0.4064)
			(stroke
				(width 0.1524)
				(type default)
			)
			(layer "F.SilkS")
		)
		(fp_line
			(start 0.7874 0.4064)
			(end -0.7874 0.4064)
			(stroke
				(width 0.1524)
				(type default)
			)
			(layer "F.SilkS")
		)
		(fp_poly
			(pts
				(xy -0.508 0.2794) (xy -0.508 0.2286) (xy -0.635 0.2286) (xy -0.635 -0.254) (xy -0.5334 -0.254)
				(xy -0.5334 -0.2794) (xy 0.5334 -0.2794) (xy 0.5334 -0.254) (xy 0.635 -0.254) (xy 0.635 0.254) (xy 0.5334 0.254)
				(xy 0.5334 0.2794)
			)
			(stroke
				(width 0)
				(type default)
			)
			(fill no)
			(layer "F.CrtYd")
		)
		(pad "1" smd rect
			(at 0.40005 0)
			(size 0.4572 0.508)
			(layers "F.Cu" "F.Mask" "F.Paste")
			(net "PSU3_REMOTE_N")
		)
		(pad "2" smd rect
			(at -0.40005 0)
			(size 0.4572 0.508)
			(layers "F.Cu" "F.Mask" "F.Paste")
			(net "GND")
		)
	)
	(footprint ""
		(layer "F.Cu")
		(at 68.972938 -60.671456 -90)
		(property "Reference" "C8"
			(at -2.737104 0.062992 90)
			(unlocked yes)
			(layer "F.SilkS")
			(effects
				(font
					(size 0.7874 0.5842)
					(thickness 0.1524)
				)
			)
		)
		(property "Value" ""
			(at 0 0 270)
			(layer "F.Fab")
			(effects
				(font
					(size 1.27 1.27)
				)
			)
		)
		(duplicate_pad_numbers_are_jumpers no)
		(fp_line
			(start -1.2954 0.5842)
			(end -1.2954 -0.5842)
			(stroke
				(width 0.1524)
				(type default)
			)
			(layer "F.SilkS")
		)
		(fp_line
			(start 1.2954 0.5842)
			(end -1.2954 0.5842)
			(stroke
				(width 0.1524)
				(type default)
			)
			(layer "F.SilkS")
		)
		(fp_line
			(start -1.2954 -0.5842)
			(end 1.2954 -0.5842)
			(stroke
				(width 0.1524)
				(type default)
			)
			(layer "F.SilkS")
		)
		(fp_line
			(start 0 -0.5842)
			(end 0 0.5842)
			(stroke
				(width 0.1524)
				(type default)
			)
			(layer "F.SilkS")
		)
		(fp_line
			(start 1.2954 -0.5842)
			(end 1.2954 0.5842)
			(stroke
				(width 0.1524)
				(type default)
			)
			(layer "F.SilkS")
		)
		(fp_poly
			(pts
				(xy 0.8636 -0.4572) (xy 0.8636 -0.3556) (xy 1.143 -0.3556) (xy 1.143 0.3556) (xy 0.8636 0.3556)
				(xy 0.8636 0.4572) (xy -0.8636 0.4572) (xy -0.8636 0.3556) (xy -1.143 0.3556) (xy -1.143 -0.3556)
				(xy -0.8636 -0.3556) (xy -0.8636 -0.4572)
			)
			(stroke
				(width 0)
				(type default)
			)
			(fill no)
			(layer "F.CrtYd")
		)
		(fp_line
			(start -0.884936 0.504952)
			(end -0.884936 -0.504952)
			(stroke
				(width 0.1)
				(type default)
			)
			(layer "F.Fab")
		)
		(fp_line
			(start 0.884936 0.504952)
			(end -0.884936 0.504952)
			(stroke
				(width 0.1)
				(type default)
			)
			(layer "F.Fab")
		)
		(fp_line
			(start -0.884936 -0.504952)
			(end 0.884936 -0.504952)
			(stroke
				(width 0.1)
				(type default)
			)
			(layer "F.Fab")
		)
		(fp_line
			(start 0.884936 -0.504952)
			(end 0.884936 0.504952)
			(stroke
				(width 0.1)
				(type default)
			)
			(layer "F.Fab")
		)
		(pad "1" smd rect
			(at 0.7366 0)
			(size 0.7112 0.8128)
			(layers "F.Cu" "F.Mask" "F.Paste")
			(net "P12V")
		)
		(pad "2" smd rect
			(at -0.7366 0)
			(size 0.7112 0.8128)
			(layers "F.Cu" "F.Mask" "F.Paste")
			(net "GND")
		)
	)
	(footprint ""
		(layer "F.Cu")
		(at 25.931622 -99.36988)
		(property "Reference" "R46"
			(at -4.080256 -0.075692 0)
			(unlocked yes)
			(layer "F.SilkS")
			(effects
				(font
					(size 0.7874 0.5842)
					(thickness 0.1524)
				)
				(justify left)
			)
		)
		(property "Value" ""
			(at 0 0 0)
			(layer "F.Fab")
			(effects
				(font
					(size 1.27 1.27)
				)
			)
		)
		(duplicate_pad_numbers_are_jumpers no)
		(fp_line
			(start -0.7874 -0.4064)
			(end 0.7874 -0.4064)
			(stroke
				(width 0.1524)
				(type default)
			)
			(layer "F.SilkS")
		)
		(fp_line
			(start -0.7874 0.4064)
			(end -0.7874 -0.4064)
			(stroke
				(width 0.1524)
				(type default)
			)
			(layer "F.SilkS")
		)
		(fp_line
			(start 0.7874 -0.4064)
			(end 0.7874 0.4064)
			(stroke
				(width 0.1524)
				(type default)
			)
			(layer "F.SilkS")
		)
		(fp_line
			(start 0.7874 0.4064)
			(end -0.7874 0.4064)
			(stroke
				(width 0.1524)
				(type default)
			)
			(layer "F.SilkS")
		)
		(fp_poly
			(pts
				(xy -0.508 0.2794) (xy -0.508 0.2286) (xy -0.635 0.2286) (xy -0.635 -0.254) (xy -0.5334 -0.254)
				(xy -0.5334 -0.2794) (xy 0.5334 -0.2794) (xy 0.5334 -0.254) (xy 0.635 -0.254) (xy 0.635 0.254) (xy 0.5334 0.254)
				(xy 0.5334 0.2794)
			)
			(stroke
				(width 0)
				(type default)
			)
			(fill no)
			(layer "F.CrtYd")
		)
		(pad "1" smd rect
			(at 0.40005 0)
			(size 0.4572 0.508)
			(layers "F.Cu" "F.Mask" "F.Paste")
			(net "PSU2_PS_KILL")
		)
		(pad "2" smd rect
			(at -0.40005 0)
			(size 0.4572 0.508)
			(layers "F.Cu" "F.Mask" "F.Paste")
			(net "GND")
		)
	)
	(footprint ""
		(layer "F.Cu")
		(at 25.857708 -360.550968)
		(property "Reference" "R59"
			(at -3.917442 -0.225298 0)
			(unlocked yes)
			(layer "F.SilkS")
			(effects
				(font
					(size 0.7874 0.5842)
					(thickness 0.1524)
				)
				(justify left)
			)
		)
		(property "Value" ""
			(at 0 0 0)
			(layer "F.Fab")
			(effects
				(font
					(size 1.27 1.27)
				)
			)
		)
		(duplicate_pad_numbers_are_jumpers no)
		(fp_line
			(start -0.7874 -0.4064)
			(end 0.7874 -0.4064)
			(stroke
				(width 0.1524)
				(type default)
			)
			(layer "F.SilkS")
		)
		(fp_line
			(start -0.7874 0.4064)
			(end -0.7874 -0.4064)
			(stroke
				(width 0.1524)
				(type default)
			)
			(layer "F.SilkS")
		)
		(fp_line
			(start 0.7874 -0.4064)
			(end 0.7874 0.4064)
			(stroke
				(width 0.1524)
				(type default)
			)
			(layer "F.SilkS")
		)
		(fp_line
			(start 0.7874 0.4064)
			(end -0.7874 0.4064)
			(stroke
				(width 0.1524)
				(type default)
			)
			(layer "F.SilkS")
		)
		(fp_poly
			(pts
				(xy -0.508 0.2794) (xy -0.508 0.2286) (xy -0.635 0.2286) (xy -0.635 -0.254) (xy -0.5334 -0.254)
				(xy -0.5334 -0.2794) (xy 0.5334 -0.2794) (xy 0.5334 -0.254) (xy 0.635 -0.254) (xy 0.635 0.254) (xy 0.5334 0.254)
				(xy 0.5334 0.2794)
			)
			(stroke
				(width 0)
				(type default)
			)
			(fill no)
			(layer "F.CrtYd")
		)
		(pad "1" smd rect
			(at 0.40005 0)
			(size 0.4572 0.508)
			(layers "F.Cu" "F.Mask" "F.Paste")
			(net "PSU5_RESET")
		)
		(pad "2" smd rect
			(at -0.40005 0)
			(size 0.4572 0.508)
			(layers "F.Cu" "F.Mask" "F.Paste")
			(net "GND")
		)
	)
	(footprint ""
		(layer "F.Cu")
		(at 26.068274 -181.847998)
		(property "Reference" "R73"
			(at -3.997198 0.128524 0)
			(unlocked yes)
			(layer "F.SilkS")
			(effects
				(font
					(size 0.7874 0.5842)
					(thickness 0.1524)
				)
				(justify left)
			)
		)
		(property "Value" ""
			(at 0 0 0)
			(layer "F.Fab")
			(effects
				(font
					(size 1.27 1.27)
				)
			)
		)
		(duplicate_pad_numbers_are_jumpers no)
		(fp_line
			(start -0.7874 -0.4064)
			(end 0.7874 -0.4064)
			(stroke
				(width 0.1524)
				(type default)
			)
			(layer "F.SilkS")
		)
		(fp_line
			(start -0.7874 0.4064)
			(end -0.7874 -0.4064)
			(stroke
				(width 0.1524)
				(type default)
			)
			(layer "F.SilkS")
		)
		(fp_line
			(start 0.7874 -0.4064)
			(end 0.7874 0.4064)
			(stroke
				(width 0.1524)
				(type default)
			)
			(layer "F.SilkS")
		)
		(fp_line
			(start 0.7874 0.4064)
			(end -0.7874 0.4064)
			(stroke
				(width 0.1524)
				(type default)
			)
			(layer "F.SilkS")
		)
		(fp_poly
			(pts
				(xy -0.508 0.2794) (xy -0.508 0.2286) (xy -0.635 0.2286) (xy -0.635 -0.254) (xy -0.5334 -0.254)
				(xy -0.5334 -0.2794) (xy 0.5334 -0.2794) (xy 0.5334 -0.254) (xy 0.635 -0.254) (xy 0.635 0.254) (xy 0.5334 0.254)
				(xy 0.5334 0.2794)
			)
			(stroke
				(width 0)
				(type default)
			)
			(fill no)
			(layer "F.CrtYd")
		)
		(pad "1" smd rect
			(at 0.40005 0)
			(size 0.4572 0.508)
			(layers "F.Cu" "F.Mask" "F.Paste")
			(net "PSU3_RESET")
		)
		(pad "2" smd rect
			(at -0.40005 0)
			(size 0.4572 0.508)
			(layers "F.Cu" "F.Mask" "F.Paste")
			(net "GND")
		)
	)
	(footprint ""
		(layer "F.Cu")
		(at 49.949608 -18.56867 180)
		(property "Reference" "CE1"
			(at -4.548124 -1.308608 0)
			(unlocked yes)
			(layer "F.SilkS")
			(effects
				(font
					(size 0.7874 0.5842)
					(thickness 0.1524)
				)
				(justify left)
			)
		)
		(property "Value" ""
			(at 0 0 180)
			(layer "F.Fab")
			(effects
				(font
					(size 1.27 1.27)
				)
			)
		)
		(duplicate_pad_numbers_are_jumpers no)
		(fp_line
			(start 0 -4.2672)
			(end 0 4.2672)
			(stroke
				(width 0.1524)
				(type default)
			)
			(layer "F.SilkS")
		)
		(fp_circle
			(center 0 0)
			(end -4.2672 0)
			(stroke
				(width 0.1524)
				(type default)
			)
			(fill no)
			(layer "F.SilkS")
		)
		(fp_poly
			(pts
				(arc
					(start 0 -4.2672)
					(mid 4.2672 0)
					(end 0 4.2672)
				)
			)
			(stroke
				(width 0)
				(type default)
			)
			(fill yes)
			(layer "F.SilkS")
		)
		(fp_poly
			(pts
				(xy -2.5146 -0.762) (xy -0.9906 -0.762) (xy -0.9906 0.762) (xy -2.5146 0.762)
			)
			(stroke
				(width 0)
				(type default)
			)
			(fill no)
			(layer "B.CrtYd")
		)
		(fp_poly
			(pts
				(arc
					(start 1.7526 0.762)
					(mid 2.291415 -0.538815)
					(end 0.9906 0)
				)
				(arc
					(start 0.9906 0.0254)
					(mid 1.206345 0.546255)
					(end 1.7272 0.762)
				)
			)
			(stroke
				(width 0)
				(type default)
			)
			(fill no)
			(layer "B.CrtYd")
		)
		(fp_poly
			(pts
				(arc
					(start -4.2672 0)
					(mid 4.2672 0)
					(end -4.2672 0)
				)
			)
			(stroke
				(width 0)
				(type default)
			)
			(fill no)
			(layer "F.CrtYd")
		)
		(fp_circle
			(center 0 0)
			(end -4.2672 0)
			(stroke
				(width 0.1)
				(type default)
			)
			(fill no)
			(layer "F.Fab")
		)
		(fp_text user "+"
			(at -5.15239 -2.408428 180)
			(unlocked yes)
			(layer "F.SilkS")
			(effects
				(font
					(size 0.7874 0.5842)
					(thickness 0.1524)
				)
				(justify left)
			)
		)
		(fp_text user "+"
			(at -5.6642 -0.34925 180)
			(unlocked yes)
			(layer "F.Fab")
			(effects
				(font
					(size 1.905 1.4224)
					(thickness 0.000001)
				)
				(justify left)
			)
		)
		(pad "1" thru_hole rect
			(at -1.75006 0 180)
			(size 1.397 1.397)
			(drill 0.9144)
			(layers "*.Cu" "*.Mask")
			(remove_unused_layers no)
			(net "P12V")
			(clearance 0.0127)
			(thermal_gap 0.0127)
			(padstack
				(mode front_inner_back)
				(layer "Inner"
					(shape circle)
					(size 1.397 1.397)
					(clearance 0.0127)
				)
				(layer "B.Cu"
					(shape rect)
					(size 1.397 1.397)
					(clearance 0.0127)
				)
			)
		)
		(pad "2" thru_hole circle
			(at 1.75006 0 180)
			(size 1.397 1.397)
			(drill 0.9144)
			(layers "*.Cu" "*.Mask")
			(remove_unused_layers no)
			(net "GND")
			(clearance 0.0127)
			(thermal_gap 0.0127)
		)
	)
	(footprint ""
		(layer "F.Cu")
		(at 13.420852 -318.358012 180)
		(property "Reference" "R140"
			(at -1.72974 -0.146304 0)
			(unlocked yes)
			(layer "F.SilkS")
			(effects
				(font
					(size 0.7874 0.5842)
					(thickness 0.1524)
				)
				(justify left)
			)
		)
		(property "Value" ""
			(at 0 0 180)
			(layer "F.Fab")
			(effects
				(font
					(size 1.27 1.27)
				)
			)
		)
		(duplicate_pad_numbers_are_jumpers no)
		(fp_line
			(start 0.7874 0.4064)
			(end -0.7874 0.4064)
			(stroke
				(width 0.1524)
				(type default)
			)
			(layer "F.SilkS")
		)
		(fp_line
			(start 0.7874 -0.4064)
			(end 0.7874 0.4064)
			(stroke
				(width 0.1524)
				(type default)
			)
			(layer "F.SilkS")
		)
		(fp_line
			(start -0.7874 0.4064)
			(end -0.7874 -0.4064)
			(stroke
				(width 0.1524)
				(type default)
			)
			(layer "F.SilkS")
		)
		(fp_line
			(start -0.7874 -0.4064)
			(end 0.7874 -0.4064)
			(stroke
				(width 0.1524)
				(type default)
			)
			(layer "F.SilkS")
		)
		(fp_poly
			(pts
				(xy -0.508 0.2794) (xy -0.508 0.2286) (xy -0.635 0.2286) (xy -0.635 -0.254) (xy -0.5334 -0.254)
				(xy -0.5334 -0.2794) (xy 0.5334 -0.2794) (xy 0.5334 -0.254) (xy 0.635 -0.254) (xy 0.635 0.254) (xy 0.5334 0.254)
				(xy 0.5334 0.2794)
			)
			(stroke
				(width 0)
				(type default)
			)
			(fill no)
			(layer "F.CrtYd")
		)
		(pad "1" smd rect
			(at 0.40005 0 180)
			(size 0.4572 0.508)
			(layers "F.Cu" "F.Mask" "F.Paste")
			(net "FAN_PWM")
		)
		(pad "2" smd rect
			(at -0.40005 0 180)
			(size 0.4572 0.508)
			(layers "F.Cu" "F.Mask" "F.Paste")
			(net "GND")
		)
	)
	(footprint ""
		(layer "F.Cu")
		(at 73.426828 -307.819806 90)
		(property "Reference" "C54"
			(at -1.283716 5.297424 90)
			(unlocked yes)
			(layer "F.SilkS")
			(effects
				(font
					(size 0.7874 0.5842)
					(thickness 0.1524)
				)
				(justify left)
			)
		)
		(property "Value" ""
			(at 0 0 90)
			(layer "F.Fab")
			(effects
				(font
					(size 1.27 1.27)
				)
			)
		)
		(duplicate_pad_numbers_are_jumpers no)
		(fp_line
			(start 0.7874 -0.4064)
			(end 0.7874 0.4064)
			(stroke
				(width 0.1524)
				(type default)
			)
			(layer "F.SilkS")
		)
		(fp_line
			(start -0.7874 -0.4064)
			(end 0.7874 -0.4064)
			(stroke
				(width 0.1524)
				(type default)
			)
			(layer "F.SilkS")
		)
		(fp_line
			(start 0 0.381)
			(end 0 -0.381)
			(stroke
				(width 0.1524)
				(type default)
			)
			(layer "F.SilkS")
		)
		(fp_line
			(start 0.7874 0.4064)
			(end -0.7874 0.4064)
			(stroke
				(width 0.1524)
				(type default)
			)
			(layer "F.SilkS")
		)
		(fp_line
			(start -0.7874 0.4064)
			(end -0.7874 -0.4064)
			(stroke
				(width 0.1524)
				(type default)
			)
			(layer "F.SilkS")
		)
		(fp_poly
			(pts
				(xy -0.5334 0.254) (xy -0.635 0.254) (xy -0.635 0.2286) (xy -0.635 -0.254) (xy -0.5334 -0.254) (xy -0.5334 -0.2794)
				(xy 0.5334 -0.2794) (xy 0.5334 -0.254) (xy 0.635 -0.254) (xy 0.635 0.254) (xy 0.5334 0.254) (xy 0.5334 0.2794)
				(xy -0.508 0.2794) (xy -0.5334 0.2794)
			)
			(stroke
				(width 0)
				(type default)
			)
			(fill no)
			(layer "F.CrtYd")
		)
		(pad "1" smd rect
			(at 0.40005 0 90)
			(size 0.4572 0.508)
			(layers "F.Cu" "F.Mask" "F.Paste")
			(net "P12V")
		)
		(pad "2" smd rect
			(at -0.40005 0 90)
			(size 0.4572 0.508)
			(layers "F.Cu" "F.Mask" "F.Paste")
			(net "GND")
		)
	)
	(footprint ""
		(layer "F.Cu")
		(at 77.254354 -14.939772 -90)
		(property "Reference" "C3"
			(at -1.75133 0.09906 90)
			(unlocked yes)
			(layer "F.SilkS")
			(effects
				(font
					(size 0.7874 0.5842)
					(thickness 0.1524)
				)
				(justify left)
			)
		)
		(property "Value" ""
			(at 0 0 270)
			(layer "F.Fab")
			(effects
				(font
					(size 1.27 1.27)
				)
			)
		)
		(duplicate_pad_numbers_are_jumpers no)
		(fp_line
			(start -0.7874 0.4064)
			(end -0.7874 -0.4064)
			(stroke
				(width 0.1524)
				(type default)
			)
			(layer "F.SilkS")
		)
		(fp_line
			(start 0.7874 0.4064)
			(end -0.7874 0.4064)
			(stroke
				(width 0.1524)
				(type default)
			)
			(layer "F.SilkS")
		)
		(fp_line
			(start 0 0.381)
			(end 0 -0.381)
			(stroke
				(width 0.1524)
				(type default)
			)
			(layer "F.SilkS")
		)
		(fp_line
			(start -0.7874 -0.4064)
			(end 0.7874 -0.4064)
			(stroke
				(width 0.1524)
				(type default)
			)
			(layer "F.SilkS")
		)
		(fp_line
			(start 0.7874 -0.4064)
			(end 0.7874 0.4064)
			(stroke
				(width 0.1524)
				(type default)
			)
			(layer "F.SilkS")
		)
		(fp_poly
			(pts
				(xy -0.5334 0.254) (xy -0.635 0.254) (xy -0.635 0.2286) (xy -0.635 -0.254) (xy -0.5334 -0.254) (xy -0.5334 -0.2794)
				(xy 0.5334 -0.2794) (xy 0.5334 -0.254) (xy 0.635 -0.254) (xy 0.635 0.254) (xy 0.5334 0.254) (xy 0.5334 0.2794)
				(xy -0.508 0.2794) (xy -0.5334 0.2794)
			)
			(stroke
				(width 0)
				(type default)
			)
			(fill no)
			(layer "F.CrtYd")
		)
		(pad "1" smd rect
			(at 0.40005 0 270)
			(size 0.4572 0.508)
			(layers "F.Cu" "F.Mask" "F.Paste")
			(net "P12V")
		)
		(pad "2" smd rect
			(at -0.40005 0 270)
			(size 0.4572 0.508)
			(layers "F.Cu" "F.Mask" "F.Paste")
			(net "GND")
		)
	)
	(footprint ""
		(layer "F.Cu")
		(at 17.162272 -330.455524 -90)
		(property "Reference" "R39"
			(at 3.685032 -0.234188 90)
			(unlocked yes)
			(layer "F.SilkS")
			(effects
				(font
					(size 0.7874 0.5842)
					(thickness 0.1524)
				)
				(justify left)
			)
		)
		(property "Value" ""
			(at 0 0 270)
			(layer "F.Fab")
			(effects
				(font
					(size 1.27 1.27)
				)
			)
		)
		(duplicate_pad_numbers_are_jumpers no)
		(fp_line
			(start -0.7874 0.4064)
			(end -0.7874 -0.4064)
			(stroke
				(width 0.1524)
				(type default)
			)
			(layer "F.SilkS")
		)
		(fp_line
			(start 0.7874 0.4064)
			(end -0.7874 0.4064)
			(stroke
				(width 0.1524)
				(type default)
			)
			(layer "F.SilkS")
		)
		(fp_line
			(start -0.7874 -0.4064)
			(end 0.7874 -0.4064)
			(stroke
				(width 0.1524)
				(type default)
			)
			(layer "F.SilkS")
		)
		(fp_line
			(start 0.7874 -0.4064)
			(end 0.7874 0.4064)
			(stroke
				(width 0.1524)
				(type default)
			)
			(layer "F.SilkS")
		)
		(fp_poly
			(pts
				(xy -0.508 0.2794) (xy -0.508 0.2286) (xy -0.635 0.2286) (xy -0.635 -0.254) (xy -0.5334 -0.254)
				(xy -0.5334 -0.2794) (xy 0.5334 -0.2794) (xy 0.5334 -0.254) (xy 0.635 -0.254) (xy 0.635 0.254) (xy 0.5334 0.254)
				(xy 0.5334 0.2794)
			)
			(stroke
				(width 0)
				(type default)
			)
			(fill no)
			(layer "F.CrtYd")
		)
		(pad "1" smd rect
			(at 0.40005 0 270)
			(size 0.4572 0.508)
			(layers "F.Cu" "F.Mask" "F.Paste")
			(net "GND")
		)
		(pad "2" smd rect
			(at -0.40005 0 270)
			(size 0.4572 0.508)
			(layers "F.Cu" "F.Mask" "F.Paste")
			(net "FRU_A2")
		)
	)
	(footprint ""
		(layer "F.Cu")
		(at 78.062074 -387.197854 180)
		(property "Reference" "R127"
			(at 0.888492 1.176274 0)
			(unlocked yes)
			(layer "F.SilkS")
			(effects
				(font
					(size 0.7874 0.5842)
					(thickness 0.1524)
				)
				(justify left)
			)
		)
		(property "Value" ""
			(at 0 0 180)
			(layer "F.Fab")
			(effects
				(font
					(size 1.27 1.27)
				)
			)
		)
		(duplicate_pad_numbers_are_jumpers no)
		(fp_line
			(start 0.7874 0.4064)
			(end -0.7874 0.4064)
			(stroke
				(width 0.1524)
				(type default)
			)
			(layer "F.SilkS")
		)
		(fp_line
			(start 0.7874 -0.4064)
			(end 0.7874 0.4064)
			(stroke
				(width 0.1524)
				(type default)
			)
			(layer "F.SilkS")
		)
		(fp_line
			(start -0.7874 0.4064)
			(end -0.7874 -0.4064)
			(stroke
				(width 0.1524)
				(type default)
			)
			(layer "F.SilkS")
		)
		(fp_line
			(start -0.7874 -0.4064)
			(end 0.7874 -0.4064)
			(stroke
				(width 0.1524)
				(type default)
			)
			(layer "F.SilkS")
		)
		(fp_poly
			(pts
				(xy -0.508 0.2794) (xy -0.508 0.2286) (xy -0.635 0.2286) (xy -0.635 -0.254) (xy -0.5334 -0.254)
				(xy -0.5334 -0.2794) (xy 0.5334 -0.2794) (xy 0.5334 -0.254) (xy 0.635 -0.254) (xy 0.635 0.254) (xy 0.5334 0.254)
				(xy 0.5334 0.2794)
			)
			(stroke
				(width 0)
				(type default)
			)
			(fill no)
			(layer "F.CrtYd")
		)
		(pad "1" smd rect
			(at 0.40005 0 180)
			(size 0.4572 0.508)
			(layers "F.Cu" "F.Mask" "F.Paste")
			(net "PSU5_REMOTE_R2_P")
		)
		(pad "2" smd rect
			(at -0.40005 0 180)
			(size 0.4572 0.508)
			(layers "F.Cu" "F.Mask" "F.Paste")
			(net "P12V")
		)
	)
	(footprint ""
		(layer "F.Cu")
		(at 71.007986 -307.819806 90)
		(property "Reference" "C56"
			(at -1.229106 5.06476 90)
			(unlocked yes)
			(layer "F.SilkS")
			(effects
				(font
					(size 0.7874 0.5842)
					(thickness 0.1524)
				)
				(justify left)
			)
		)
		(property "Value" ""
			(at 0 0 90)
			(layer "F.Fab")
			(effects
				(font
					(size 1.27 1.27)
				)
			)
		)
		(duplicate_pad_numbers_are_jumpers no)
		(fp_line
			(start 0.7874 -0.4064)
			(end 0.7874 0.4064)
			(stroke
				(width 0.1524)
				(type default)
			)
			(layer "F.SilkS")
		)
		(fp_line
			(start -0.7874 -0.4064)
			(end 0.7874 -0.4064)
			(stroke
				(width 0.1524)
				(type default)
			)
			(layer "F.SilkS")
		)
		(fp_line
			(start 0 0.381)
			(end 0 -0.381)
			(stroke
				(width 0.1524)
				(type default)
			)
			(layer "F.SilkS")
		)
		(fp_line
			(start 0.7874 0.4064)
			(end -0.7874 0.4064)
			(stroke
				(width 0.1524)
				(type default)
			)
			(layer "F.SilkS")
		)
		(fp_line
			(start -0.7874 0.4064)
			(end -0.7874 -0.4064)
			(stroke
				(width 0.1524)
				(type default)
			)
			(layer "F.SilkS")
		)
		(fp_poly
			(pts
				(xy -0.5334 0.254) (xy -0.635 0.254) (xy -0.635 0.2286) (xy -0.635 -0.254) (xy -0.5334 -0.254) (xy -0.5334 -0.2794)
				(xy 0.5334 -0.2794) (xy 0.5334 -0.254) (xy 0.635 -0.254) (xy 0.635 0.254) (xy 0.5334 0.254) (xy 0.5334 0.2794)
				(xy -0.508 0.2794) (xy -0.5334 0.2794)
			)
			(stroke
				(width 0)
				(type default)
			)
			(fill no)
			(layer "F.CrtYd")
		)
		(pad "1" smd rect
			(at 0.40005 0 90)
			(size 0.4572 0.508)
			(layers "F.Cu" "F.Mask" "F.Paste")
			(net "P12V")
		)
		(pad "2" smd rect
			(at -0.40005 0 90)
			(size 0.4572 0.508)
			(layers "F.Cu" "F.Mask" "F.Paste")
			(net "GND")
		)
	)
	(footprint ""
		(layer "F.Cu")
		(at 70.678548 -487.29138 90)
		(property "Reference" "C83"
			(at -4.10845 0.070104 90)
			(unlocked yes)
			(layer "F.SilkS")
			(effects
				(font
					(size 0.7874 0.5842)
					(thickness 0.1524)
				)
				(justify left)
			)
		)
		(property "Value" ""
			(at 0 0 90)
			(layer "F.Fab")
			(effects
				(font
					(size 1.27 1.27)
				)
			)
		)
		(duplicate_pad_numbers_are_jumpers no)
		(fp_line
			(start 0.7874 -0.4064)
			(end 0.7874 0.4064)
			(stroke
				(width 0.1524)
				(type default)
			)
			(layer "F.SilkS")
		)
		(fp_line
			(start -0.7874 -0.4064)
			(end 0.7874 -0.4064)
			(stroke
				(width 0.1524)
				(type default)
			)
			(layer "F.SilkS")
		)
		(fp_line
			(start 0 0.381)
			(end 0 -0.381)
			(stroke
				(width 0.1524)
				(type default)
			)
			(layer "F.SilkS")
		)
		(fp_line
			(start 0.7874 0.4064)
			(end -0.7874 0.4064)
			(stroke
				(width 0.1524)
				(type default)
			)
			(layer "F.SilkS")
		)
		(fp_line
			(start -0.7874 0.4064)
			(end -0.7874 -0.4064)
			(stroke
				(width 0.1524)
				(type default)
			)
			(layer "F.SilkS")
		)
		(fp_poly
			(pts
				(xy -0.5334 0.254) (xy -0.635 0.254) (xy -0.635 0.2286) (xy -0.635 -0.254) (xy -0.5334 -0.254) (xy -0.5334 -0.2794)
				(xy 0.5334 -0.2794) (xy 0.5334 -0.254) (xy 0.635 -0.254) (xy 0.635 0.254) (xy 0.5334 0.254) (xy 0.5334 0.2794)
				(xy -0.508 0.2794) (xy -0.5334 0.2794)
			)
			(stroke
				(width 0)
				(type default)
			)
			(fill no)
			(layer "F.CrtYd")
		)
		(pad "1" smd rect
			(at 0.40005 0 90)
			(size 0.4572 0.508)
			(layers "F.Cu" "F.Mask" "F.Paste")
			(net "P12V")
		)
		(pad "2" smd rect
			(at -0.40005 0 90)
			(size 0.4572 0.508)
			(layers "F.Cu" "F.Mask" "F.Paste")
			(net "GND")
		)
	)
	(footprint ""
		(layer "F.Cu")
		(at 70.997572 -354.308664 90)
		(property "Reference" "C61"
			(at -3.90779 0.6096 90)
			(unlocked yes)
			(layer "F.SilkS")
			(effects
				(font
					(size 0.7874 0.5842)
					(thickness 0.1524)
				)
				(justify left)
			)
		)
		(property "Value" ""
			(at 0 0 90)
			(layer "F.Fab")
			(effects
				(font
					(size 1.27 1.27)
				)
			)
		)
		(duplicate_pad_numbers_are_jumpers no)
		(fp_line
			(start 0.7874 -0.4064)
			(end 0.7874 0.4064)
			(stroke
				(width 0.1524)
				(type default)
			)
			(layer "F.SilkS")
		)
		(fp_line
			(start -0.7874 -0.4064)
			(end 0.7874 -0.4064)
			(stroke
				(width 0.1524)
				(type default)
			)
			(layer "F.SilkS")
		)
		(fp_line
			(start 0 0.381)
			(end 0 -0.381)
			(stroke
				(width 0.1524)
				(type default)
			)
			(layer "F.SilkS")
		)
		(fp_line
			(start 0.7874 0.4064)
			(end -0.7874 0.4064)
			(stroke
				(width 0.1524)
				(type default)
			)
			(layer "F.SilkS")
		)
		(fp_line
			(start -0.7874 0.4064)
			(end -0.7874 -0.4064)
			(stroke
				(width 0.1524)
				(type default)
			)
			(layer "F.SilkS")
		)
		(fp_poly
			(pts
				(xy -0.5334 0.254) (xy -0.635 0.254) (xy -0.635 0.2286) (xy -0.635 -0.254) (xy -0.5334 -0.254) (xy -0.5334 -0.2794)
				(xy 0.5334 -0.2794) (xy 0.5334 -0.254) (xy 0.635 -0.254) (xy 0.635 0.254) (xy 0.5334 0.254) (xy 0.5334 0.2794)
				(xy -0.508 0.2794) (xy -0.5334 0.2794)
			)
			(stroke
				(width 0)
				(type default)
			)
			(fill no)
			(layer "F.CrtYd")
		)
		(pad "1" smd rect
			(at 0.40005 0 90)
			(size 0.4572 0.508)
			(layers "F.Cu" "F.Mask" "F.Paste")
			(net "P12V")
		)
		(pad "2" smd rect
			(at -0.40005 0 90)
			(size 0.4572 0.508)
			(layers "F.Cu" "F.Mask" "F.Paste")
			(net "GND")
		)
	)
	(footprint ""
		(layer "F.Cu")
		(at 51.411124 -262.266176 180)
		(property "Reference" "CE7"
			(at -3.278124 3.86588 0)
			(unlocked yes)
			(layer "F.SilkS")
			(effects
				(font
					(size 0.7874 0.5842)
					(thickness 0.1524)
				)
				(justify left)
			)
		)
		(property "Value" ""
			(at 0 0 180)
			(layer "F.Fab")
			(effects
				(font
					(size 1.27 1.27)
				)
			)
		)
		(duplicate_pad_numbers_are_jumpers no)
		(fp_line
			(start 0 -4.2672)
			(end 0 4.2672)
			(stroke
				(width 0.1524)
				(type default)
			)
			(layer "F.SilkS")
		)
		(fp_circle
			(center 0 0)
			(end -4.2672 0)
			(stroke
				(width 0.1524)
				(type default)
			)
			(fill no)
			(layer "F.SilkS")
		)
		(fp_poly
			(pts
				(arc
					(start 0 -4.2672)
					(mid 4.2672 0)
					(end 0 4.2672)
				)
			)
			(stroke
				(width 0)
				(type default)
			)
			(fill yes)
			(layer "F.SilkS")
		)
		(fp_poly
			(pts
				(xy -2.5146 -0.762) (xy -0.9906 -0.762) (xy -0.9906 0.762) (xy -2.5146 0.762)
			)
			(stroke
				(width 0)
				(type default)
			)
			(fill no)
			(layer "B.CrtYd")
		)
		(fp_poly
			(pts
				(arc
					(start 1.7526 0.762)
					(mid 2.291415 -0.538815)
					(end 0.9906 0)
				)
				(arc
					(start 0.9906 0.0254)
					(mid 1.206345 0.546255)
					(end 1.7272 0.762)
				)
			)
			(stroke
				(width 0)
				(type default)
			)
			(fill no)
			(layer "B.CrtYd")
		)
		(fp_poly
			(pts
				(arc
					(start -4.2672 0)
					(mid 4.2672 0)
					(end -4.2672 0)
				)
			)
			(stroke
				(width 0)
				(type default)
			)
			(fill no)
			(layer "F.CrtYd")
		)
		(fp_circle
			(center 0 0)
			(end -4.2672 0)
			(stroke
				(width 0.1)
				(type default)
			)
			(fill no)
			(layer "F.Fab")
		)
		(fp_text user "+"
			(at -5.049266 0.28321 180)
			(unlocked yes)
			(layer "F.SilkS")
			(effects
				(font
					(size 0.7874 0.5842)
					(thickness 0.1524)
				)
				(justify left)
			)
		)
		(fp_text user "+"
			(at -5.6642 -0.34925 180)
			(unlocked yes)
			(layer "F.Fab")
			(effects
				(font
					(size 1.905 1.4224)
					(thickness 0.000001)
				)
				(justify left)
			)
		)
		(pad "1" thru_hole rect
			(at -1.75006 0 180)
			(size 1.397 1.397)
			(drill 0.9144)
			(layers "*.Cu" "*.Mask")
			(remove_unused_layers no)
			(net "P12V")
			(clearance 0.0127)
			(thermal_gap 0.0127)
			(padstack
				(mode front_inner_back)
				(layer "Inner"
					(shape circle)
					(size 1.397 1.397)
					(clearance 0.0127)
				)
				(layer "B.Cu"
					(shape rect)
					(size 1.397 1.397)
					(clearance 0.0127)
				)
			)
		)
		(pad "2" thru_hole circle
			(at 1.75006 0 180)
			(size 1.397 1.397)
			(drill 0.9144)
			(layers "*.Cu" "*.Mask")
			(remove_unused_layers no)
			(net "GND")
			(clearance 0.0127)
			(thermal_gap 0.0127)
		)
	)
	(footprint ""
		(layer "F.Cu")
		(at 26.068274 -184.266078)
		(property "Reference" "R72"
			(at -3.997198 0.128524 0)
			(unlocked yes)
			(layer "F.SilkS")
			(effects
				(font
					(size 0.7874 0.5842)
					(thickness 0.1524)
				)
				(justify left)
			)
		)
		(property "Value" ""
			(at 0 0 0)
			(layer "F.Fab")
			(effects
				(font
					(size 1.27 1.27)
				)
			)
		)
		(duplicate_pad_numbers_are_jumpers no)
		(fp_line
			(start -0.7874 -0.4064)
			(end 0.7874 -0.4064)
			(stroke
				(width 0.1524)
				(type default)
			)
			(layer "F.SilkS")
		)
		(fp_line
			(start -0.7874 0.4064)
			(end -0.7874 -0.4064)
			(stroke
				(width 0.1524)
				(type default)
			)
			(layer "F.SilkS")
		)
		(fp_line
			(start 0.7874 -0.4064)
			(end 0.7874 0.4064)
			(stroke
				(width 0.1524)
				(type default)
			)
			(layer "F.SilkS")
		)
		(fp_line
			(start 0.7874 0.4064)
			(end -0.7874 0.4064)
			(stroke
				(width 0.1524)
				(type default)
			)
			(layer "F.SilkS")
		)
		(fp_poly
			(pts
				(xy -0.508 0.2794) (xy -0.508 0.2286) (xy -0.635 0.2286) (xy -0.635 -0.254) (xy -0.5334 -0.254)
				(xy -0.5334 -0.2794) (xy 0.5334 -0.2794) (xy 0.5334 -0.254) (xy 0.635 -0.254) (xy 0.635 0.254) (xy 0.5334 0.254)
				(xy 0.5334 0.2794)
			)
			(stroke
				(width 0)
				(type default)
			)
			(fill no)
			(layer "F.CrtYd")
		)
		(pad "1" smd rect
			(at 0.40005 0)
			(size 0.4572 0.508)
			(layers "F.Cu" "F.Mask" "F.Paste")
			(net "PSU3_RESET")
		)
		(pad "2" smd rect
			(at -0.40005 0)
			(size 0.4572 0.508)
			(layers "F.Cu" "F.Mask" "F.Paste")
			(net "P12V_STBY")
		)
	)
	(footprint ""
		(layer "F.Cu")
		(at 97.946464 -505.85878)
		(property "Reference" ""
			(at 0 0 0)
			(layer "F.SilkS")
			(hide yes)
			(effects
				(font
					(size 1.27 1.27)
				)
			)
		)
		(property "Value" ""
			(at 0 0 0)
			(layer "F.Fab")
			(effects
				(font
					(size 1.27 1.27)
				)
			)
		)
		(duplicate_pad_numbers_are_jumpers no)
		(fp_poly
			(pts
				(arc
					(start 1.4986 0)
					(mid -1.4986 0)
					(end 1.4986 0)
				)
			)
			(stroke
				(width 0)
				(type default)
			)
			(fill no)
			(layer "F.CrtYd")
		)
		(pad "1" smd circle
			(at 0 0)
			(size 0.9906 0.9906)
			(layers "F.Cu" "F.Mask" "F.Paste")
			(net "Net_171")
		)
		(zone
			(layer "F.Cu")
			(hatch none 0.5)
			(connect_pads
				(clearance 0)
			)
			(min_thickness 0.25)
			(keepout
				(tracks not_allowed)
				(vias allowed)
				(pads allowed)
				(copperpour not_allowed)
				(footprints allowed)
			)
			(placement
				(enabled no)
				(sheetname "")
			)
			(fill
				(thermal_gap 0.5)
				(thermal_bridge_width 0.5)
				(island_removal_mode 0)
			)
			(polygon
				(pts
					(arc
						(start 99.572064 -505.85878)
						(mid 96.320864 -505.85878)
						(end 99.572064 -505.85878)
					)
				)
			)
		)
	)
	(footprint ""
		(layer "F.Cu")
		(at 50.217324 -173.13783 180)
		(property "Reference" "CE9"
			(at 0.06858 -5.780024 0)
			(unlocked yes)
			(layer "F.SilkS")
			(effects
				(font
					(size 0.7874 0.5842)
					(thickness 0.1524)
				)
				(justify left)
			)
		)
		(property "Value" ""
			(at 0 0 180)
			(layer "F.Fab")
			(effects
				(font
					(size 1.27 1.27)
				)
			)
		)
		(duplicate_pad_numbers_are_jumpers no)
		(fp_line
			(start 0 -4.2672)
			(end 0 4.2672)
			(stroke
				(width 0.1524)
				(type default)
			)
			(layer "F.SilkS")
		)
		(fp_circle
			(center 0 0)
			(end -4.2672 0)
			(stroke
				(width 0.1524)
				(type default)
			)
			(fill no)
			(layer "F.SilkS")
		)
		(fp_poly
			(pts
				(arc
					(start 0 -4.2672)
					(mid 4.2672 0)
					(end 0 4.2672)
				)
			)
			(stroke
				(width 0)
				(type default)
			)
			(fill yes)
			(layer "F.SilkS")
		)
		(fp_poly
			(pts
				(xy -2.5146 -0.762) (xy -0.9906 -0.762) (xy -0.9906 0.762) (xy -2.5146 0.762)
			)
			(stroke
				(width 0)
				(type default)
			)
			(fill no)
			(layer "B.CrtYd")
		)
		(fp_poly
			(pts
				(arc
					(start 1.7526 0.762)
					(mid 2.291415 -0.538815)
					(end 0.9906 0)
				)
				(arc
					(start 0.9906 0.0254)
					(mid 1.206345 0.546255)
					(end 1.7272 0.762)
				)
			)
			(stroke
				(width 0)
				(type default)
			)
			(fill no)
			(layer "B.CrtYd")
		)
		(fp_poly
			(pts
				(arc
					(start -4.2672 0)
					(mid 4.2672 0)
					(end -4.2672 0)
				)
			)
			(stroke
				(width 0)
				(type default)
			)
			(fill no)
			(layer "F.CrtYd")
		)
		(fp_circle
			(center 0 0)
			(end -4.2672 0)
			(stroke
				(width 0.1)
				(type default)
			)
			(fill no)
			(layer "F.Fab")
		)
		(fp_text user "+"
			(at -4.90728 1.70053 180)
			(unlocked yes)
			(layer "F.SilkS")
			(effects
				(font
					(size 0.7874 0.5842)
					(thickness 0.1524)
				)
				(justify left)
			)
		)
		(fp_text user "+"
			(at -5.6642 -0.34925 180)
			(unlocked yes)
			(layer "F.Fab")
			(effects
				(font
					(size 1.905 1.4224)
					(thickness 0.000001)
				)
				(justify left)
			)
		)
		(pad "1" thru_hole rect
			(at -1.75006 0 180)
			(size 1.397 1.397)
			(drill 0.9144)
			(layers "*.Cu" "*.Mask")
			(remove_unused_layers no)
			(net "P12V")
			(clearance 0.0127)
			(thermal_gap 0.0127)
			(padstack
				(mode front_inner_back)
				(layer "Inner"
					(shape circle)
					(size 1.397 1.397)
					(clearance 0.0127)
				)
				(layer "B.Cu"
					(shape rect)
					(size 1.397 1.397)
					(clearance 0.0127)
				)
			)
		)
		(pad "2" thru_hole circle
			(at 1.75006 0 180)
			(size 1.397 1.397)
			(drill 0.9144)
			(layers "*.Cu" "*.Mask")
			(remove_unused_layers no)
			(net "GND")
			(clearance 0.0127)
			(thermal_gap 0.0127)
		)
	)
	(footprint ""
		(layer "F.Cu")
		(at 91.399868 -197.81012)
		(property "Reference" "H20"
			(at -5.1308 -5.23113 0)
			(unlocked yes)
			(layer "F.SilkS")
			(effects
				(font
					(size 0.7874 0.5842)
					(thickness 0.1524)
				)
				(justify left)
			)
		)
		(property "Value" ""
			(at 0 0 0)
			(layer "F.Fab")
			(effects
				(font
					(size 1.27 1.27)
				)
			)
		)
		(duplicate_pad_numbers_are_jumpers no)
		(fp_circle
			(center 0 0)
			(end 4.826 0)
			(stroke
				(width 0.1524)
				(type default)
			)
			(fill no)
			(layer "F.SilkS")
		)
		(fp_circle
			(center 0 0)
			(end 4.826 0)
			(stroke
				(width 0.1524)
				(type default)
			)
			(fill no)
			(layer "B.SilkS")
		)
		(fp_poly
			(pts
				(arc
					(start 0 4.0132)
					(mid 0 -4.0132)
					(end 0 4.0132)
				)
			)
			(stroke
				(width 0)
				(type default)
			)
			(fill no)
			(layer "F.CrtYd")
		)
		(pad "" np_thru_hole circle
			(at 0 0)
			(size 8.001 8.001)
			(drill 8.001)
			(layers "*.Cu" "*.Mask")
			(clearance 0.381)
			(thermal_gap 0.381)
		)
		(zone
			(layers "F.Cu" "B.Cu" "In1.Cu" "In2.Cu" "In3.Cu" "In4.Cu" "In5.Cu" "In6.Cu")
			(hatch none 0.5)
			(connect_pads
				(clearance 0)
			)
			(min_thickness 0.25)
			(keepout
				(tracks not_allowed)
				(vias allowed)
				(pads allowed)
				(copperpour not_allowed)
				(footprints allowed)
			)
			(placement
				(enabled no)
				(sheetname "")
			)
			(fill
				(thermal_gap 0.5)
				(thermal_bridge_width 0.5)
				(island_removal_mode 0)
			)
			(polygon
				(pts
					(arc
						(start 91.399868 -193.28892)
						(mid 91.399868 -202.33132)
						(end 91.399868 -193.28892)
					)
				)
			)
		)
	)
	(footprint ""
		(layer "F.Cu")
		(at 74.832718 -263.260078 90)
		(property "Reference" "C46"
			(at -4.410456 0.239268 90)
			(unlocked yes)
			(layer "F.SilkS")
			(effects
				(font
					(size 0.7874 0.5842)
					(thickness 0.1524)
				)
				(justify left)
			)
		)
		(property "Value" ""
			(at 0 0 90)
			(layer "F.Fab")
			(effects
				(font
					(size 1.27 1.27)
				)
			)
		)
		(duplicate_pad_numbers_are_jumpers no)
		(fp_line
			(start 0.7874 -0.4064)
			(end 0.7874 0.4064)
			(stroke
				(width 0.1524)
				(type default)
			)
			(layer "F.SilkS")
		)
		(fp_line
			(start -0.7874 -0.4064)
			(end 0.7874 -0.4064)
			(stroke
				(width 0.1524)
				(type default)
			)
			(layer "F.SilkS")
		)
		(fp_line
			(start 0 0.381)
			(end 0 -0.381)
			(stroke
				(width 0.1524)
				(type default)
			)
			(layer "F.SilkS")
		)
		(fp_line
			(start 0.7874 0.4064)
			(end -0.7874 0.4064)
			(stroke
				(width 0.1524)
				(type default)
			)
			(layer "F.SilkS")
		)
		(fp_line
			(start -0.7874 0.4064)
			(end -0.7874 -0.4064)
			(stroke
				(width 0.1524)
				(type default)
			)
			(layer "F.SilkS")
		)
		(fp_poly
			(pts
				(xy -0.5334 0.254) (xy -0.635 0.254) (xy -0.635 0.2286) (xy -0.635 -0.254) (xy -0.5334 -0.254) (xy -0.5334 -0.2794)
				(xy 0.5334 -0.2794) (xy 0.5334 -0.254) (xy 0.635 -0.254) (xy 0.635 0.254) (xy 0.5334 0.254) (xy 0.5334 0.2794)
				(xy -0.508 0.2794) (xy -0.5334 0.2794)
			)
			(stroke
				(width 0)
				(type default)
			)
			(fill no)
			(layer "F.CrtYd")
		)
		(pad "1" smd rect
			(at 0.40005 0 90)
			(size 0.4572 0.508)
			(layers "F.Cu" "F.Mask" "F.Paste")
			(net "P12V")
		)
		(pad "2" smd rect
			(at -0.40005 0 90)
			(size 0.4572 0.508)
			(layers "F.Cu" "F.Mask" "F.Paste")
			(net "GND")
		)
	)
	(footprint ""
		(layer "F.Cu")
		(at 2.81559 -395.443964 90)
		(property "Reference" "R152"
			(at -4.444746 0.160528 90)
			(unlocked yes)
			(layer "F.SilkS")
			(effects
				(font
					(size 0.7874 0.5842)
					(thickness 0.1524)
				)
				(justify left)
			)
		)
		(property "Value" ""
			(at 0 0 90)
			(layer "F.Fab")
			(effects
				(font
					(size 1.27 1.27)
				)
			)
		)
		(duplicate_pad_numbers_are_jumpers no)
		(fp_line
			(start 0.7874 -0.4064)
			(end 0.7874 0.4064)
			(stroke
				(width 0.1524)
				(type default)
			)
			(layer "F.SilkS")
		)
		(fp_line
			(start -0.7874 -0.4064)
			(end 0.7874 -0.4064)
			(stroke
				(width 0.1524)
				(type default)
			)
			(layer "F.SilkS")
		)
		(fp_line
			(start 0.7874 0.4064)
			(end -0.7874 0.4064)
			(stroke
				(width 0.1524)
				(type default)
			)
			(layer "F.SilkS")
		)
		(fp_line
			(start -0.7874 0.4064)
			(end -0.7874 -0.4064)
			(stroke
				(width 0.1524)
				(type default)
			)
			(layer "F.SilkS")
		)
		(fp_poly
			(pts
				(xy -0.508 0.2794) (xy -0.508 0.2286) (xy -0.635 0.2286) (xy -0.635 -0.254) (xy -0.5334 -0.254)
				(xy -0.5334 -0.2794) (xy 0.5334 -0.2794) (xy 0.5334 -0.254) (xy 0.635 -0.254) (xy 0.635 0.254) (xy 0.5334 0.254)
				(xy 0.5334 0.2794)
			)
			(stroke
				(width 0)
				(type default)
			)
			(fill no)
			(layer "F.CrtYd")
		)
		(pad "1" smd rect
			(at 0.40005 0 90)
			(size 0.4572 0.508)
			(layers "F.Cu" "F.Mask" "F.Paste")
			(net "N42132933")
		)
		(pad "2" smd rect
			(at -0.40005 0 90)
			(size 0.4572 0.508)
			(layers "F.Cu" "F.Mask" "F.Paste")
			(net "GND")
		)
	)
	(footprint ""
		(layer "F.Cu")
		(at 46.496478 -248.705116 180)
		(property "Reference" "R95"
			(at -0.92964 -0.866902 0)
			(unlocked yes)
			(layer "F.SilkS")
			(effects
				(font
					(size 0.7874 0.5842)
					(thickness 0.1524)
				)
				(justify left)
			)
		)
		(property "Value" ""
			(at 0 0 180)
			(layer "F.Fab")
			(effects
				(font
					(size 1.27 1.27)
				)
			)
		)
		(duplicate_pad_numbers_are_jumpers no)
		(fp_line
			(start 0.7874 0.4064)
			(end -0.7874 0.4064)
			(stroke
				(width 0.1524)
				(type default)
			)
			(layer "F.SilkS")
		)
		(fp_line
			(start 0.7874 -0.4064)
			(end 0.7874 0.4064)
			(stroke
				(width 0.1524)
				(type default)
			)
			(layer "F.SilkS")
		)
		(fp_line
			(start -0.7874 0.4064)
			(end -0.7874 -0.4064)
			(stroke
				(width 0.1524)
				(type default)
			)
			(layer "F.SilkS")
		)
		(fp_line
			(start -0.7874 -0.4064)
			(end 0.7874 -0.4064)
			(stroke
				(width 0.1524)
				(type default)
			)
			(layer "F.SilkS")
		)
		(fp_poly
			(pts
				(xy -0.508 0.2794) (xy -0.508 0.2286) (xy -0.635 0.2286) (xy -0.635 -0.254) (xy -0.5334 -0.254)
				(xy -0.5334 -0.2794) (xy 0.5334 -0.2794) (xy 0.5334 -0.254) (xy 0.635 -0.254) (xy 0.635 0.254) (xy 0.5334 0.254)
				(xy 0.5334 0.2794)
			)
			(stroke
				(width 0)
				(type default)
			)
			(fill no)
			(layer "F.CrtYd")
		)
		(pad "1" smd rect
			(at 0.40005 0 180)
			(size 0.4572 0.508)
			(layers "F.Cu" "F.Mask" "F.Paste")
			(net "PSU3_REMOTE_R_N")
		)
		(pad "2" smd rect
			(at -0.40005 0 180)
			(size 0.4572 0.508)
			(layers "F.Cu" "F.Mask" "F.Paste")
			(net "GND")
		)
	)
	(footprint ""
		(layer "F.Cu")
		(at 74.69886 -415.478722 -90)
		(property "Reference" "C66"
			(at -3.000502 0.051816 90)
			(unlocked yes)
			(layer "F.SilkS")
			(effects
				(font
					(size 0.7874 0.5842)
					(thickness 0.1524)
				)
				(justify left)
			)
		)
		(property "Value" ""
			(at 0 0 270)
			(layer "F.Fab")
			(effects
				(font
					(size 1.27 1.27)
				)
			)
		)
		(duplicate_pad_numbers_are_jumpers no)
		(fp_line
			(start -0.7874 0.4064)
			(end -0.7874 -0.4064)
			(stroke
				(width 0.1524)
				(type default)
			)
			(layer "F.SilkS")
		)
		(fp_line
			(start 0.7874 0.4064)
			(end -0.7874 0.4064)
			(stroke
				(width 0.1524)
				(type default)
			)
			(layer "F.SilkS")
		)
		(fp_line
			(start 0 0.381)
			(end 0 -0.381)
			(stroke
				(width 0.1524)
				(type default)
			)
			(layer "F.SilkS")
		)
		(fp_line
			(start -0.7874 -0.4064)
			(end 0.7874 -0.4064)
			(stroke
				(width 0.1524)
				(type default)
			)
			(layer "F.SilkS")
		)
		(fp_line
			(start 0.7874 -0.4064)
			(end 0.7874 0.4064)
			(stroke
				(width 0.1524)
				(type default)
			)
			(layer "F.SilkS")
		)
		(fp_poly
			(pts
				(xy -0.5334 0.254) (xy -0.635 0.254) (xy -0.635 0.2286) (xy -0.635 -0.254) (xy -0.5334 -0.254) (xy -0.5334 -0.2794)
				(xy 0.5334 -0.2794) (xy 0.5334 -0.254) (xy 0.635 -0.254) (xy 0.635 0.254) (xy 0.5334 0.254) (xy 0.5334 0.2794)
				(xy -0.508 0.2794) (xy -0.5334 0.2794)
			)
			(stroke
				(width 0)
				(type default)
			)
			(fill no)
			(layer "F.CrtYd")
		)
		(pad "1" smd rect
			(at 0.40005 0 270)
			(size 0.4572 0.508)
			(layers "F.Cu" "F.Mask" "F.Paste")
			(net "P12V")
		)
		(pad "2" smd rect
			(at -0.40005 0 270)
			(size 0.4572 0.508)
			(layers "F.Cu" "F.Mask" "F.Paste")
			(net "GND")
		)
	)
	(footprint ""
		(layer "F.Cu")
		(at 2.439924 -380.824994 90)
		(property "Reference" "J32"
			(at -1.722628 4.838954 90)
			(unlocked yes)
			(layer "F.SilkS")
			(effects
				(font
					(size 0.7874 0.5842)
					(thickness 0.1524)
				)
				(justify left)
			)
		)
		(property "Value" ""
			(at 0 0 90)
			(layer "F.Fab")
			(effects
				(font
					(size 1.27 1.27)
				)
			)
		)
		(duplicate_pad_numbers_are_jumpers no)
		(fp_line
			(start 1.849882 -1.999996)
			(end -3.02006 -1.999996)
			(stroke
				(width 0.1524)
				(type default)
			)
			(layer "F.SilkS")
		)
		(fp_line
			(start -3.02006 -1.999996)
			(end -3.02006 3.999992)
			(stroke
				(width 0.1524)
				(type default)
			)
			(layer "F.SilkS")
		)
		(fp_line
			(start 1.35001 -1.500124)
			(end -2.519934 -1.500124)
			(stroke
				(width 0.1524)
				(type default)
			)
			(layer "F.SilkS")
		)
		(fp_line
			(start -2.519934 -1.500124)
			(end -2.519934 3.50012)
			(stroke
				(width 0.1524)
				(type default)
			)
			(layer "F.SilkS")
		)
		(fp_line
			(start 1.849882 0.500126)
			(end 1.35001 0.500126)
			(stroke
				(width 0.1524)
				(type default)
			)
			(layer "F.SilkS")
		)
		(fp_line
			(start 1.35001 0.500126)
			(end 1.35001 -1.500124)
			(stroke
				(width 0.1524)
				(type default)
			)
			(layer "F.SilkS")
		)
		(fp_line
			(start 1.35001 1.500124)
			(end 1.849882 1.500124)
			(stroke
				(width 0.1524)
				(type default)
			)
			(layer "F.SilkS")
		)
		(fp_line
			(start 1.35001 3.50012)
			(end 1.35001 1.500124)
			(stroke
				(width 0.1524)
				(type default)
			)
			(layer "F.SilkS")
		)
		(fp_line
			(start -2.519934 3.50012)
			(end 1.35001 3.50012)
			(stroke
				(width 0.1524)
				(type default)
			)
			(layer "F.SilkS")
		)
		(fp_line
			(start 1.849882 3.999992)
			(end 1.849882 -1.999996)
			(stroke
				(width 0.1524)
				(type default)
			)
			(layer "F.SilkS")
		)
		(fp_line
			(start -3.02006 3.999992)
			(end 1.849882 3.999992)
			(stroke
				(width 0.1524)
				(type default)
			)
			(layer "F.SilkS")
		)
		(fp_poly
			(pts
				(xy 2.01041 0) (xy 3.06959 -0.52959) (xy 3.06959 0.52959)
			)
			(stroke
				(width 0)
				(type default)
			)
			(fill yes)
			(layer "F.SilkS")
		)
		(fp_poly
			(pts
				(xy -0.8382 2.8194) (xy 0.8382 2.8194) (xy 0.8382 -0.8382) (xy -0.8382 -0.8382)
			)
			(stroke
				(width 0)
				(type default)
			)
			(fill no)
			(layer "B.CrtYd")
		)
		(fp_poly
			(pts
				(xy -3.02006 3.999992) (xy 1.849882 3.999992) (xy 1.849882 -1.999996) (xy -3.02006 -1.999996)
			)
			(stroke
				(width 0)
				(type default)
			)
			(fill no)
			(layer "F.CrtYd")
		)
		(fp_line
			(start 1.849882 -1.999996)
			(end -3.02006 -1.999996)
			(stroke
				(width 0.1)
				(type default)
			)
			(layer "F.Fab")
		)
		(fp_line
			(start -3.02006 -1.999996)
			(end -3.02006 3.999992)
			(stroke
				(width 0.1)
				(type default)
			)
			(layer "F.Fab")
		)
		(fp_line
			(start 1.849882 3.999992)
			(end 1.849882 -1.999996)
			(stroke
				(width 0.1)
				(type default)
			)
			(layer "F.Fab")
		)
		(fp_line
			(start -3.02006 3.999992)
			(end 1.849882 3.999992)
			(stroke
				(width 0.1)
				(type default)
			)
			(layer "F.Fab")
		)
		(fp_poly
			(pts
				(xy 2.01041 0) (xy 3.06959 -0.52959) (xy 3.06959 0.52959)
			)
			(stroke
				(width 0)
				(type default)
			)
			(fill yes)
			(layer "F.Fab")
		)
		(fp_text user "2"
			(at 2.5527 2.16535 90)
			(unlocked yes)
			(layer "F.SilkS")
			(effects
				(font
					(size 0.7874 0.5842)
					(thickness 0.1524)
				)
			)
		)
		(fp_text user "1"
			(at 1.2192 0.00127 90)
			(unlocked yes)
			(layer "B.SilkS")
			(effects
				(font
					(size 0.7874 0.5842)
					(thickness 0.1524)
				)
				(justify mirror)
			)
		)
		(fp_text user "2"
			(at 1.2192 2.001266 90)
			(unlocked yes)
			(layer "B.SilkS")
			(effects
				(font
					(size 0.7874 0.5842)
					(thickness 0.1524)
				)
				(justify mirror)
			)
		)
		(fp_text user "1"
			(at 1.2192 0.00127 90)
			(unlocked yes)
			(layer "B.Fab")
			(effects
				(font
					(size 0.7874 0.5842)
					(thickness 0.1524)
				)
				(justify mirror)
			)
		)
		(fp_text user "2"
			(at 1.2192 2.001266 90)
			(unlocked yes)
			(layer "B.Fab")
			(effects
				(font
					(size 0.7874 0.5842)
					(thickness 0.1524)
				)
				(justify mirror)
			)
		)
		(fp_text user "2"
			(at 2.5527 2.16535 90)
			(unlocked yes)
			(layer "F.Fab")
			(effects
				(font
					(size 0.7874 0.5842)
					(thickness 0.1524)
				)
			)
		)
		(pad "1" thru_hole rect
			(at 0 0 90)
			(size 1.524 1.524)
			(drill 1.016)
			(layers "*.Cu" "*.Mask")
			(remove_unused_layers no)
			(net "POWER_SW1_PWR_CTR_12V")
			(clearance 0)
			(padstack
				(mode front_inner_back)
				(layer "Inner"
					(shape circle)
					(size 1.524 1.524)
					(clearance 0)
				)
				(layer "B.Cu"
					(shape rect)
					(size 1.524 1.524)
					(clearance 0)
				)
			)
		)
		(pad "2" thru_hole circle
			(at 0 1.999996 90)
			(size 1.524 1.524)
			(drill 1.016)
			(layers "*.Cu" "*.Mask")
			(remove_unused_layers no)
			(net "GND")
			(clearance 0)
		)
	)
	(footprint ""
		(layer "F.Cu")
		(at 50.32756 -285.205424 180)
		(property "Reference" "CE13"
			(at -4.667758 1.872742 0)
			(unlocked yes)
			(layer "F.SilkS")
			(effects
				(font
					(size 0.7874 0.5842)
					(thickness 0.1524)
				)
				(justify left)
			)
		)
		(property "Value" ""
			(at 0 0 180)
			(layer "F.Fab")
			(effects
				(font
					(size 1.27 1.27)
				)
			)
		)
		(duplicate_pad_numbers_are_jumpers no)
		(fp_line
			(start 0 -4.2672)
			(end 0 4.2672)
			(stroke
				(width 0.1524)
				(type default)
			)
			(layer "F.SilkS")
		)
		(fp_circle
			(center 0 0)
			(end -4.2672 0)
			(stroke
				(width 0.1524)
				(type default)
			)
			(fill no)
			(layer "F.SilkS")
		)
		(fp_poly
			(pts
				(arc
					(start 0 -4.2672)
					(mid 4.2672 0)
					(end 0 4.2672)
				)
			)
			(stroke
				(width 0)
				(type default)
			)
			(fill yes)
			(layer "F.SilkS")
		)
		(fp_poly
			(pts
				(xy -2.5146 -0.762) (xy -0.9906 -0.762) (xy -0.9906 0.762) (xy -2.5146 0.762)
			)
			(stroke
				(width 0)
				(type default)
			)
			(fill no)
			(layer "B.CrtYd")
		)
		(fp_poly
			(pts
				(arc
					(start 1.7526 0.762)
					(mid 2.291415 -0.538815)
					(end 0.9906 0)
				)
				(arc
					(start 0.9906 0.0254)
					(mid 1.206345 0.546255)
					(end 1.7272 0.762)
				)
			)
			(stroke
				(width 0)
				(type default)
			)
			(fill no)
			(layer "B.CrtYd")
		)
		(fp_poly
			(pts
				(arc
					(start -4.2672 0)
					(mid 4.2672 0)
					(end -4.2672 0)
				)
			)
			(stroke
				(width 0)
				(type default)
			)
			(fill no)
			(layer "F.CrtYd")
		)
		(fp_circle
			(center 0 0)
			(end -4.2672 0)
			(stroke
				(width 0.1)
				(type default)
			)
			(fill no)
			(layer "F.Fab")
		)
		(fp_text user "+"
			(at -5.6642 0.15367 180)
			(unlocked yes)
			(layer "F.SilkS")
			(effects
				(font
					(size 0.7874 0.5842)
					(thickness 0.1524)
				)
				(justify left)
			)
		)
		(fp_text user "+"
			(at -5.6642 -0.34925 180)
			(unlocked yes)
			(layer "F.Fab")
			(effects
				(font
					(size 1.905 1.4224)
					(thickness 0.000001)
				)
				(justify left)
			)
		)
		(pad "1" thru_hole rect
			(at -1.75006 0 180)
			(size 1.397 1.397)
			(drill 0.9144)
			(layers "*.Cu" "*.Mask")
			(remove_unused_layers no)
			(net "P12V")
			(clearance 0.0127)
			(thermal_gap 0.0127)
			(padstack
				(mode front_inner_back)
				(layer "Inner"
					(shape circle)
					(size 1.397 1.397)
					(clearance 0.0127)
				)
				(layer "B.Cu"
					(shape rect)
					(size 1.397 1.397)
					(clearance 0.0127)
				)
			)
		)
		(pad "2" thru_hole circle
			(at 1.75006 0 180)
			(size 1.397 1.397)
			(drill 0.9144)
			(layers "*.Cu" "*.Mask")
			(remove_unused_layers no)
			(net "GND")
			(clearance 0.0127)
			(thermal_gap 0.0127)
		)
	)
	(footprint ""
		(layer "F.Cu")
		(at 70.260718 -60.163456 -90)
		(property "Reference" "C9"
			(at -2.559304 0.19939 90)
			(unlocked yes)
			(layer "F.SilkS")
			(effects
				(font
					(size 0.7874 0.5842)
					(thickness 0.1524)
				)
				(justify left)
			)
		)
		(property "Value" ""
			(at 0 0 270)
			(layer "F.Fab")
			(effects
				(font
					(size 1.27 1.27)
				)
			)
		)
		(duplicate_pad_numbers_are_jumpers no)
		(fp_line
			(start -0.7874 0.4064)
			(end -0.7874 -0.4064)
			(stroke
				(width 0.1524)
				(type default)
			)
			(layer "F.SilkS")
		)
		(fp_line
			(start 0.7874 0.4064)
			(end -0.7874 0.4064)
			(stroke
				(width 0.1524)
				(type default)
			)
			(layer "F.SilkS")
		)
		(fp_line
			(start 0 0.381)
			(end 0 -0.381)
			(stroke
				(width 0.1524)
				(type default)
			)
			(layer "F.SilkS")
		)
		(fp_line
			(start -0.7874 -0.4064)
			(end 0.7874 -0.4064)
			(stroke
				(width 0.1524)
				(type default)
			)
			(layer "F.SilkS")
		)
		(fp_line
			(start 0.7874 -0.4064)
			(end 0.7874 0.4064)
			(stroke
				(width 0.1524)
				(type default)
			)
			(layer "F.SilkS")
		)
		(fp_poly
			(pts
				(xy -0.5334 0.254) (xy -0.635 0.254) (xy -0.635 0.2286) (xy -0.635 -0.254) (xy -0.5334 -0.254) (xy -0.5334 -0.2794)
				(xy 0.5334 -0.2794) (xy 0.5334 -0.254) (xy 0.635 -0.254) (xy 0.635 0.254) (xy 0.5334 0.254) (xy 0.5334 0.2794)
				(xy -0.508 0.2794) (xy -0.5334 0.2794)
			)
			(stroke
				(width 0)
				(type default)
			)
			(fill no)
			(layer "F.CrtYd")
		)
		(pad "1" smd rect
			(at 0.40005 0 270)
			(size 0.4572 0.508)
			(layers "F.Cu" "F.Mask" "F.Paste")
			(net "P12V")
		)
		(pad "2" smd rect
			(at -0.40005 0 270)
			(size 0.4572 0.508)
			(layers "F.Cu" "F.Mask" "F.Paste")
			(net "GND")
		)
	)
	(footprint ""
		(layer "F.Cu")
		(at 77.999844 -210.09991)
		(property "Reference" "H7"
			(at -2.377186 -8.725154 0)
			(unlocked yes)
			(layer "F.SilkS")
			(effects
				(font
					(size 0.7874 0.5842)
					(thickness 0.1524)
				)
				(justify left)
			)
		)
		(property "Value" ""
			(at 0 0 0)
			(layer "F.Fab")
			(effects
				(font
					(size 1.27 1.27)
				)
			)
		)
		(duplicate_pad_numbers_are_jumpers no)
		(fp_circle
			(center 0 0)
			(end 7.999984 0)
			(stroke
				(width 0.1524)
				(type default)
			)
			(fill no)
			(layer "F.SilkS")
		)
		(fp_circle
			(center 0 0)
			(end 14.7066 0)
			(stroke
				(width 0.1524)
				(type default)
			)
			(fill no)
			(layer "B.SilkS")
		)
		(fp_poly
			(pts
				(arc
					(start 5.0038 0)
					(mid -5.0038 0)
					(end 5.0038 0)
				)
			)
			(stroke
				(width 0)
				(type default)
			)
			(fill no)
			(layer "F.CrtYd")
		)
		(pad "" np_thru_hole circle
			(at 0 0)
			(size 4.0132 4.0132)
			(drill 4.0132)
			(layers "*.Cu" "*.Mask")
			(clearance 0.381)
			(thermal_gap 0.381)
		)
		(pad "2" thru_hole circle
			(at 0 -3.50012)
			(size 0.762 0.762)
			(drill 0.5588)
			(layers "*.Cu" "*.Mask")
			(remove_unused_layers no)
			(net "GND")
			(clearance 0.1524)
			(thermal_gap 0.1524)
		)
		(pad "3" thru_hole circle
			(at -2.500122 -2.500122)
			(size 0.762 0.762)
			(drill 0.5588)
			(layers "*.Cu" "*.Mask")
			(remove_unused_layers no)
			(net "GND")
			(clearance 0.1524)
			(thermal_gap 0.1524)
		)
		(pad "4" thru_hole circle
			(at -3.50012 0)
			(size 0.762 0.762)
			(drill 0.5588)
			(layers "*.Cu" "*.Mask")
			(remove_unused_layers no)
			(net "GND")
			(clearance 0.1524)
			(thermal_gap 0.1524)
		)
		(pad "5" thru_hole circle
			(at -2.500122 2.500122)
			(size 0.762 0.762)
			(drill 0.5588)
			(layers "*.Cu" "*.Mask")
			(remove_unused_layers no)
			(net "GND")
			(clearance 0.1524)
			(thermal_gap 0.1524)
		)
		(pad "6" thru_hole circle
			(at 0 3.50012)
			(size 0.762 0.762)
			(drill 0.5588)
			(layers "*.Cu" "*.Mask")
			(remove_unused_layers no)
			(net "GND")
			(clearance 0.1524)
			(thermal_gap 0.1524)
		)
		(pad "7" thru_hole circle
			(at 2.500122 2.500122)
			(size 0.762 0.762)
			(drill 0.5588)
			(layers "*.Cu" "*.Mask")
			(remove_unused_layers no)
			(net "GND")
			(clearance 0.1524)
			(thermal_gap 0.1524)
		)
		(pad "8" thru_hole circle
			(at 3.50012 0)
			(size 0.762 0.762)
			(drill 0.5588)
			(layers "*.Cu" "*.Mask")
			(remove_unused_layers no)
			(net "GND")
			(clearance 0.1524)
			(thermal_gap 0.1524)
		)
		(pad "9" thru_hole circle
			(at 2.500122 -2.500122)
			(size 0.762 0.762)
			(drill 0.5588)
			(layers "*.Cu" "*.Mask")
			(remove_unused_layers no)
			(net "GND")
			(clearance 0.1524)
			(thermal_gap 0.1524)
		)
		(zone
			(layer "F.Cu")
			(hatch none 0.5)
			(connect_pads
				(clearance 0)
			)
			(min_thickness 0.25)
			(keepout
				(tracks not_allowed)
				(vias allowed)
				(pads allowed)
				(copperpour not_allowed)
				(footprints allowed)
			)
			(placement
				(enabled no)
				(sheetname "")
			)
			(fill
				(thermal_gap 0.5)
				(thermal_bridge_width 0.5)
				(island_removal_mode 0)
			)
			(polygon
				(pts
					(arc
						(start 77.999844 -218.10091)
						(mid 69.998844 -210.09991)
						(end 77.999844 -202.09891)
					)
					(arc
						(start 77.999844 -202.09891)
						(mid 79.434944 -203.53401)
						(end 77.999844 -204.96911)
					)
					(arc
						(start 77.999844 -204.96911)
						(mid 72.869044 -210.09991)
						(end 77.999844 -215.23071)
					)
					(arc
						(start 77.999844 -215.23071)
						(mid 79.434944 -216.66581)
						(end 77.999844 -218.10091)
					)
				)
			)
		)
		(zone
			(layer "F.Cu")
			(hatch none 0.5)
			(connect_pads
				(clearance 0)
			)
			(min_thickness 0.25)
			(keepout
				(tracks not_allowed)
				(vias allowed)
				(pads allowed)
				(copperpour not_allowed)
				(footprints allowed)
			)
			(placement
				(enabled no)
				(sheetname "")
			)
			(fill
				(thermal_gap 0.5)
				(thermal_bridge_width 0.5)
				(island_removal_mode 0)
			)
			(polygon
				(pts
					(arc
						(start 77.999844 -218.10091)
						(mid 86.000844 -210.09991)
						(end 77.999844 -202.09891)
					)
					(arc
						(start 77.999844 -202.09891)
						(mid 76.564744 -203.53401)
						(end 77.999844 -204.96911)
					)
					(arc
						(start 77.999844 -204.96911)
						(mid 83.130644 -210.09991)
						(end 77.999844 -215.23071)
					)
					(arc
						(start 77.999844 -215.23071)
						(mid 76.564744 -216.66581)
						(end 77.999844 -218.10091)
					)
				)
			)
		)
		(zone
			(layers "F.Cu" "B.Cu" "In1.Cu" "In2.Cu" "In3.Cu" "In4.Cu" "In5.Cu" "In6.Cu")
			(hatch none 0.5)
			(connect_pads
				(clearance 0)
			)
			(min_thickness 0.25)
			(keepout
				(tracks not_allowed)
				(vias allowed)
				(pads allowed)
				(copperpour not_allowed)
				(footprints allowed)
			)
			(placement
				(enabled no)
				(sheetname "")
			)
			(fill
				(thermal_gap 0.5)
				(thermal_bridge_width 0.5)
				(island_removal_mode 0)
			)
			(polygon
				(pts
					(arc
						(start 80.511904 -210.09991)
						(mid 75.487784 -210.09991)
						(end 80.511904 -210.09991)
					)
				)
			)
		)
	)
	(footprint ""
		(layer "F.Cu")
		(at 46.436788 -251.703332 180)
		(property "Reference" "R100"
			(at 2.469388 -1.292098 0)
			(unlocked yes)
			(layer "F.SilkS")
			(effects
				(font
					(size 0.7874 0.5842)
					(thickness 0.1524)
				)
				(justify left)
			)
		)
		(property "Value" ""
			(at 0 0 180)
			(layer "F.Fab")
			(effects
				(font
					(size 1.27 1.27)
				)
			)
		)
		(duplicate_pad_numbers_are_jumpers no)
		(fp_line
			(start 0.7874 0.4064)
			(end -0.7874 0.4064)
			(stroke
				(width 0.1524)
				(type default)
			)
			(layer "F.SilkS")
		)
		(fp_line
			(start 0.7874 -0.4064)
			(end 0.7874 0.4064)
			(stroke
				(width 0.1524)
				(type default)
			)
			(layer "F.SilkS")
		)
		(fp_line
			(start -0.7874 0.4064)
			(end -0.7874 -0.4064)
			(stroke
				(width 0.1524)
				(type default)
			)
			(layer "F.SilkS")
		)
		(fp_line
			(start -0.7874 -0.4064)
			(end 0.7874 -0.4064)
			(stroke
				(width 0.1524)
				(type default)
			)
			(layer "F.SilkS")
		)
		(fp_poly
			(pts
				(xy -0.508 0.2794) (xy -0.508 0.2286) (xy -0.635 0.2286) (xy -0.635 -0.254) (xy -0.5334 -0.254)
				(xy -0.5334 -0.2794) (xy 0.5334 -0.2794) (xy 0.5334 -0.254) (xy 0.635 -0.254) (xy 0.635 0.254) (xy 0.5334 0.254)
				(xy 0.5334 0.2794)
			)
			(stroke
				(width 0)
				(type default)
			)
			(fill no)
			(layer "F.CrtYd")
		)
		(pad "1" smd rect
			(at 0.40005 0 180)
			(size 0.4572 0.508)
			(layers "F.Cu" "F.Mask" "F.Paste")
			(net "PSU6_REMOTE_R_P")
		)
		(pad "2" smd rect
			(at -0.40005 0 180)
			(size 0.4572 0.508)
			(layers "F.Cu" "F.Mask" "F.Paste")
			(net "P12V")
		)
	)
	(footprint ""
		(layer "F.Cu")
		(at 39.798752 -197.274942)
		(property "Reference" "R42"
			(at 2.029968 0.33401 0)
			(unlocked yes)
			(layer "F.SilkS")
			(effects
				(font
					(size 0.7874 0.5842)
					(thickness 0.1524)
				)
				(justify left)
			)
		)
		(property "Value" ""
			(at 0 0 0)
			(layer "F.Fab")
			(effects
				(font
					(size 1.27 1.27)
				)
			)
		)
		(duplicate_pad_numbers_are_jumpers no)
		(fp_line
			(start -0.7874 -0.4064)
			(end 0.7874 -0.4064)
			(stroke
				(width 0.1524)
				(type default)
			)
			(layer "F.SilkS")
		)
		(fp_line
			(start -0.7874 0.4064)
			(end -0.7874 -0.4064)
			(stroke
				(width 0.1524)
				(type default)
			)
			(layer "F.SilkS")
		)
		(fp_line
			(start 0.7874 -0.4064)
			(end 0.7874 0.4064)
			(stroke
				(width 0.1524)
				(type default)
			)
			(layer "F.SilkS")
		)
		(fp_line
			(start 0.7874 0.4064)
			(end -0.7874 0.4064)
			(stroke
				(width 0.1524)
				(type default)
			)
			(layer "F.SilkS")
		)
		(fp_poly
			(pts
				(xy -0.508 0.2794) (xy -0.508 0.2286) (xy -0.635 0.2286) (xy -0.635 -0.254) (xy -0.5334 -0.254)
				(xy -0.5334 -0.2794) (xy 0.5334 -0.2794) (xy 0.5334 -0.254) (xy 0.635 -0.254) (xy 0.635 0.254) (xy 0.5334 0.254)
				(xy 0.5334 0.2794)
			)
			(stroke
				(width 0)
				(type default)
			)
			(fill no)
			(layer "F.CrtYd")
		)
		(pad "1" smd rect
			(at 0.40005 0)
			(size 0.4572 0.508)
			(layers "F.Cu" "F.Mask" "F.Paste")
			(net "GND")
		)
		(pad "2" smd rect
			(at -0.40005 0)
			(size 0.4572 0.508)
			(layers "F.Cu" "F.Mask" "F.Paste")
			(net "P12V_STBY")
		)
	)
	(footprint ""
		(layer "F.Cu")
		(at 71.390764 -460.240634 -90)
		(property "Reference" "C71"
			(at -3.534156 -0.42799 90)
			(unlocked yes)
			(layer "F.SilkS")
			(effects
				(font
					(size 0.7874 0.5842)
					(thickness 0.1524)
				)
			)
		)
		(property "Value" ""
			(at 0 0 270)
			(layer "F.Fab")
			(effects
				(font
					(size 1.27 1.27)
				)
			)
		)
		(duplicate_pad_numbers_are_jumpers no)
		(fp_line
			(start -1.2954 0.5842)
			(end -1.2954 -0.5842)
			(stroke
				(width 0.1524)
				(type default)
			)
			(layer "F.SilkS")
		)
		(fp_line
			(start 1.2954 0.5842)
			(end -1.2954 0.5842)
			(stroke
				(width 0.1524)
				(type default)
			)
			(layer "F.SilkS")
		)
		(fp_line
			(start -1.2954 -0.5842)
			(end 1.2954 -0.5842)
			(stroke
				(width 0.1524)
				(type default)
			)
			(layer "F.SilkS")
		)
		(fp_line
			(start 0 -0.5842)
			(end 0 0.5842)
			(stroke
				(width 0.1524)
				(type default)
			)
			(layer "F.SilkS")
		)
		(fp_line
			(start 1.2954 -0.5842)
			(end 1.2954 0.5842)
			(stroke
				(width 0.1524)
				(type default)
			)
			(layer "F.SilkS")
		)
		(fp_poly
			(pts
				(xy 0.8636 -0.4572) (xy 0.8636 -0.3556) (xy 1.143 -0.3556) (xy 1.143 0.3556) (xy 0.8636 0.3556)
				(xy 0.8636 0.4572) (xy -0.8636 0.4572) (xy -0.8636 0.3556) (xy -1.143 0.3556) (xy -1.143 -0.3556)
				(xy -0.8636 -0.3556) (xy -0.8636 -0.4572)
			)
			(stroke
				(width 0)
				(type default)
			)
			(fill no)
			(layer "F.CrtYd")
		)
		(fp_line
			(start -0.884936 0.504952)
			(end -0.884936 -0.504952)
			(stroke
				(width 0.1)
				(type default)
			)
			(layer "F.Fab")
		)
		(fp_line
			(start 0.884936 0.504952)
			(end -0.884936 0.504952)
			(stroke
				(width 0.1)
				(type default)
			)
			(layer "F.Fab")
		)
		(fp_line
			(start -0.884936 -0.504952)
			(end 0.884936 -0.504952)
			(stroke
				(width 0.1)
				(type default)
			)
			(layer "F.Fab")
		)
		(fp_line
			(start 0.884936 -0.504952)
			(end 0.884936 0.504952)
			(stroke
				(width 0.1)
				(type default)
			)
			(layer "F.Fab")
		)
		(pad "1" smd rect
			(at 0.7366 0)
			(size 0.7112 0.8128)
			(layers "F.Cu" "F.Mask" "F.Paste")
			(net "P12V")
		)
		(pad "2" smd rect
			(at -0.7366 0)
			(size 0.7112 0.8128)
			(layers "F.Cu" "F.Mask" "F.Paste")
			(net "GND")
		)
	)
	(footprint ""
		(layer "F.Cu")
		(at 39.858442 -110.774226 180)
		(property "Reference" "R3"
			(at -1.626616 0.658622 0)
			(unlocked yes)
			(layer "F.SilkS")
			(effects
				(font
					(size 0.7874 0.5842)
					(thickness 0.1524)
				)
				(justify left)
			)
		)
		(property "Value" ""
			(at 0 0 180)
			(layer "F.Fab")
			(effects
				(font
					(size 1.27 1.27)
				)
			)
		)
		(duplicate_pad_numbers_are_jumpers no)
		(fp_line
			(start 0.7874 0.4064)
			(end -0.7874 0.4064)
			(stroke
				(width 0.1524)
				(type default)
			)
			(layer "F.SilkS")
		)
		(fp_line
			(start 0.7874 -0.4064)
			(end 0.7874 0.4064)
			(stroke
				(width 0.1524)
				(type default)
			)
			(layer "F.SilkS")
		)
		(fp_line
			(start -0.7874 0.4064)
			(end -0.7874 -0.4064)
			(stroke
				(width 0.1524)
				(type default)
			)
			(layer "F.SilkS")
		)
		(fp_line
			(start -0.7874 -0.4064)
			(end 0.7874 -0.4064)
			(stroke
				(width 0.1524)
				(type default)
			)
			(layer "F.SilkS")
		)
		(fp_poly
			(pts
				(xy -0.508 0.2794) (xy -0.508 0.2286) (xy -0.635 0.2286) (xy -0.635 -0.254) (xy -0.5334 -0.254)
				(xy -0.5334 -0.2794) (xy 0.5334 -0.2794) (xy 0.5334 -0.254) (xy 0.635 -0.254) (xy 0.635 0.254) (xy 0.5334 0.254)
				(xy 0.5334 0.2794)
			)
			(stroke
				(width 0)
				(type default)
			)
			(fill no)
			(layer "F.CrtYd")
		)
		(pad "1" smd rect
			(at 0.40005 0 180)
			(size 0.4572 0.508)
			(layers "F.Cu" "F.Mask" "F.Paste")
			(net "PSU2_REMOTE_P")
		)
		(pad "2" smd rect
			(at -0.40005 0 180)
			(size 0.4572 0.508)
			(layers "F.Cu" "F.Mask" "F.Paste")
			(net "P12V")
		)
	)
	(footprint ""
		(layer "F.Cu")
		(at 46.40834 -243.096034 180)
		(property "Reference" "R92"
			(at 4.252722 -0.212598 0)
			(unlocked yes)
			(layer "F.SilkS")
			(effects
				(font
					(size 0.7874 0.5842)
					(thickness 0.1524)
				)
				(justify left)
			)
		)
		(property "Value" ""
			(at 0 0 180)
			(layer "F.Fab")
			(effects
				(font
					(size 1.27 1.27)
				)
			)
		)
		(duplicate_pad_numbers_are_jumpers no)
		(fp_line
			(start 0.7874 0.4064)
			(end -0.7874 0.4064)
			(stroke
				(width 0.1524)
				(type default)
			)
			(layer "F.SilkS")
		)
		(fp_line
			(start 0.7874 -0.4064)
			(end 0.7874 0.4064)
			(stroke
				(width 0.1524)
				(type default)
			)
			(layer "F.SilkS")
		)
		(fp_line
			(start -0.7874 0.4064)
			(end -0.7874 -0.4064)
			(stroke
				(width 0.1524)
				(type default)
			)
			(layer "F.SilkS")
		)
		(fp_line
			(start -0.7874 -0.4064)
			(end 0.7874 -0.4064)
			(stroke
				(width 0.1524)
				(type default)
			)
			(layer "F.SilkS")
		)
		(fp_poly
			(pts
				(xy -0.508 0.2794) (xy -0.508 0.2286) (xy -0.635 0.2286) (xy -0.635 -0.254) (xy -0.5334 -0.254)
				(xy -0.5334 -0.2794) (xy 0.5334 -0.2794) (xy 0.5334 -0.254) (xy 0.635 -0.254) (xy 0.635 0.254) (xy 0.5334 0.254)
				(xy 0.5334 0.2794)
			)
			(stroke
				(width 0)
				(type default)
			)
			(fill no)
			(layer "F.CrtYd")
		)
		(pad "1" smd rect
			(at 0.40005 0 180)
			(size 0.4572 0.508)
			(layers "F.Cu" "F.Mask" "F.Paste")
			(net "PSU2_REMOTE_R_P")
		)
		(pad "2" smd rect
			(at -0.40005 0 180)
			(size 0.4572 0.508)
			(layers "F.Cu" "F.Mask" "F.Paste")
			(net "P12V")
		)
	)
	(footprint ""
		(layer "F.Cu")
		(at 25.931622 -100.590096)
		(property "Reference" "R67"
			(at -4.080256 -0.075692 0)
			(unlocked yes)
			(layer "F.SilkS")
			(effects
				(font
					(size 0.7874 0.5842)
					(thickness 0.1524)
				)
				(justify left)
			)
		)
		(property "Value" ""
			(at 0 0 0)
			(layer "F.Fab")
			(effects
				(font
					(size 1.27 1.27)
				)
			)
		)
		(duplicate_pad_numbers_are_jumpers no)
		(fp_line
			(start -0.7874 -0.4064)
			(end 0.7874 -0.4064)
			(stroke
				(width 0.1524)
				(type default)
			)
			(layer "F.SilkS")
		)
		(fp_line
			(start -0.7874 0.4064)
			(end -0.7874 -0.4064)
			(stroke
				(width 0.1524)
				(type default)
			)
			(layer "F.SilkS")
		)
		(fp_line
			(start 0.7874 -0.4064)
			(end 0.7874 0.4064)
			(stroke
				(width 0.1524)
				(type default)
			)
			(layer "F.SilkS")
		)
		(fp_line
			(start 0.7874 0.4064)
			(end -0.7874 0.4064)
			(stroke
				(width 0.1524)
				(type default)
			)
			(layer "F.SilkS")
		)
		(fp_poly
			(pts
				(xy -0.508 0.2794) (xy -0.508 0.2286) (xy -0.635 0.2286) (xy -0.635 -0.254) (xy -0.5334 -0.254)
				(xy -0.5334 -0.2794) (xy 0.5334 -0.2794) (xy 0.5334 -0.254) (xy 0.635 -0.254) (xy 0.635 0.254) (xy 0.5334 0.254)
				(xy 0.5334 0.2794)
			)
			(stroke
				(width 0)
				(type default)
			)
			(fill no)
			(layer "F.CrtYd")
		)
		(pad "1" smd rect
			(at 0.40005 0)
			(size 0.4572 0.508)
			(layers "F.Cu" "F.Mask" "F.Paste")
			(net "PSU2_PS_KILL")
		)
		(pad "2" smd rect
			(at -0.40005 0)
			(size 0.4572 0.508)
			(layers "F.Cu" "F.Mask" "F.Paste")
			(net "GND")
		)
	)
	(footprint ""
		(layer "F.Cu")
		(at 73.687178 -263.260078 90)
		(property "Reference" "C47"
			(at -4.374134 0.10795 90)
			(unlocked yes)
			(layer "F.SilkS")
			(effects
				(font
					(size 0.7874 0.5842)
					(thickness 0.1524)
				)
				(justify left)
			)
		)
		(property "Value" ""
			(at 0 0 90)
			(layer "F.Fab")
			(effects
				(font
					(size 1.27 1.27)
				)
			)
		)
		(duplicate_pad_numbers_are_jumpers no)
		(fp_line
			(start 0.7874 -0.4064)
			(end 0.7874 0.4064)
			(stroke
				(width 0.1524)
				(type default)
			)
			(layer "F.SilkS")
		)
		(fp_line
			(start -0.7874 -0.4064)
			(end 0.7874 -0.4064)
			(stroke
				(width 0.1524)
				(type default)
			)
			(layer "F.SilkS")
		)
		(fp_line
			(start 0 0.381)
			(end 0 -0.381)
			(stroke
				(width 0.1524)
				(type default)
			)
			(layer "F.SilkS")
		)
		(fp_line
			(start 0.7874 0.4064)
			(end -0.7874 0.4064)
			(stroke
				(width 0.1524)
				(type default)
			)
			(layer "F.SilkS")
		)
		(fp_line
			(start -0.7874 0.4064)
			(end -0.7874 -0.4064)
			(stroke
				(width 0.1524)
				(type default)
			)
			(layer "F.SilkS")
		)
		(fp_poly
			(pts
				(xy -0.5334 0.254) (xy -0.635 0.254) (xy -0.635 0.2286) (xy -0.635 -0.254) (xy -0.5334 -0.254) (xy -0.5334 -0.2794)
				(xy 0.5334 -0.2794) (xy 0.5334 -0.254) (xy 0.635 -0.254) (xy 0.635 0.254) (xy 0.5334 0.254) (xy 0.5334 0.2794)
				(xy -0.508 0.2794) (xy -0.5334 0.2794)
			)
			(stroke
				(width 0)
				(type default)
			)
			(fill no)
			(layer "F.CrtYd")
		)
		(pad "1" smd rect
			(at 0.40005 0 90)
			(size 0.4572 0.508)
			(layers "F.Cu" "F.Mask" "F.Paste")
			(net "P12V")
		)
		(pad "2" smd rect
			(at -0.40005 0 90)
			(size 0.4572 0.508)
			(layers "F.Cu" "F.Mask" "F.Paste")
			(net "GND")
		)
	)
	(footprint ""
		(layer "F.Cu")
		(at 72.590152 -220.425772 90)
		(property "Reference" "C39"
			(at -3.945636 0.03175 90)
			(unlocked yes)
			(layer "F.SilkS")
			(effects
				(font
					(size 0.7874 0.5842)
					(thickness 0.1524)
				)
				(justify left)
			)
		)
		(property "Value" ""
			(at 0 0 90)
			(layer "F.Fab")
			(effects
				(font
					(size 1.27 1.27)
				)
			)
		)
		(duplicate_pad_numbers_are_jumpers no)
		(fp_line
			(start 0.7874 -0.4064)
			(end 0.7874 0.4064)
			(stroke
				(width 0.1524)
				(type default)
			)
			(layer "F.SilkS")
		)
		(fp_line
			(start -0.7874 -0.4064)
			(end 0.7874 -0.4064)
			(stroke
				(width 0.1524)
				(type default)
			)
			(layer "F.SilkS")
		)
		(fp_line
			(start 0 0.381)
			(end 0 -0.381)
			(stroke
				(width 0.1524)
				(type default)
			)
			(layer "F.SilkS")
		)
		(fp_line
			(start 0.7874 0.4064)
			(end -0.7874 0.4064)
			(stroke
				(width 0.1524)
				(type default)
			)
			(layer "F.SilkS")
		)
		(fp_line
			(start -0.7874 0.4064)
			(end -0.7874 -0.4064)
			(stroke
				(width 0.1524)
				(type default)
			)
			(layer "F.SilkS")
		)
		(fp_poly
			(pts
				(xy -0.5334 0.254) (xy -0.635 0.254) (xy -0.635 0.2286) (xy -0.635 -0.254) (xy -0.5334 -0.254) (xy -0.5334 -0.2794)
				(xy 0.5334 -0.2794) (xy 0.5334 -0.254) (xy 0.635 -0.254) (xy 0.635 0.254) (xy 0.5334 0.254) (xy 0.5334 0.2794)
				(xy -0.508 0.2794) (xy -0.5334 0.2794)
			)
			(stroke
				(width 0)
				(type default)
			)
			(fill no)
			(layer "F.CrtYd")
		)
		(pad "1" smd rect
			(at 0.40005 0 90)
			(size 0.4572 0.508)
			(layers "F.Cu" "F.Mask" "F.Paste")
			(net "P12V")
		)
		(pad "2" smd rect
			(at -0.40005 0 90)
			(size 0.4572 0.508)
			(layers "F.Cu" "F.Mask" "F.Paste")
			(net "GND")
		)
	)
	(footprint ""
		(layer "F.Cu")
		(at 79.898748 -504.572778 -90)
		(property "Reference" "C78"
			(at -3.551682 0.005842 90)
			(unlocked yes)
			(layer "F.SilkS")
			(effects
				(font
					(size 0.7874 0.5842)
					(thickness 0.1524)
				)
			)
		)
		(property "Value" ""
			(at 0 0 270)
			(layer "F.Fab")
			(effects
				(font
					(size 1.27 1.27)
				)
			)
		)
		(duplicate_pad_numbers_are_jumpers no)
		(fp_line
			(start -1.2954 0.5842)
			(end -1.2954 -0.5842)
			(stroke
				(width 0.1524)
				(type default)
			)
			(layer "F.SilkS")
		)
		(fp_line
			(start 1.2954 0.5842)
			(end -1.2954 0.5842)
			(stroke
				(width 0.1524)
				(type default)
			)
			(layer "F.SilkS")
		)
		(fp_line
			(start -1.2954 -0.5842)
			(end 1.2954 -0.5842)
			(stroke
				(width 0.1524)
				(type default)
			)
			(layer "F.SilkS")
		)
		(fp_line
			(start 0 -0.5842)
			(end 0 0.5842)
			(stroke
				(width 0.1524)
				(type default)
			)
			(layer "F.SilkS")
		)
		(fp_line
			(start 1.2954 -0.5842)
			(end 1.2954 0.5842)
			(stroke
				(width 0.1524)
				(type default)
			)
			(layer "F.SilkS")
		)
		(fp_poly
			(pts
				(xy 0.8636 -0.4572) (xy 0.8636 -0.3556) (xy 1.143 -0.3556) (xy 1.143 0.3556) (xy 0.8636 0.3556)
				(xy 0.8636 0.4572) (xy -0.8636 0.4572) (xy -0.8636 0.3556) (xy -1.143 0.3556) (xy -1.143 -0.3556)
				(xy -0.8636 -0.3556) (xy -0.8636 -0.4572)
			)
			(stroke
				(width 0)
				(type default)
			)
			(fill no)
			(layer "F.CrtYd")
		)
		(fp_line
			(start -0.884936 0.504952)
			(end -0.884936 -0.504952)
			(stroke
				(width 0.1)
				(type default)
			)
			(layer "F.Fab")
		)
		(fp_line
			(start 0.884936 0.504952)
			(end -0.884936 0.504952)
			(stroke
				(width 0.1)
				(type default)
			)
			(layer "F.Fab")
		)
		(fp_line
			(start -0.884936 -0.504952)
			(end 0.884936 -0.504952)
			(stroke
				(width 0.1)
				(type default)
			)
			(layer "F.Fab")
		)
		(fp_line
			(start 0.884936 -0.504952)
			(end 0.884936 0.504952)
			(stroke
				(width 0.1)
				(type default)
			)
			(layer "F.Fab")
		)
		(pad "1" smd rect
			(at 0.7366 0)
			(size 0.7112 0.8128)
			(layers "F.Cu" "F.Mask" "F.Paste")
			(net "P12V")
		)
		(pad "2" smd rect
			(at -0.7366 0)
			(size 0.7112 0.8128)
			(layers "F.Cu" "F.Mask" "F.Paste")
			(net "GND")
		)
	)
	(footprint ""
		(layer "F.Cu")
		(at 70.85457 -175.945546 90)
		(property "Reference" "C33"
			(at -4.154424 0.196088 90)
			(unlocked yes)
			(layer "F.SilkS")
			(effects
				(font
					(size 0.7874 0.5842)
					(thickness 0.1524)
				)
				(justify left)
			)
		)
		(property "Value" ""
			(at 0 0 90)
			(layer "F.Fab")
			(effects
				(font
					(size 1.27 1.27)
				)
			)
		)
		(duplicate_pad_numbers_are_jumpers no)
		(fp_line
			(start 0.7874 -0.4064)
			(end 0.7874 0.4064)
			(stroke
				(width 0.1524)
				(type default)
			)
			(layer "F.SilkS")
		)
		(fp_line
			(start -0.7874 -0.4064)
			(end 0.7874 -0.4064)
			(stroke
				(width 0.1524)
				(type default)
			)
			(layer "F.SilkS")
		)
		(fp_line
			(start 0 0.381)
			(end 0 -0.381)
			(stroke
				(width 0.1524)
				(type default)
			)
			(layer "F.SilkS")
		)
		(fp_line
			(start 0.7874 0.4064)
			(end -0.7874 0.4064)
			(stroke
				(width 0.1524)
				(type default)
			)
			(layer "F.SilkS")
		)
		(fp_line
			(start -0.7874 0.4064)
			(end -0.7874 -0.4064)
			(stroke
				(width 0.1524)
				(type default)
			)
			(layer "F.SilkS")
		)
		(fp_poly
			(pts
				(xy -0.5334 0.254) (xy -0.635 0.254) (xy -0.635 0.2286) (xy -0.635 -0.254) (xy -0.5334 -0.254) (xy -0.5334 -0.2794)
				(xy 0.5334 -0.2794) (xy 0.5334 -0.254) (xy 0.635 -0.254) (xy 0.635 0.254) (xy 0.5334 0.254) (xy 0.5334 0.2794)
				(xy -0.508 0.2794) (xy -0.5334 0.2794)
			)
			(stroke
				(width 0)
				(type default)
			)
			(fill no)
			(layer "F.CrtYd")
		)
		(pad "1" smd rect
			(at 0.40005 0 90)
			(size 0.4572 0.508)
			(layers "F.Cu" "F.Mask" "F.Paste")
			(net "P12V")
		)
		(pad "2" smd rect
			(at -0.40005 0 90)
			(size 0.4572 0.508)
			(layers "F.Cu" "F.Mask" "F.Paste")
			(net "GND")
		)
	)
	(footprint ""
		(layer "F.Cu")
		(at 25.997662 -9.509252)
		(property "Reference" "R63"
			(at -3.764788 0.113792 0)
			(unlocked yes)
			(layer "F.SilkS")
			(effects
				(font
					(size 0.7874 0.5842)
					(thickness 0.1524)
				)
				(justify left)
			)
		)
		(property "Value" ""
			(at 0 0 0)
			(layer "F.Fab")
			(effects
				(font
					(size 1.27 1.27)
				)
			)
		)
		(duplicate_pad_numbers_are_jumpers no)
		(fp_line
			(start -0.7874 -0.4064)
			(end 0.7874 -0.4064)
			(stroke
				(width 0.1524)
				(type default)
			)
			(layer "F.SilkS")
		)
		(fp_line
			(start -0.7874 0.4064)
			(end -0.7874 -0.4064)
			(stroke
				(width 0.1524)
				(type default)
			)
			(layer "F.SilkS")
		)
		(fp_line
			(start 0.7874 -0.4064)
			(end 0.7874 0.4064)
			(stroke
				(width 0.1524)
				(type default)
			)
			(layer "F.SilkS")
		)
		(fp_line
			(start 0.7874 0.4064)
			(end -0.7874 0.4064)
			(stroke
				(width 0.1524)
				(type default)
			)
			(layer "F.SilkS")
		)
		(fp_poly
			(pts
				(xy -0.508 0.2794) (xy -0.508 0.2286) (xy -0.635 0.2286) (xy -0.635 -0.254) (xy -0.5334 -0.254)
				(xy -0.5334 -0.2794) (xy 0.5334 -0.2794) (xy 0.5334 -0.254) (xy 0.635 -0.254) (xy 0.635 0.254) (xy 0.5334 0.254)
				(xy 0.5334 0.2794)
			)
			(stroke
				(width 0)
				(type default)
			)
			(fill no)
			(layer "F.CrtYd")
		)
		(pad "1" smd rect
			(at 0.40005 0)
			(size 0.4572 0.508)
			(layers "F.Cu" "F.Mask" "F.Paste")
			(net "PSU1_PS_KILL")
		)
		(pad "2" smd rect
			(at -0.40005 0)
			(size 0.4572 0.508)
			(layers "F.Cu" "F.Mask" "F.Paste")
			(net "GND")
		)
	)
	(footprint ""
		(layer "F.Cu")
		(at 74.626978 -307.819806 90)
		(property "Reference" "C53"
			(at -1.302004 5.422138 90)
			(unlocked yes)
			(layer "F.SilkS")
			(effects
				(font
					(size 0.7874 0.5842)
					(thickness 0.1524)
				)
				(justify left)
			)
		)
		(property "Value" ""
			(at 0 0 90)
			(layer "F.Fab")
			(effects
				(font
					(size 1.27 1.27)
				)
			)
		)
		(duplicate_pad_numbers_are_jumpers no)
		(fp_line
			(start 0.7874 -0.4064)
			(end 0.7874 0.4064)
			(stroke
				(width 0.1524)
				(type default)
			)
			(layer "F.SilkS")
		)
		(fp_line
			(start -0.7874 -0.4064)
			(end 0.7874 -0.4064)
			(stroke
				(width 0.1524)
				(type default)
			)
			(layer "F.SilkS")
		)
		(fp_line
			(start 0 0.381)
			(end 0 -0.381)
			(stroke
				(width 0.1524)
				(type default)
			)
			(layer "F.SilkS")
		)
		(fp_line
			(start 0.7874 0.4064)
			(end -0.7874 0.4064)
			(stroke
				(width 0.1524)
				(type default)
			)
			(layer "F.SilkS")
		)
		(fp_line
			(start -0.7874 0.4064)
			(end -0.7874 -0.4064)
			(stroke
				(width 0.1524)
				(type default)
			)
			(layer "F.SilkS")
		)
		(fp_poly
			(pts
				(xy -0.5334 0.254) (xy -0.635 0.254) (xy -0.635 0.2286) (xy -0.635 -0.254) (xy -0.5334 -0.254) (xy -0.5334 -0.2794)
				(xy 0.5334 -0.2794) (xy 0.5334 -0.254) (xy 0.635 -0.254) (xy 0.635 0.254) (xy 0.5334 0.254) (xy 0.5334 0.2794)
				(xy -0.508 0.2794) (xy -0.5334 0.2794)
			)
			(stroke
				(width 0)
				(type default)
			)
			(fill no)
			(layer "F.CrtYd")
		)
		(pad "1" smd rect
			(at 0.40005 0 90)
			(size 0.4572 0.508)
			(layers "F.Cu" "F.Mask" "F.Paste")
			(net "P12V")
		)
		(pad "2" smd rect
			(at -0.40005 0 90)
			(size 0.4572 0.508)
			(layers "F.Cu" "F.Mask" "F.Paste")
			(net "GND")
		)
	)
	(footprint ""
		(layer "F.Cu")
		(at 27.29357 -280.04389)
		(property "Reference" "R137"
			(at -3.851402 0.175768 0)
			(unlocked yes)
			(layer "F.SilkS")
			(effects
				(font
					(size 0.7874 0.5842)
					(thickness 0.1524)
				)
				(justify left)
			)
		)
		(property "Value" ""
			(at 0 0 0)
			(layer "F.Fab")
			(effects
				(font
					(size 1.27 1.27)
				)
			)
		)
		(duplicate_pad_numbers_are_jumpers no)
		(fp_line
			(start -0.7874 -0.4064)
			(end 0.7874 -0.4064)
			(stroke
				(width 0.1524)
				(type default)
			)
			(layer "F.SilkS")
		)
		(fp_line
			(start -0.7874 0.4064)
			(end -0.7874 -0.4064)
			(stroke
				(width 0.1524)
				(type default)
			)
			(layer "F.SilkS")
		)
		(fp_line
			(start 0.7874 -0.4064)
			(end 0.7874 0.4064)
			(stroke
				(width 0.1524)
				(type default)
			)
			(layer "F.SilkS")
		)
		(fp_line
			(start 0.7874 0.4064)
			(end -0.7874 0.4064)
			(stroke
				(width 0.1524)
				(type default)
			)
			(layer "F.SilkS")
		)
		(fp_poly
			(pts
				(xy -0.508 0.2794) (xy -0.508 0.2286) (xy -0.635 0.2286) (xy -0.635 -0.254) (xy -0.5334 -0.254)
				(xy -0.5334 -0.2794) (xy 0.5334 -0.2794) (xy 0.5334 -0.254) (xy 0.635 -0.254) (xy 0.635 0.254) (xy 0.5334 0.254)
				(xy 0.5334 0.2794)
			)
			(stroke
				(width 0)
				(type default)
			)
			(fill no)
			(layer "F.CrtYd")
		)
		(pad "1" smd rect
			(at 0.40005 0)
			(size 0.4572 0.508)
			(layers "F.Cu" "F.Mask" "F.Paste")
			(net "PSU4_CSAHRE")
		)
		(pad "2" smd rect
			(at -0.40005 0)
			(size 0.4572 0.508)
			(layers "F.Cu" "F.Mask" "F.Paste")
			(net "PSU_CSAHRE")
		)
	)
	(footprint ""
		(layer "F.Cu")
		(at 26.226008 -448.493388)
		(property "Reference" "R85"
			(at -3.597402 -0.121666 0)
			(unlocked yes)
			(layer "F.SilkS")
			(effects
				(font
					(size 0.7874 0.5842)
					(thickness 0.1524)
				)
				(justify left)
			)
		)
		(property "Value" ""
			(at 0 0 0)
			(layer "F.Fab")
			(effects
				(font
					(size 1.27 1.27)
				)
			)
		)
		(duplicate_pad_numbers_are_jumpers no)
		(fp_line
			(start -0.7874 -0.4064)
			(end 0.7874 -0.4064)
			(stroke
				(width 0.1524)
				(type default)
			)
			(layer "F.SilkS")
		)
		(fp_line
			(start -0.7874 0.4064)
			(end -0.7874 -0.4064)
			(stroke
				(width 0.1524)
				(type default)
			)
			(layer "F.SilkS")
		)
		(fp_line
			(start 0.7874 -0.4064)
			(end 0.7874 0.4064)
			(stroke
				(width 0.1524)
				(type default)
			)
			(layer "F.SilkS")
		)
		(fp_line
			(start 0.7874 0.4064)
			(end -0.7874 0.4064)
			(stroke
				(width 0.1524)
				(type default)
			)
			(layer "F.SilkS")
		)
		(fp_poly
			(pts
				(xy -0.508 0.2794) (xy -0.508 0.2286) (xy -0.635 0.2286) (xy -0.635 -0.254) (xy -0.5334 -0.254)
				(xy -0.5334 -0.2794) (xy 0.5334 -0.2794) (xy 0.5334 -0.254) (xy 0.635 -0.254) (xy 0.635 0.254) (xy 0.5334 0.254)
				(xy 0.5334 0.2794)
			)
			(stroke
				(width 0)
				(type default)
			)
			(fill no)
			(layer "F.CrtYd")
		)
		(pad "1" smd rect
			(at 0.40005 0)
			(size 0.4572 0.508)
			(layers "F.Cu" "F.Mask" "F.Paste")
			(net "PSU6_RESET")
		)
		(pad "2" smd rect
			(at -0.40005 0)
			(size 0.4572 0.508)
			(layers "F.Cu" "F.Mask" "F.Paste")
			(net "GND")
		)
	)
	(footprint ""
		(layer "F.Cu")
		(at 50.284126 -395.548358 180)
		(property "Reference" "CE18"
			(at -3.83413 -2.721864 0)
			(unlocked yes)
			(layer "F.SilkS")
			(effects
				(font
					(size 0.7874 0.5842)
					(thickness 0.1524)
				)
				(justify left)
			)
		)
		(property "Value" ""
			(at 0 0 180)
			(layer "F.Fab")
			(effects
				(font
					(size 1.27 1.27)
				)
			)
		)
		(duplicate_pad_numbers_are_jumpers no)
		(fp_line
			(start 0 -4.2672)
			(end 0 4.2672)
			(stroke
				(width 0.1524)
				(type default)
			)
			(layer "F.SilkS")
		)
		(fp_circle
			(center 0 0)
			(end -4.2672 0)
			(stroke
				(width 0.1524)
				(type default)
			)
			(fill no)
			(layer "F.SilkS")
		)
		(fp_poly
			(pts
				(arc
					(start 0 -4.2672)
					(mid 4.2672 0)
					(end 0 4.2672)
				)
			)
			(stroke
				(width 0)
				(type default)
			)
			(fill yes)
			(layer "F.SilkS")
		)
		(fp_poly
			(pts
				(xy -2.5146 -0.762) (xy -0.9906 -0.762) (xy -0.9906 0.762) (xy -2.5146 0.762)
			)
			(stroke
				(width 0)
				(type default)
			)
			(fill no)
			(layer "B.CrtYd")
		)
		(fp_poly
			(pts
				(arc
					(start 1.7526 0.762)
					(mid 2.291415 -0.538815)
					(end 0.9906 0)
				)
				(arc
					(start 0.9906 0.0254)
					(mid 1.206345 0.546255)
					(end 1.7272 0.762)
				)
			)
			(stroke
				(width 0)
				(type default)
			)
			(fill no)
			(layer "B.CrtYd")
		)
		(fp_poly
			(pts
				(arc
					(start -4.2672 0)
					(mid 4.2672 0)
					(end -4.2672 0)
				)
			)
			(stroke
				(width 0)
				(type default)
			)
			(fill no)
			(layer "F.CrtYd")
		)
		(fp_circle
			(center 0 0)
			(end -4.2672 0)
			(stroke
				(width 0.1)
				(type default)
			)
			(fill no)
			(layer "F.Fab")
		)
		(fp_text user "+"
			(at -4.934204 -1.625854 180)
			(unlocked yes)
			(layer "F.SilkS")
			(effects
				(font
					(size 0.7874 0.5842)
					(thickness 0.1524)
				)
				(justify left)
			)
		)
		(fp_text user "+"
			(at -5.6642 -0.34925 180)
			(unlocked yes)
			(layer "F.Fab")
			(effects
				(font
					(size 1.905 1.4224)
					(thickness 0.000001)
				)
				(justify left)
			)
		)
		(pad "1" thru_hole rect
			(at -1.75006 0 180)
			(size 1.397 1.397)
			(drill 0.9144)
			(layers "*.Cu" "*.Mask")
			(remove_unused_layers no)
			(net "P12V")
			(clearance 0.0127)
			(thermal_gap 0.0127)
			(padstack
				(mode front_inner_back)
				(layer "Inner"
					(shape circle)
					(size 1.397 1.397)
					(clearance 0.0127)
				)
				(layer "B.Cu"
					(shape rect)
					(size 1.397 1.397)
					(clearance 0.0127)
				)
			)
		)
		(pad "2" thru_hole circle
			(at 1.75006 0 180)
			(size 1.397 1.397)
			(drill 0.9144)
			(layers "*.Cu" "*.Mask")
			(remove_unused_layers no)
			(net "GND")
			(clearance 0.0127)
			(thermal_gap 0.0127)
		)
	)
	(footprint ""
		(layer "F.Cu")
		(at 16.348964 -336.728562)
		(property "Reference" "U1"
			(at 3.592322 0.869696 90)
			(unlocked yes)
			(layer "F.SilkS")
			(effects
				(font
					(size 0.7874 0.5842)
					(thickness 0.1524)
				)
				(justify left)
			)
		)
		(property "Value" ""
			(at 0 0 0)
			(layer "F.Fab")
			(effects
				(font
					(size 1.27 1.27)
				)
			)
		)
		(duplicate_pad_numbers_are_jumpers no)
		(fp_line
			(start -2.5146 -1.4224)
			(end 2.5146 -1.4224)
			(stroke
				(width 0.1524)
				(type default)
			)
			(layer "F.SilkS")
		)
		(fp_line
			(start -2.5146 -0.4572)
			(end -2.5146 -1.4224)
			(stroke
				(width 0.1524)
				(type default)
			)
			(layer "F.SilkS")
		)
		(fp_line
			(start -2.5146 0.4572)
			(end -2.0574 0)
			(stroke
				(width 0.1524)
				(type default)
			)
			(layer "F.SilkS")
		)
		(fp_line
			(start -2.5146 1.4224)
			(end -2.5146 0.4572)
			(stroke
				(width 0.1524)
				(type default)
			)
			(layer "F.SilkS")
		)
		(fp_line
			(start -2.0574 0)
			(end -2.5146 -0.4572)
			(stroke
				(width 0.1524)
				(type default)
			)
			(layer "F.SilkS")
		)
		(fp_line
			(start 2.5146 -1.4224)
			(end 2.5146 1.4224)
			(stroke
				(width 0.1524)
				(type default)
			)
			(layer "F.SilkS")
		)
		(fp_line
			(start 2.5146 1.4224)
			(end -2.5146 1.4224)
			(stroke
				(width 0.1524)
				(type default)
			)
			(layer "F.SilkS")
		)
		(fp_circle
			(center -1.905 0.889)
			(end -1.651 0.889)
			(stroke
				(width 0.1524)
				(type default)
			)
			(fill no)
			(layer "F.SilkS")
		)
		(fp_poly
			(pts
				(xy -2.1844 3.5052) (xy -2.1844 2.0066) (xy -2.5146 2.0066) (xy -2.5146 -2.0066) (xy -2.1844 -2.0066)
				(xy -2.1844 -3.5052) (xy 2.1844 -3.5052) (xy 2.1844 -2.0066) (xy 2.5146 -2.0066) (xy 2.5146 2.0066)
				(xy 2.1844 2.0066) (xy 2.1844 3.5052)
			)
			(stroke
				(width 0)
				(type default)
			)
			(fill no)
			(layer "F.CrtYd")
		)
		(pad "1" smd rect
			(at -1.905 2.6416)
			(size 0.5588 1.7272)
			(layers "F.Cu" "F.Mask" "F.Paste")
			(net "FRU_A0")
		)
		(pad "2" smd rect
			(at -0.635 2.6416)
			(size 0.5588 1.7272)
			(layers "F.Cu" "F.Mask" "F.Paste")
			(net "FRU_A1")
		)
		(pad "3" smd rect
			(at 0.635 2.6416)
			(size 0.5588 1.7272)
			(layers "F.Cu" "F.Mask" "F.Paste")
			(net "FRU_A2")
		)
		(pad "4" smd rect
			(at 1.905 2.6416)
			(size 0.5588 1.7272)
			(layers "F.Cu" "F.Mask" "F.Paste")
			(net "GND")
		)
		(pad "5" smd rect
			(at 1.905 -2.6416)
			(size 0.5588 1.7272)
			(layers "F.Cu" "F.Mask" "F.Paste")
			(net "I2C_PDB_SDA")
		)
		(pad "6" smd rect
			(at 0.635 -2.6416)
			(size 0.5588 1.7272)
			(layers "F.Cu" "F.Mask" "F.Paste")
			(net "I2C_PDB_SCL")
		)
		(pad "7" smd rect
			(at -0.635 -2.6416)
			(size 0.5588 1.7272)
			(layers "F.Cu" "F.Mask" "F.Paste")
			(net "FRU_WP")
		)
		(pad "8" smd rect
			(at -1.905 -2.6416)
			(size 0.5588 1.7272)
			(layers "F.Cu" "F.Mask" "F.Paste")
			(net "P3V3")
		)
	)
	(footprint ""
		(layer "F.Cu")
		(at 26.102056 -277.377144)
		(property "Reference" "R56"
			(at -4.060444 0.200152 0)
			(unlocked yes)
			(layer "F.SilkS")
			(effects
				(font
					(size 0.7874 0.5842)
					(thickness 0.1524)
				)
				(justify left)
			)
		)
		(property "Value" ""
			(at 0 0 0)
			(layer "F.Fab")
			(effects
				(font
					(size 1.27 1.27)
				)
			)
		)
		(duplicate_pad_numbers_are_jumpers no)
		(fp_line
			(start -0.7874 -0.4064)
			(end 0.7874 -0.4064)
			(stroke
				(width 0.1524)
				(type default)
			)
			(layer "F.SilkS")
		)
		(fp_line
			(start -0.7874 0.4064)
			(end -0.7874 -0.4064)
			(stroke
				(width 0.1524)
				(type default)
			)
			(layer "F.SilkS")
		)
		(fp_line
			(start 0.7874 -0.4064)
			(end 0.7874 0.4064)
			(stroke
				(width 0.1524)
				(type default)
			)
			(layer "F.SilkS")
		)
		(fp_line
			(start 0.7874 0.4064)
			(end -0.7874 0.4064)
			(stroke
				(width 0.1524)
				(type default)
			)
			(layer "F.SilkS")
		)
		(fp_poly
			(pts
				(xy -0.508 0.2794) (xy -0.508 0.2286) (xy -0.635 0.2286) (xy -0.635 -0.254) (xy -0.5334 -0.254)
				(xy -0.5334 -0.2794) (xy 0.5334 -0.2794) (xy 0.5334 -0.254) (xy 0.635 -0.254) (xy 0.635 0.254) (xy 0.5334 0.254)
				(xy 0.5334 0.2794)
			)
			(stroke
				(width 0)
				(type default)
			)
			(fill no)
			(layer "F.CrtYd")
		)
		(pad "1" smd rect
			(at 0.40005 0)
			(size 0.4572 0.508)
			(layers "F.Cu" "F.Mask" "F.Paste")
			(net "PSU4_PS_KILL")
		)
		(pad "2" smd rect
			(at -0.40005 0)
			(size 0.4572 0.508)
			(layers "F.Cu" "F.Mask" "F.Paste")
			(net "GND")
		)
	)
	(footprint ""
		(layer "F.Cu")
		(at 73.45934 -326.522588 -90)
		(property "Reference" "C51"
			(at -2.752344 0.042418 90)
			(unlocked yes)
			(layer "F.SilkS")
			(effects
				(font
					(size 0.7874 0.5842)
					(thickness 0.1524)
				)
				(justify left)
			)
		)
		(property "Value" ""
			(at 0 0 270)
			(layer "F.Fab")
			(effects
				(font
					(size 1.27 1.27)
				)
			)
		)
		(duplicate_pad_numbers_are_jumpers no)
		(fp_line
			(start -0.7874 0.4064)
			(end -0.7874 -0.4064)
			(stroke
				(width 0.1524)
				(type default)
			)
			(layer "F.SilkS")
		)
		(fp_line
			(start 0.7874 0.4064)
			(end -0.7874 0.4064)
			(stroke
				(width 0.1524)
				(type default)
			)
			(layer "F.SilkS")
		)
		(fp_line
			(start 0 0.381)
			(end 0 -0.381)
			(stroke
				(width 0.1524)
				(type default)
			)
			(layer "F.SilkS")
		)
		(fp_line
			(start -0.7874 -0.4064)
			(end 0.7874 -0.4064)
			(stroke
				(width 0.1524)
				(type default)
			)
			(layer "F.SilkS")
		)
		(fp_line
			(start 0.7874 -0.4064)
			(end 0.7874 0.4064)
			(stroke
				(width 0.1524)
				(type default)
			)
			(layer "F.SilkS")
		)
		(fp_poly
			(pts
				(xy -0.5334 0.254) (xy -0.635 0.254) (xy -0.635 0.2286) (xy -0.635 -0.254) (xy -0.5334 -0.254) (xy -0.5334 -0.2794)
				(xy 0.5334 -0.2794) (xy 0.5334 -0.254) (xy 0.635 -0.254) (xy 0.635 0.254) (xy 0.5334 0.254) (xy 0.5334 0.2794)
				(xy -0.508 0.2794) (xy -0.5334 0.2794)
			)
			(stroke
				(width 0)
				(type default)
			)
			(fill no)
			(layer "F.CrtYd")
		)
		(pad "1" smd rect
			(at 0.40005 0 270)
			(size 0.4572 0.508)
			(layers "F.Cu" "F.Mask" "F.Paste")
			(net "P12V")
		)
		(pad "2" smd rect
			(at -0.40005 0 270)
			(size 0.4572 0.508)
			(layers "F.Cu" "F.Mask" "F.Paste")
			(net "GND")
		)
	)
	(footprint ""
		(layer "F.Cu")
		(at 39.94531 -459.16596 180)
		(property "Reference" "R26"
			(at -1.790446 -0.167386 0)
			(unlocked yes)
			(layer "F.SilkS")
			(effects
				(font
					(size 0.7874 0.5842)
					(thickness 0.1524)
				)
				(justify left)
			)
		)
		(property "Value" ""
			(at 0 0 180)
			(layer "F.Fab")
			(effects
				(font
					(size 1.27 1.27)
				)
			)
		)
		(duplicate_pad_numbers_are_jumpers no)
		(fp_line
			(start 0.7874 0.4064)
			(end -0.7874 0.4064)
			(stroke
				(width 0.1524)
				(type default)
			)
			(layer "F.SilkS")
		)
		(fp_line
			(start 0.7874 -0.4064)
			(end 0.7874 0.4064)
			(stroke
				(width 0.1524)
				(type default)
			)
			(layer "F.SilkS")
		)
		(fp_line
			(start -0.7874 0.4064)
			(end -0.7874 -0.4064)
			(stroke
				(width 0.1524)
				(type default)
			)
			(layer "F.SilkS")
		)
		(fp_line
			(start -0.7874 -0.4064)
			(end 0.7874 -0.4064)
			(stroke
				(width 0.1524)
				(type default)
			)
			(layer "F.SilkS")
		)
		(fp_poly
			(pts
				(xy -0.508 0.2794) (xy -0.508 0.2286) (xy -0.635 0.2286) (xy -0.635 -0.254) (xy -0.5334 -0.254)
				(xy -0.5334 -0.2794) (xy 0.5334 -0.2794) (xy 0.5334 -0.254) (xy 0.635 -0.254) (xy 0.635 0.254) (xy 0.5334 0.254)
				(xy 0.5334 0.2794)
			)
			(stroke
				(width 0)
				(type default)
			)
			(fill no)
			(layer "F.CrtYd")
		)
		(pad "1" smd rect
			(at 0.40005 0 180)
			(size 0.4572 0.508)
			(layers "F.Cu" "F.Mask" "F.Paste")
			(net "PSU6_RETURN")
		)
		(pad "2" smd rect
			(at -0.40005 0 180)
			(size 0.4572 0.508)
			(layers "F.Cu" "F.Mask" "F.Paste")
			(net "GND")
		)
	)
	(footprint ""
		(layer "F.Cu")
		(at 13.71473 -131.750054 180)
		(property "Reference" "J29"
			(at -5.524754 4.01066 0)
			(unlocked yes)
			(layer "F.SilkS")
			(effects
				(font
					(size 0.7874 0.5842)
					(thickness 0.1524)
				)
				(justify left)
			)
		)
		(property "Value" ""
			(at 0 0 180)
			(layer "F.Fab")
			(effects
				(font
					(size 1.27 1.27)
				)
			)
		)
		(duplicate_pad_numbers_are_jumpers no)
		(fp_line
			(start 12.644882 12.899898)
			(end -3.754882 12.899898)
			(stroke
				(width 0.1524)
				(type default)
			)
			(layer "F.SilkS")
		)
		(fp_line
			(start 12.644882 3.7846)
			(end 12.644882 12.899898)
			(stroke
				(width 0.1524)
				(type default)
			)
			(layer "F.SilkS")
		)
		(fp_line
			(start 12.644882 -3.800094)
			(end 12.644882 1.2192)
			(stroke
				(width 0.1524)
				(type default)
			)
			(layer "F.SilkS")
		)
		(fp_line
			(start -3.754882 12.899898)
			(end -3.754882 3.7846)
			(stroke
				(width 0.1524)
				(type default)
			)
			(layer "F.SilkS")
		)
		(fp_line
			(start -3.754882 1.2192)
			(end -3.754882 -3.800094)
			(stroke
				(width 0.1524)
				(type default)
			)
			(layer "F.SilkS")
		)
		(fp_line
			(start -3.754882 -3.800094)
			(end 12.644882 -3.800094)
			(stroke
				(width 0.1524)
				(type default)
			)
			(layer "F.SilkS")
		)
		(fp_poly
			(pts
				(xy -4.125214 0) (xy -5.806186 0.840486) (xy -5.806186 -0.840486)
			)
			(stroke
				(width 0)
				(type default)
			)
			(fill yes)
			(layer "F.SilkS")
		)
		(fp_poly
			(pts
				(xy 7.5184 11.176) (xy 11.4808 11.176) (xy 11.4808 9.7282) (xy 7.5184 9.7282)
			)
			(stroke
				(width 0)
				(type default)
			)
			(fill no)
			(layer "B.CrtYd")
		)
		(fp_poly
			(pts
				(xy -2.591562 11.176) (xy 1.370838 11.176) (xy 1.370838 9.7282) (xy -2.591562 9.7282)
			)
			(stroke
				(width 0)
				(type default)
			)
			(fill no)
			(layer "B.CrtYd")
		)
		(fp_poly
			(pts
				(xy 9.627362 -3.256026) (xy 9.627362 -1.808226) (xy 8.357362 -1.808226) (xy 8.357362 0.731774) (xy -0.735838 0.731774)
				(xy -0.735838 -0.741426) (xy 0.534162 -0.741426) (xy 0.534162 -3.256026)
			)
			(stroke
				(width 0)
				(type default)
			)
			(fill no)
			(layer "B.CrtYd")
		)
		(fp_poly
			(pts
				(arc
					(start 11.088116 2.500122)
					(mid 13.551916 2.500122)
					(end 11.088116 2.500122)
				)
			)
			(stroke
				(width 0)
				(type default)
			)
			(fill no)
			(layer "B.CrtYd")
		)
		(fp_poly
			(pts
				(arc
					(start -4.661916 2.500122)
					(mid -2.198116 2.500122)
					(end -4.661916 2.500122)
				)
			)
			(stroke
				(width 0)
				(type default)
			)
			(fill no)
			(layer "B.CrtYd")
		)
		(fp_poly
			(pts
				(arc
					(start 8.3058 6.35)
					(mid 12.0142 6.35)
					(end 8.3058 6.35)
				)
			)
			(stroke
				(width 0)
				(type default)
			)
			(fill no)
			(layer "B.CrtYd")
		)
		(fp_poly
			(pts
				(arc
					(start -3.1242 6.35)
					(mid 0.5842 6.35)
					(end -3.1242 6.35)
				)
			)
			(stroke
				(width 0)
				(type default)
			)
			(fill no)
			(layer "B.CrtYd")
		)
		(fp_poly
			(pts
				(xy -3.754882 12.899898)
				(arc
					(start -3.754882 3.688334)
					(mid -4.661838 2.500089)
					(end -3.754882 1.311656)
				)
				(xy -3.754882 -3.800094) (xy 12.644882 -3.800094)
				(arc
					(start 12.644882 1.311656)
					(mid 13.552083 2.500089)
					(end 12.644882 3.688334)
				)
				(xy 12.644882 12.899898)
			)
			(stroke
				(width 0)
				(type default)
			)
			(fill no)
			(layer "F.CrtYd")
		)
		(fp_line
			(start 12.644882 12.899898)
			(end -3.754882 12.899898)
			(stroke
				(width 0.1)
				(type default)
			)
			(layer "F.Fab")
		)
		(fp_line
			(start 12.644882 -3.800094)
			(end 12.644882 12.899898)
			(stroke
				(width 0.1)
				(type default)
			)
			(layer "F.Fab")
		)
		(fp_line
			(start -3.754882 12.899898)
			(end -3.754882 -3.800094)
			(stroke
				(width 0.1)
				(type default)
			)
			(layer "F.Fab")
		)
		(fp_line
			(start -3.754882 -3.800094)
			(end 12.644882 -3.800094)
			(stroke
				(width 0.1)
				(type default)
			)
			(layer "F.Fab")
		)
		(fp_poly
			(pts
				(xy -4.125214 0) (xy -5.806186 0.840486) (xy -5.806186 -0.840486)
			)
			(stroke
				(width 0)
				(type default)
			)
			(fill yes)
			(layer "F.Fab")
		)
		(fp_text user "7"
			(at 13.151866 -0.098806 0)
			(unlocked yes)
			(layer "F.SilkS")
			(effects
				(font
					(size 0.7874 0.5842)
					(thickness 0.1524)
				)
			)
		)
		(fp_text user "8"
			(at 13.051536 -2.872486 0)
			(unlocked yes)
			(layer "F.SilkS")
			(effects
				(font
					(size 0.7874 0.5842)
					(thickness 0.1524)
				)
			)
		)
		(fp_text user "2"
			(at -4.254754 -3.141218 0)
			(unlocked yes)
			(layer "F.SilkS")
			(effects
				(font
					(size 0.7874 0.5842)
					(thickness 0.1524)
				)
			)
		)
		(fp_text user "1"
			(at -4.45516 -0.935482 0)
			(unlocked yes)
			(layer "F.SilkS")
			(effects
				(font
					(size 0.7874 0.5842)
					(thickness 0.1524)
				)
			)
		)
		(fp_text user "8"
			(at 10.255504 -2.572766 0)
			(unlocked yes)
			(layer "B.SilkS")
			(effects
				(font
					(size 0.7874 0.5842)
					(thickness 0.1524)
				)
				(justify mirror)
			)
		)
		(fp_text user "7"
			(at 8.998204 -0.007366 0)
			(unlocked yes)
			(layer "B.SilkS")
			(effects
				(font
					(size 0.7874 0.5842)
					(thickness 0.1524)
				)
				(justify mirror)
			)
		)
		(fp_text user "2"
			(at 0.070104 -2.725166 0)
			(unlocked yes)
			(layer "B.SilkS")
			(effects
				(font
					(size 0.7874 0.5842)
					(thickness 0.1524)
				)
				(justify mirror)
			)
		)
		(fp_text user "1"
			(at -1.047496 -0.147066 0)
			(unlocked yes)
			(layer "B.SilkS")
			(effects
				(font
					(size 0.7874 0.5842)
					(thickness 0.1524)
				)
				(justify mirror)
			)
		)
		(fp_text user "8"
			(at 10.1219 -2.479548 180)
			(unlocked yes)
			(layer "B.Fab")
			(effects
				(font
					(size 0.7874 0.5842)
					(thickness 0.000001)
				)
				(justify mirror)
			)
		)
		(fp_text user "7"
			(at 8.8646 0.085852 180)
			(unlocked yes)
			(layer "B.Fab")
			(effects
				(font
					(size 0.7874 0.5842)
					(thickness 0.000001)
				)
				(justify mirror)
			)
		)
		(fp_text user "2"
			(at -0.0635 -2.631948 180)
			(unlocked yes)
			(layer "B.Fab")
			(effects
				(font
					(size 0.7874 0.5842)
					(thickness 0.000001)
				)
				(justify mirror)
			)
		)
		(fp_text user "1"
			(at -1.1811 -0.053848 180)
			(unlocked yes)
			(layer "B.Fab")
			(effects
				(font
					(size 0.7874 0.5842)
					(thickness 0.000001)
				)
				(justify mirror)
			)
		)
		(fp_text user "8"
			(at 13.2715 -2.593848 180)
			(unlocked yes)
			(layer "F.Fab")
			(effects
				(font
					(size 0.7874 0.5842)
					(thickness 0.000001)
				)
			)
		)
		(fp_text user "7"
			(at 13.2334 -0.079248 180)
			(unlocked yes)
			(layer "F.Fab")
			(effects
				(font
					(size 0.7874 0.5842)
					(thickness 0.000001)
				)
			)
		)
		(fp_text user "1"
			(at -4.4323 -1.019048 180)
			(unlocked yes)
			(layer "F.Fab")
			(effects
				(font
					(size 0.7874 0.5842)
					(thickness 0.000001)
				)
			)
		)
		(fp_text user "2"
			(at -4.4704 -2.581148 180)
			(unlocked yes)
			(layer "F.Fab")
			(effects
				(font
					(size 0.7874 0.5842)
					(thickness 0.000001)
				)
			)
		)
		(pad "" np_thru_hole circle
			(at -1.27 6.35 180)
			(size 3.2004 3.2004)
			(drill 3.2004)
			(layers "*.Cu" "*.Mask")
			(clearance 0.381)
			(thermal_gap 0.381)
		)
		(pad "" np_thru_hole circle
			(at 10.16 6.35 180)
			(size 3.2004 3.2004)
			(drill 3.2004)
			(layers "*.Cu" "*.Mask")
			(clearance 0.381)
			(thermal_gap 0.381)
		)
		(pad "1" thru_hole rect
			(at 0 0 180)
			(size 1.3208 1.3208)
			(drill 0.9144)
			(layers "*.Cu" "*.Mask")
			(remove_unused_layers no)
			(net "LAN1_P1_P")
			(clearance 0.0508)
			(thermal_gap 0.0508)
			(padstack
				(mode front_inner_back)
				(layer "Inner"
					(shape circle)
					(size 1.3208 1.3208)
					(clearance 0.0508)
				)
				(layer "B.Cu"
					(shape rect)
					(size 1.3208 1.3208)
					(clearance 0.0508)
				)
			)
		)
		(pad "2" thru_hole circle
			(at 1.27 -2.54 180)
			(size 1.3208 1.3208)
			(drill 0.9144)
			(layers "*.Cu" "*.Mask")
			(remove_unused_layers no)
			(net "LAN1_P1_N")
			(clearance 0.0508)
			(thermal_gap 0.0508)
		)
		(pad "3" thru_hole circle
			(at 2.54 0 180)
			(size 1.3208 1.3208)
			(drill 0.9144)
			(layers "*.Cu" "*.Mask")
			(remove_unused_layers no)
			(net "LAN1_P2_P")
			(clearance 0.0508)
			(thermal_gap 0.0508)
		)
		(pad "4" thru_hole circle
			(at 3.81 -2.54 180)
			(size 1.3208 1.3208)
			(drill 0.9144)
			(layers "*.Cu" "*.Mask")
			(remove_unused_layers no)
			(net "LAN1_P3_P")
			(clearance 0.0508)
			(thermal_gap 0.0508)
		)
		(pad "5" thru_hole circle
			(at 5.08 0 180)
			(size 1.3208 1.3208)
			(drill 0.9144)
			(layers "*.Cu" "*.Mask")
			(remove_unused_layers no)
			(net "LAN1_P3_N")
			(clearance 0.0508)
			(thermal_gap 0.0508)
		)
		(pad "6" thru_hole circle
			(at 6.35 -2.54 180)
			(size 1.3208 1.3208)
			(drill 0.9144)
			(layers "*.Cu" "*.Mask")
			(remove_unused_layers no)
			(net "LAN1_P2_N")
			(clearance 0.0508)
			(thermal_gap 0.0508)
		)
		(pad "7" thru_hole circle
			(at 7.62 0 180)
			(size 1.3208 1.3208)
			(drill 0.9144)
			(layers "*.Cu" "*.Mask")
			(remove_unused_layers no)
			(net "LAN1_P4_P")
			(clearance 0.0508)
			(thermal_gap 0.0508)
		)
		(pad "8" thru_hole circle
			(at 8.89 -2.54 180)
			(size 1.3208 1.3208)
			(drill 0.9144)
			(layers "*.Cu" "*.Mask")
			(remove_unused_layers no)
			(net "LAN1_P4_N")
			(clearance 0.0508)
			(thermal_gap 0.0508)
		)
		(pad "9" thru_hole circle
			(at -1.854962 10.459974 180)
			(size 1.3208 1.3208)
			(drill 0.9144)
			(layers "*.Cu" "*.Mask")
			(remove_unused_layers no)
			(net "N42126764")
			(clearance 0.0508)
			(thermal_gap 0.0508)
		)
		(pad "10" thru_hole circle
			(at 0.635 10.459974 180)
			(size 1.3208 1.3208)
			(drill 0.9144)
			(layers "*.Cu" "*.Mask")
			(remove_unused_layers no)
			(net "N42126673")
			(clearance 0.0508)
			(thermal_gap 0.0508)
		)
		(pad "11" thru_hole circle
			(at 8.255 10.459974 180)
			(size 1.3208 1.3208)
			(drill 0.9144)
			(layers "*.Cu" "*.Mask")
			(remove_unused_layers no)
			(net "Net_424")
			(clearance 0.0508)
			(thermal_gap 0.0508)
		)
		(pad "12" thru_hole circle
			(at 10.744962 10.459974 180)
			(size 1.3208 1.3208)
			(drill 0.9144)
			(layers "*.Cu" "*.Mask")
			(remove_unused_layers no)
			(net "N42130542")
			(clearance 0.0508)
			(thermal_gap 0.0508)
		)
		(pad "G1" thru_hole circle
			(at -3.430016 2.500122 180)
			(size 2.3622 2.3622)
			(drill 1.6002)
			(layers "*.Cu" "*.Mask")
			(remove_unused_layers no)
			(net "GND")
			(clearance -0.127)
		)
		(pad "G2" thru_hole circle
			(at 12.320016 2.500122 180)
			(size 2.3622 2.3622)
			(drill 1.6002)
			(layers "*.Cu" "*.Mask")
			(remove_unused_layers no)
			(net "GND")
			(clearance -0.127)
		)
		(zone
			(layers "F.Cu" "B.Cu" "In1.Cu" "In2.Cu" "In3.Cu" "In4.Cu" "In5.Cu" "In6.Cu")
			(hatch none 0.5)
			(connect_pads
				(clearance 0)
			)
			(min_thickness 0.25)
			(keepout
				(tracks not_allowed)
				(vias allowed)
				(pads allowed)
				(copperpour not_allowed)
				(footprints allowed)
			)
			(placement
				(enabled no)
				(sheetname "")
			)
			(fill
				(thermal_gap 0.5)
				(thermal_bridge_width 0.5)
				(island_removal_mode 0)
			)
			(polygon
				(pts
					(arc
						(start 5.56133 -138.100054)
						(mid 1.54813 -138.100054)
						(end 5.56133 -138.100054)
					)
				)
			)
		)
		(zone
			(layers "F.Cu" "B.Cu" "In1.Cu" "In2.Cu" "In3.Cu" "In4.Cu" "In5.Cu" "In6.Cu")
			(hatch none 0.5)
			(connect_pads
				(clearance 0)
			)
			(min_thickness 0.25)
			(keepout
				(tracks not_allowed)
				(vias allowed)
				(pads allowed)
				(copperpour not_allowed)
				(footprints allowed)
			)
			(placement
				(enabled no)
				(sheetname "")
			)
			(fill
				(thermal_gap 0.5)
				(thermal_bridge_width 0.5)
				(island_removal_mode 0)
			)
			(polygon
				(pts
					(arc
						(start 16.99133 -138.100054)
						(mid 12.97813 -138.100054)
						(end 16.99133 -138.100054)
					)
				)
			)
		)
	)
	(footprint ""
		(layer "F.Cu")
		(at 27.640026 -462.229962 -90)
		(property "Reference" "R101"
			(at -1.317752 1.035304 90)
			(unlocked yes)
			(layer "F.SilkS")
			(effects
				(font
					(size 0.7874 0.5842)
					(thickness 0.1524)
				)
				(justify left)
			)
		)
		(property "Value" ""
			(at 0 0 270)
			(layer "F.Fab")
			(effects
				(font
					(size 1.27 1.27)
				)
			)
		)
		(duplicate_pad_numbers_are_jumpers no)
		(fp_line
			(start -0.7874 0.4064)
			(end -0.7874 -0.4064)
			(stroke
				(width 0.1524)
				(type default)
			)
			(layer "F.SilkS")
		)
		(fp_line
			(start 0.7874 0.4064)
			(end -0.7874 0.4064)
			(stroke
				(width 0.1524)
				(type default)
			)
			(layer "F.SilkS")
		)
		(fp_line
			(start -0.7874 -0.4064)
			(end 0.7874 -0.4064)
			(stroke
				(width 0.1524)
				(type default)
			)
			(layer "F.SilkS")
		)
		(fp_line
			(start 0.7874 -0.4064)
			(end 0.7874 0.4064)
			(stroke
				(width 0.1524)
				(type default)
			)
			(layer "F.SilkS")
		)
		(fp_poly
			(pts
				(xy -0.508 0.2794) (xy -0.508 0.2286) (xy -0.635 0.2286) (xy -0.635 -0.254) (xy -0.5334 -0.254)
				(xy -0.5334 -0.2794) (xy 0.5334 -0.2794) (xy 0.5334 -0.254) (xy 0.635 -0.254) (xy 0.635 0.254) (xy 0.5334 0.254)
				(xy 0.5334 0.2794)
			)
			(stroke
				(width 0)
				(type default)
			)
			(fill no)
			(layer "F.CrtYd")
		)
		(pad "1" smd rect
			(at 0.40005 0 270)
			(size 0.4572 0.508)
			(layers "F.Cu" "F.Mask" "F.Paste")
			(net "PSU6_REMOTE_N")
		)
		(pad "2" smd rect
			(at -0.40005 0 270)
			(size 0.4572 0.508)
			(layers "F.Cu" "F.Mask" "F.Paste")
			(net "PSU6_REMOTE_R_N")
		)
	)
	(footprint ""
		(layer "F.Cu")
		(at 2.439924 -152.374854 90)
		(property "Reference" "J33"
			(at -1.582928 4.743704 90)
			(unlocked yes)
			(layer "F.SilkS")
			(effects
				(font
					(size 0.7874 0.5842)
					(thickness 0.1524)
				)
				(justify left)
			)
		)
		(property "Value" ""
			(at 0 0 90)
			(layer "F.Fab")
			(effects
				(font
					(size 1.27 1.27)
				)
			)
		)
		(duplicate_pad_numbers_are_jumpers no)
		(fp_line
			(start 1.849882 -1.999996)
			(end -3.02006 -1.999996)
			(stroke
				(width 0.1524)
				(type default)
			)
			(layer "F.SilkS")
		)
		(fp_line
			(start -3.02006 -1.999996)
			(end -3.02006 3.999992)
			(stroke
				(width 0.1524)
				(type default)
			)
			(layer "F.SilkS")
		)
		(fp_line
			(start 1.35001 -1.500124)
			(end -2.519934 -1.500124)
			(stroke
				(width 0.1524)
				(type default)
			)
			(layer "F.SilkS")
		)
		(fp_line
			(start -2.519934 -1.500124)
			(end -2.519934 3.50012)
			(stroke
				(width 0.1524)
				(type default)
			)
			(layer "F.SilkS")
		)
		(fp_line
			(start 1.849882 0.500126)
			(end 1.35001 0.500126)
			(stroke
				(width 0.1524)
				(type default)
			)
			(layer "F.SilkS")
		)
		(fp_line
			(start 1.35001 0.500126)
			(end 1.35001 -1.500124)
			(stroke
				(width 0.1524)
				(type default)
			)
			(layer "F.SilkS")
		)
		(fp_line
			(start 1.35001 1.500124)
			(end 1.849882 1.500124)
			(stroke
				(width 0.1524)
				(type default)
			)
			(layer "F.SilkS")
		)
		(fp_line
			(start 1.35001 3.50012)
			(end 1.35001 1.500124)
			(stroke
				(width 0.1524)
				(type default)
			)
			(layer "F.SilkS")
		)
		(fp_line
			(start -2.519934 3.50012)
			(end 1.35001 3.50012)
			(stroke
				(width 0.1524)
				(type default)
			)
			(layer "F.SilkS")
		)
		(fp_line
			(start 1.849882 3.999992)
			(end 1.849882 -1.999996)
			(stroke
				(width 0.1524)
				(type default)
			)
			(layer "F.SilkS")
		)
		(fp_line
			(start -3.02006 3.999992)
			(end 1.849882 3.999992)
			(stroke
				(width 0.1524)
				(type default)
			)
			(layer "F.SilkS")
		)
		(fp_poly
			(pts
				(xy 2.01041 0) (xy 3.06959 -0.52959) (xy 3.06959 0.52959)
			)
			(stroke
				(width 0)
				(type default)
			)
			(fill yes)
			(layer "F.SilkS")
		)
		(fp_poly
			(pts
				(xy -0.8382 2.8194) (xy 0.8382 2.8194) (xy 0.8382 -0.8382) (xy -0.8382 -0.8382)
			)
			(stroke
				(width 0)
				(type default)
			)
			(fill no)
			(layer "B.CrtYd")
		)
		(fp_poly
			(pts
				(xy -3.02006 3.999992) (xy 1.849882 3.999992) (xy 1.849882 -1.999996) (xy -3.02006 -1.999996)
			)
			(stroke
				(width 0)
				(type default)
			)
			(fill no)
			(layer "F.CrtYd")
		)
		(fp_line
			(start 1.849882 -1.999996)
			(end -3.02006 -1.999996)
			(stroke
				(width 0.1)
				(type default)
			)
			(layer "F.Fab")
		)
		(fp_line
			(start -3.02006 -1.999996)
			(end -3.02006 3.999992)
			(stroke
				(width 0.1)
				(type default)
			)
			(layer "F.Fab")
		)
		(fp_line
			(start 1.849882 3.999992)
			(end 1.849882 -1.999996)
			(stroke
				(width 0.1)
				(type default)
			)
			(layer "F.Fab")
		)
		(fp_line
			(start -3.02006 3.999992)
			(end 1.849882 3.999992)
			(stroke
				(width 0.1)
				(type default)
			)
			(layer "F.Fab")
		)
		(fp_poly
			(pts
				(xy 2.01041 0) (xy 3.06959 -0.52959) (xy 3.06959 0.52959)
			)
			(stroke
				(width 0)
				(type default)
			)
			(fill yes)
			(layer "F.Fab")
		)
		(fp_text user "2"
			(at 2.5527 2.16535 90)
			(unlocked yes)
			(layer "F.SilkS")
			(effects
				(font
					(size 0.7874 0.5842)
					(thickness 0.1524)
				)
			)
		)
		(fp_text user "1"
			(at 1.2192 0.00127 90)
			(unlocked yes)
			(layer "B.SilkS")
			(effects
				(font
					(size 0.7874 0.5842)
					(thickness 0.1524)
				)
				(justify mirror)
			)
		)
		(fp_text user "2"
			(at 1.2192 2.001266 90)
			(unlocked yes)
			(layer "B.SilkS")
			(effects
				(font
					(size 0.7874 0.5842)
					(thickness 0.1524)
				)
				(justify mirror)
			)
		)
		(fp_text user "1"
			(at 1.2192 0.00127 90)
			(unlocked yes)
			(layer "B.Fab")
			(effects
				(font
					(size 0.7874 0.5842)
					(thickness 0.1524)
				)
				(justify mirror)
			)
		)
		(fp_text user "2"
			(at 1.2192 2.001266 90)
			(unlocked yes)
			(layer "B.Fab")
			(effects
				(font
					(size 0.7874 0.5842)
					(thickness 0.1524)
				)
				(justify mirror)
			)
		)
		(fp_text user "2"
			(at 2.5527 2.16535 90)
			(unlocked yes)
			(layer "F.Fab")
			(effects
				(font
					(size 0.7874 0.5842)
					(thickness 0.1524)
				)
			)
		)
		(pad "1" thru_hole rect
			(at 0 0 90)
			(size 1.524 1.524)
			(drill 1.016)
			(layers "*.Cu" "*.Mask")
			(remove_unused_layers no)
			(net "CM_PWR_CTL_IN")
			(clearance 0)
			(padstack
				(mode front_inner_back)
				(layer "Inner"
					(shape circle)
					(size 1.524 1.524)
					(clearance 0)
				)
				(layer "B.Cu"
					(shape rect)
					(size 1.524 1.524)
					(clearance 0)
				)
			)
		)
		(pad "2" thru_hole circle
			(at 0 1.999996 90)
			(size 1.524 1.524)
			(drill 1.016)
			(layers "*.Cu" "*.Mask")
			(remove_unused_layers no)
			(net "GND")
			(clearance 0)
		)
	)
	(footprint ""
		(layer "F.Cu")
		(at 91.399868 -464.509866)
		(property "Reference" "H19"
			(at -5.1308 -5.23113 0)
			(unlocked yes)
			(layer "F.SilkS")
			(effects
				(font
					(size 0.7874 0.5842)
					(thickness 0.1524)
				)
				(justify left)
			)
		)
		(property "Value" ""
			(at 0 0 0)
			(layer "F.Fab")
			(effects
				(font
					(size 1.27 1.27)
				)
			)
		)
		(duplicate_pad_numbers_are_jumpers no)
		(fp_circle
			(center 0 0)
			(end 4.826 0)
			(stroke
				(width 0.1524)
				(type default)
			)
			(fill no)
			(layer "F.SilkS")
		)
		(fp_circle
			(center 0 0)
			(end 4.826 0)
			(stroke
				(width 0.1524)
				(type default)
			)
			(fill no)
			(layer "B.SilkS")
		)
		(fp_poly
			(pts
				(arc
					(start 0 4.0132)
					(mid 0 -4.0132)
					(end 0 4.0132)
				)
			)
			(stroke
				(width 0)
				(type default)
			)
			(fill no)
			(layer "F.CrtYd")
		)
		(pad "" np_thru_hole circle
			(at 0 0)
			(size 8.001 8.001)
			(drill 8.001)
			(layers "*.Cu" "*.Mask")
			(clearance 0.381)
			(thermal_gap 0.381)
		)
		(zone
			(layers "F.Cu" "B.Cu" "In1.Cu" "In2.Cu" "In3.Cu" "In4.Cu" "In5.Cu" "In6.Cu")
			(hatch none 0.5)
			(connect_pads
				(clearance 0)
			)
			(min_thickness 0.25)
			(keepout
				(tracks not_allowed)
				(vias allowed)
				(pads allowed)
				(copperpour not_allowed)
				(footprints allowed)
			)
			(placement
				(enabled no)
				(sheetname "")
			)
			(fill
				(thermal_gap 0.5)
				(thermal_bridge_width 0.5)
				(island_removal_mode 0)
			)
			(polygon
				(pts
					(arc
						(start 91.399868 -459.988666)
						(mid 91.399868 -469.031066)
						(end 91.399868 -459.988666)
					)
				)
			)
		)
	)
	(footprint ""
		(layer "F.Cu")
		(at 25.976072 -6.147562)
		(property "Reference" "R64"
			(at -3.764788 0.113792 0)
			(unlocked yes)
			(layer "F.SilkS")
			(effects
				(font
					(size 0.7874 0.5842)
					(thickness 0.1524)
				)
				(justify left)
			)
		)
		(property "Value" ""
			(at 0 0 0)
			(layer "F.Fab")
			(effects
				(font
					(size 1.27 1.27)
				)
			)
		)
		(duplicate_pad_numbers_are_jumpers no)
		(fp_line
			(start -0.7874 -0.4064)
			(end 0.7874 -0.4064)
			(stroke
				(width 0.1524)
				(type default)
			)
			(layer "F.SilkS")
		)
		(fp_line
			(start -0.7874 0.4064)
			(end -0.7874 -0.4064)
			(stroke
				(width 0.1524)
				(type default)
			)
			(layer "F.SilkS")
		)
		(fp_line
			(start 0.7874 -0.4064)
			(end 0.7874 0.4064)
			(stroke
				(width 0.1524)
				(type default)
			)
			(layer "F.SilkS")
		)
		(fp_line
			(start 0.7874 0.4064)
			(end -0.7874 0.4064)
			(stroke
				(width 0.1524)
				(type default)
			)
			(layer "F.SilkS")
		)
		(fp_poly
			(pts
				(xy -0.508 0.2794) (xy -0.508 0.2286) (xy -0.635 0.2286) (xy -0.635 -0.254) (xy -0.5334 -0.254)
				(xy -0.5334 -0.2794) (xy 0.5334 -0.2794) (xy 0.5334 -0.254) (xy 0.635 -0.254) (xy 0.635 0.254) (xy 0.5334 0.254)
				(xy 0.5334 0.2794)
			)
			(stroke
				(width 0)
				(type default)
			)
			(fill no)
			(layer "F.CrtYd")
		)
		(pad "1" smd rect
			(at 0.40005 0)
			(size 0.4572 0.508)
			(layers "F.Cu" "F.Mask" "F.Paste")
			(net "PSU1_RESET")
		)
		(pad "2" smd rect
			(at -0.40005 0)
			(size 0.4572 0.508)
			(layers "F.Cu" "F.Mask" "F.Paste")
			(net "P12V_STBY")
		)
	)
	(footprint ""
		(layer "F.Cu")
		(at 2.965958 -145.894298 90)
		(property "Reference" "R150"
			(at -0.783844 1.37795 90)
			(unlocked yes)
			(layer "F.SilkS")
			(effects
				(font
					(size 0.7874 0.5842)
					(thickness 0.1524)
				)
				(justify left)
			)
		)
		(property "Value" ""
			(at 0 0 90)
			(layer "F.Fab")
			(effects
				(font
					(size 1.27 1.27)
				)
			)
		)
		(duplicate_pad_numbers_are_jumpers no)
		(fp_line
			(start 0.7874 -0.4064)
			(end 0.7874 0.4064)
			(stroke
				(width 0.1524)
				(type default)
			)
			(layer "F.SilkS")
		)
		(fp_line
			(start -0.7874 -0.4064)
			(end 0.7874 -0.4064)
			(stroke
				(width 0.1524)
				(type default)
			)
			(layer "F.SilkS")
		)
		(fp_line
			(start 0.7874 0.4064)
			(end -0.7874 0.4064)
			(stroke
				(width 0.1524)
				(type default)
			)
			(layer "F.SilkS")
		)
		(fp_line
			(start -0.7874 0.4064)
			(end -0.7874 -0.4064)
			(stroke
				(width 0.1524)
				(type default)
			)
			(layer "F.SilkS")
		)
		(fp_poly
			(pts
				(xy -0.508 0.2794) (xy -0.508 0.2286) (xy -0.635 0.2286) (xy -0.635 -0.254) (xy -0.5334 -0.254)
				(xy -0.5334 -0.2794) (xy 0.5334 -0.2794) (xy 0.5334 -0.254) (xy 0.635 -0.254) (xy 0.635 0.254) (xy 0.5334 0.254)
				(xy 0.5334 0.2794)
			)
			(stroke
				(width 0)
				(type default)
			)
			(fill no)
			(layer "F.CrtYd")
		)
		(pad "1" smd rect
			(at 0.40005 0 90)
			(size 0.4572 0.508)
			(layers "F.Cu" "F.Mask" "F.Paste")
			(net "GND")
		)
		(pad "2" smd rect
			(at -0.40005 0 90)
			(size 0.4572 0.508)
			(layers "F.Cu" "F.Mask" "F.Paste")
			(net "N42130542")
		)
	)
	(footprint ""
		(layer "F.Cu")
		(at 11.444224 -461.694022)
		(property "Reference" "J20"
			(at -5.522214 -4.48056 0)
			(unlocked yes)
			(layer "F.SilkS")
			(effects
				(font
					(size 0.7874 0.5842)
					(thickness 0.1524)
				)
				(justify left)
			)
		)
		(property "Value" ""
			(at 0 0 0)
			(layer "F.Fab")
			(effects
				(font
					(size 1.27 1.27)
				)
			)
		)
		(duplicate_pad_numbers_are_jumpers no)
		(fp_line
			(start -8.949944 17.100042)
			(end -8.949944 20.699984)
			(stroke
				(width 0.1524)
				(type default)
			)
			(layer "F.SilkS")
		)
		(fp_line
			(start -8.949944 20.699984)
			(end -7.349998 20.699984)
			(stroke
				(width 0.1524)
				(type default)
			)
			(layer "F.SilkS")
		)
		(fp_line
			(start -7.349998 -3.299968)
			(end 2.450084 -3.299968)
			(stroke
				(width 0.1524)
				(type default)
			)
			(layer "F.SilkS")
		)
		(fp_line
			(start -7.349998 -2.899918)
			(end 2.450084 -2.899918)
			(stroke
				(width 0.1524)
				(type default)
			)
			(layer "F.SilkS")
		)
		(fp_line
			(start -7.349998 17.100042)
			(end -8.949944 17.100042)
			(stroke
				(width 0.1524)
				(type default)
			)
			(layer "F.SilkS")
		)
		(fp_line
			(start -7.349998 40.699944)
			(end -7.349998 -3.299968)
			(stroke
				(width 0.1524)
				(type default)
			)
			(layer "F.SilkS")
		)
		(fp_line
			(start -7.349998 41.099994)
			(end -7.349998 40.699944)
			(stroke
				(width 0.1524)
				(type default)
			)
			(layer "F.SilkS")
		)
		(fp_line
			(start 2.450084 -3.299968)
			(end 2.450084 -2.899918)
			(stroke
				(width 0.1524)
				(type default)
			)
			(layer "F.SilkS")
		)
		(fp_line
			(start 2.450084 -2.899918)
			(end 2.450084 40.699944)
			(stroke
				(width 0.1524)
				(type default)
			)
			(layer "F.SilkS")
		)
		(fp_line
			(start 2.450084 40.699944)
			(end -7.349998 40.699944)
			(stroke
				(width 0.1524)
				(type default)
			)
			(layer "F.SilkS")
		)
		(fp_line
			(start 2.450084 40.699944)
			(end 2.450084 41.099994)
			(stroke
				(width 0.1524)
				(type default)
			)
			(layer "F.SilkS")
		)
		(fp_line
			(start 2.450084 41.099994)
			(end -7.349998 41.099994)
			(stroke
				(width 0.1524)
				(type default)
			)
			(layer "F.SilkS")
		)
		(fp_poly
			(pts
				(xy 0.042418 -5.091176) (xy -1.227582 -5.091176) (xy -0.567182 -3.567176)
			)
			(stroke
				(width 0)
				(type default)
			)
			(fill yes)
			(layer "F.SilkS")
		)
		(fp_poly
			(pts
				(xy -7.349998 17.100042) (xy -8.949944 17.100042) (xy -8.949944 20.699984) (xy -7.349998 20.699984)
			)
			(stroke
				(width 0)
				(type default)
			)
			(fill yes)
			(layer "F.SilkS")
		)
		(fp_poly
			(pts
				(xy 1.0414 -1.0414) (xy -6.5278 -1.0414) (xy -6.5532 -1.0414) (xy -6.5532 38.8366) (xy -6.5278 38.8366)
				(xy 1.0414 38.8366)
			)
			(stroke
				(width 0)
				(type default)
			)
			(fill no)
			(layer "B.CrtYd")
		)
		(fp_poly
			(pts
				(xy -8.949944 17.100042) (xy -7.349998 17.100042) (xy -7.349998 -3.299968) (xy 2.450084 -3.299968)
				(xy 2.450084 41.099994) (xy -7.349998 41.099994) (xy -7.349998 20.699984) (xy -8.949944 20.699984)
			)
			(stroke
				(width 0)
				(type default)
			)
			(fill no)
			(layer "F.CrtYd")
		)
		(fp_line
			(start -8.949944 17.100042)
			(end -8.949944 20.699984)
			(stroke
				(width 0.1)
				(type default)
			)
			(layer "F.Fab")
		)
		(fp_line
			(start -8.949944 20.699984)
			(end -7.349998 20.699984)
			(stroke
				(width 0.1)
				(type default)
			)
			(layer "F.Fab")
		)
		(fp_line
			(start -7.349998 -3.299968)
			(end 2.450084 -3.299968)
			(stroke
				(width 0.1)
				(type default)
			)
			(layer "F.Fab")
		)
		(fp_line
			(start -7.349998 -2.899918)
			(end -7.349998 -3.299968)
			(stroke
				(width 0.1)
				(type default)
			)
			(layer "F.Fab")
		)
		(fp_line
			(start -7.349998 -2.899918)
			(end 2.44983 -2.899918)
			(stroke
				(width 0.1)
				(type default)
			)
			(layer "F.Fab")
		)
		(fp_line
			(start -7.349998 17.100042)
			(end -8.949944 17.100042)
			(stroke
				(width 0.1)
				(type default)
			)
			(layer "F.Fab")
		)
		(fp_line
			(start -7.349998 40.699944)
			(end -7.349998 -2.899918)
			(stroke
				(width 0.1)
				(type default)
			)
			(layer "F.Fab")
		)
		(fp_line
			(start -7.349998 41.099994)
			(end -7.349998 40.699944)
			(stroke
				(width 0.1)
				(type default)
			)
			(layer "F.Fab")
		)
		(fp_line
			(start 2.44983 -2.899918)
			(end 2.44983 40.699944)
			(stroke
				(width 0.1)
				(type default)
			)
			(layer "F.Fab")
		)
		(fp_line
			(start 2.44983 40.699944)
			(end -7.349998 40.699944)
			(stroke
				(width 0.1)
				(type default)
			)
			(layer "F.Fab")
		)
		(fp_line
			(start 2.450084 -3.299968)
			(end 2.450084 -2.899918)
			(stroke
				(width 0.1)
				(type default)
			)
			(layer "F.Fab")
		)
		(fp_line
			(start 2.450084 40.699944)
			(end 2.450084 41.099994)
			(stroke
				(width 0.1)
				(type default)
			)
			(layer "F.Fab")
		)
		(fp_line
			(start 2.450084 41.099994)
			(end -7.349998 41.099994)
			(stroke
				(width 0.1)
				(type default)
			)
			(layer "F.Fab")
		)
		(fp_poly
			(pts
				(xy 0.409956 -4.940808) (xy -0.860044 -4.940808) (xy -0.199644 -3.416808)
			)
			(stroke
				(width 0)
				(type default)
			)
			(fill yes)
			(layer "F.Fab")
		)
		(fp_text user "11"
			(at -9.198356 -0.33655 0)
			(unlocked yes)
			(layer "F.SilkS")
			(effects
				(font
					(size 0.7874 0.5842)
					(thickness 0.1524)
				)
				(justify left)
			)
		)
		(fp_text user "20"
			(at -6.240526 42.137076 0)
			(unlocked yes)
			(layer "F.SilkS")
			(effects
				(font
					(size 0.7874 0.5842)
					(thickness 0.1524)
				)
				(justify left)
			)
		)
		(fp_text user "1"
			(at -1.490218 -4.315714 0)
			(unlocked yes)
			(layer "F.SilkS")
			(effects
				(font
					(size 0.7874 0.5842)
					(thickness 0.1524)
				)
				(justify left)
			)
		)
		(fp_text user "10"
			(at -0.358902 42.337482 0)
			(unlocked yes)
			(layer "F.SilkS")
			(effects
				(font
					(size 0.7874 0.5842)
					(thickness 0.1524)
				)
				(justify left)
			)
		)
		(fp_text user "20"
			(at -5.506212 40.406574 270)
			(unlocked yes)
			(layer "B.SilkS")
			(effects
				(font
					(size 0.7874 0.5842)
					(thickness 0.1524)
				)
				(justify left mirror)
			)
		)
		(fp_text user "11"
			(at -5.279136 -2.356612 90)
			(unlocked yes)
			(layer "B.SilkS")
			(effects
				(font
					(size 0.7874 0.5842)
					(thickness 0.1524)
				)
				(justify left mirror)
			)
		)
		(fp_text user "10"
			(at -0.15875 40.350948 270)
			(unlocked yes)
			(layer "B.SilkS")
			(effects
				(font
					(size 0.7874 0.5842)
					(thickness 0.1524)
				)
				(justify left mirror)
			)
		)
		(fp_text user "1"
			(at 0.246126 -2.382012 90)
			(unlocked yes)
			(layer "B.SilkS")
			(effects
				(font
					(size 0.7874 0.5842)
					(thickness 0.1524)
				)
				(justify left mirror)
			)
		)
		(fp_text user "11"
			(at -5.506212 -1.086612 270)
			(unlocked yes)
			(layer "B.Fab")
			(effects
				(font
					(size 0.7874 0.5842)
					(thickness 0.000001)
				)
				(justify left mirror)
			)
		)
		(fp_text user "20"
			(at -5.506212 40.406574 270)
			(unlocked yes)
			(layer "B.Fab")
			(effects
				(font
					(size 0.7874 0.5842)
					(thickness 0.000001)
				)
				(justify left mirror)
			)
		)
		(fp_text user "10"
			(at -0.15875 40.350948 270)
			(unlocked yes)
			(layer "B.Fab")
			(effects
				(font
					(size 0.7874 0.5842)
					(thickness 0.000001)
				)
				(justify left mirror)
			)
		)
		(fp_text user "1"
			(at 0.01905 -1.112012 270)
			(unlocked yes)
			(layer "B.Fab")
			(effects
				(font
					(size 0.7874 0.5842)
					(thickness 0.000001)
				)
				(justify left mirror)
			)
		)
		(fp_text user "20"
			(at -5.506212 41.264332 270)
			(unlocked yes)
			(layer "F.Fab")
			(effects
				(font
					(size 0.7874 0.5842)
					(thickness 0.000001)
				)
				(justify left)
			)
		)
		(fp_text user "11"
			(at -5.455412 -4.713224 270)
			(unlocked yes)
			(layer "F.Fab")
			(effects
				(font
					(size 0.7874 0.5842)
					(thickness 0.000001)
				)
				(justify left)
			)
		)
		(fp_text user "10"
			(at -0.183896 41.102534 270)
			(unlocked yes)
			(layer "F.Fab")
			(effects
				(font
					(size 0.7874 0.5842)
					(thickness 0.000001)
				)
				(justify left)
			)
		)
		(fp_text user "1"
			(at 0.53086 -3.95732 270)
			(unlocked yes)
			(layer "F.Fab")
			(effects
				(font
					(size 0.7874 0.5842)
					(thickness 0.000001)
				)
				(justify left)
			)
		)
		(pad "1" thru_hole rect
			(at 0 0 270)
			(size 1.9558 1.9558)
			(drill 1.4478)
			(layers "*.Cu" "*.Mask")
			(remove_unused_layers no)
			(net "FAN1_TACH")
			(clearance 0)
			(padstack
				(mode front_inner_back)
				(layer "Inner"
					(shape circle)
					(size 1.9558 1.9558)
					(clearance 0)
				)
				(layer "B.Cu"
					(shape rect)
					(size 1.9558 1.9558)
					(clearance 0)
				)
			)
		)
		(pad "2" thru_hole circle
			(at 0 4.19989 270)
			(size 1.9558 1.9558)
			(drill 1.4478)
			(layers "*.Cu" "*.Mask")
			(remove_unused_layers no)
			(net "P12V")
			(clearance 0)
		)
		(pad "3" thru_hole circle
			(at 0 8.400034 270)
			(size 1.9558 1.9558)
			(drill 1.4478)
			(layers "*.Cu" "*.Mask")
			(remove_unused_layers no)
			(net "P12V")
			(clearance 0)
		)
		(pad "4" thru_hole circle
			(at 0 12.599924 270)
			(size 1.9558 1.9558)
			(drill 1.4478)
			(layers "*.Cu" "*.Mask")
			(remove_unused_layers no)
			(net "FAN2_TACH")
			(clearance 0)
		)
		(pad "5" thru_hole circle
			(at 0 16.800068 270)
			(size 1.9558 1.9558)
			(drill 1.4478)
			(layers "*.Cu" "*.Mask")
			(remove_unused_layers no)
			(net "P12V")
			(clearance 0)
		)
		(pad "6" thru_hole circle
			(at 0 20.999958 270)
			(size 1.9558 1.9558)
			(drill 1.4478)
			(layers "*.Cu" "*.Mask")
			(remove_unused_layers no)
			(net "P12V")
			(clearance 0)
		)
		(pad "7" thru_hole circle
			(at 0 25.200102 270)
			(size 1.9558 1.9558)
			(drill 1.4478)
			(layers "*.Cu" "*.Mask")
			(remove_unused_layers no)
			(net "FAN3_TACH")
			(clearance 0)
		)
		(pad "8" thru_hole circle
			(at 0 29.399992 270)
			(size 1.9558 1.9558)
			(drill 1.4478)
			(layers "*.Cu" "*.Mask")
			(remove_unused_layers no)
			(net "P12V")
			(clearance 0)
		)
		(pad "9" thru_hole circle
			(at 0 33.599882 270)
			(size 1.9558 1.9558)
			(drill 1.4478)
			(layers "*.Cu" "*.Mask")
			(remove_unused_layers no)
			(net "P12V")
			(clearance 0)
		)
		(pad "10" thru_hole circle
			(at 0 37.800026 270)
			(size 1.9558 1.9558)
			(drill 1.4478)
			(layers "*.Cu" "*.Mask")
			(remove_unused_layers no)
			(net "FAN4_TACH")
			(clearance 0)
		)
		(pad "11" thru_hole circle
			(at -5.500116 0 270)
			(size 1.9558 1.9558)
			(drill 1.4478)
			(layers "*.Cu" "*.Mask")
			(remove_unused_layers no)
			(net "FAN5_TACH")
			(clearance 0)
		)
		(pad "12" thru_hole circle
			(at -5.500116 4.19989 270)
			(size 1.9558 1.9558)
			(drill 1.4478)
			(layers "*.Cu" "*.Mask")
			(remove_unused_layers no)
			(net "GND")
			(clearance 0)
		)
		(pad "13" thru_hole circle
			(at -5.500116 8.400034 270)
			(size 1.9558 1.9558)
			(drill 1.4478)
			(layers "*.Cu" "*.Mask")
			(remove_unused_layers no)
			(net "GND")
			(clearance 0)
		)
		(pad "14" thru_hole circle
			(at -5.500116 12.599924 270)
			(size 1.9558 1.9558)
			(drill 1.4478)
			(layers "*.Cu" "*.Mask")
			(remove_unused_layers no)
			(net "FAN6_TACH")
			(clearance 0)
		)
		(pad "15" thru_hole circle
			(at -5.500116 16.800068 270)
			(size 1.9558 1.9558)
			(drill 1.4478)
			(layers "*.Cu" "*.Mask")
			(remove_unused_layers no)
			(net "GND")
			(clearance 0)
		)
		(pad "16" thru_hole circle
			(at -5.500116 20.999958 270)
			(size 1.9558 1.9558)
			(drill 1.4478)
			(layers "*.Cu" "*.Mask")
			(remove_unused_layers no)
			(net "GND")
			(clearance 0)
		)
		(pad "17" thru_hole circle
			(at -5.500116 25.200102 270)
			(size 1.9558 1.9558)
			(drill 1.4478)
			(layers "*.Cu" "*.Mask")
			(remove_unused_layers no)
			(net "FAN_PWM")
			(clearance 0)
		)
		(pad "18" thru_hole circle
			(at -5.500116 29.399992 270)
			(size 1.9558 1.9558)
			(drill 1.4478)
			(layers "*.Cu" "*.Mask")
			(remove_unused_layers no)
			(net "GND")
			(clearance 0)
		)
		(pad "19" thru_hole circle
			(at -5.500116 33.599882 270)
			(size 1.9558 1.9558)
			(drill 1.4478)
			(layers "*.Cu" "*.Mask")
			(remove_unused_layers no)
			(net "GND")
			(clearance 0)
		)
		(pad "20" thru_hole circle
			(at -5.500116 37.800026 270)
			(size 1.9558 1.9558)
			(drill 1.4478)
			(layers "*.Cu" "*.Mask")
			(remove_unused_layers no)
			(net "FAN_PWM")
			(clearance 0)
		)
	)
	(footprint ""
		(layer "F.Cu")
		(at 46.430692 -238.246666 180)
		(property "Reference" "R88"
			(at 4.272788 0.078232 0)
			(unlocked yes)
			(layer "F.SilkS")
			(effects
				(font
					(size 0.7874 0.5842)
					(thickness 0.1524)
				)
				(justify left)
			)
		)
		(property "Value" ""
			(at 0 0 180)
			(layer "F.Fab")
			(effects
				(font
					(size 1.27 1.27)
				)
			)
		)
		(duplicate_pad_numbers_are_jumpers no)
		(fp_line
			(start 0.7874 0.4064)
			(end -0.7874 0.4064)
			(stroke
				(width 0.1524)
				(type default)
			)
			(layer "F.SilkS")
		)
		(fp_line
			(start 0.7874 -0.4064)
			(end 0.7874 0.4064)
			(stroke
				(width 0.1524)
				(type default)
			)
			(layer "F.SilkS")
		)
		(fp_line
			(start -0.7874 0.4064)
			(end -0.7874 -0.4064)
			(stroke
				(width 0.1524)
				(type default)
			)
			(layer "F.SilkS")
		)
		(fp_line
			(start -0.7874 -0.4064)
			(end 0.7874 -0.4064)
			(stroke
				(width 0.1524)
				(type default)
			)
			(layer "F.SilkS")
		)
		(fp_poly
			(pts
				(xy -0.508 0.2794) (xy -0.508 0.2286) (xy -0.635 0.2286) (xy -0.635 -0.254) (xy -0.5334 -0.254)
				(xy -0.5334 -0.2794) (xy 0.5334 -0.2794) (xy 0.5334 -0.254) (xy 0.635 -0.254) (xy 0.635 0.254) (xy 0.5334 0.254)
				(xy 0.5334 0.2794)
			)
			(stroke
				(width 0)
				(type default)
			)
			(fill no)
			(layer "F.CrtYd")
		)
		(pad "1" smd rect
			(at 0.40005 0 180)
			(size 0.4572 0.508)
			(layers "F.Cu" "F.Mask" "F.Paste")
			(net "PSU1_REMOTE_R_P")
		)
		(pad "2" smd rect
			(at -0.40005 0 180)
			(size 0.4572 0.508)
			(layers "F.Cu" "F.Mask" "F.Paste")
			(net "P12V")
		)
	)
	(footprint ""
		(layer "F.Cu")
		(at 77.999844 -478.300034)
		(property "Reference" "H13"
			(at -5.799582 -2.59334 0)
			(unlocked yes)
			(layer "F.SilkS")
			(effects
				(font
					(size 0.7874 0.5842)
					(thickness 0.1524)
				)
				(justify left)
			)
		)
		(property "Value" ""
			(at 0 0 0)
			(layer "F.Fab")
			(effects
				(font
					(size 1.27 1.27)
				)
			)
		)
		(duplicate_pad_numbers_are_jumpers no)
		(fp_line
			(start -3.4163 0)
			(end -3.4163 -0.4953)
			(stroke
				(width 0.1524)
				(type default)
			)
			(layer "F.SilkS")
		)
		(fp_line
			(start -3.4163 0.4953)
			(end -3.4163 0)
			(stroke
				(width 0.1524)
				(type default)
			)
			(layer "F.SilkS")
		)
		(fp_line
			(start 3.4163 -0.4953)
			(end 3.4163 0.4953)
			(stroke
				(width 0.1524)
				(type default)
			)
			(layer "F.SilkS")
		)
		(fp_arc
			(start -3.4163 -0.4953)
			(mid -2.415689 -2.910989)
			(end 0 -3.9116)
			(stroke
				(width 0.1524)
				(type default)
			)
			(layer "F.SilkS")
		)
		(fp_arc
			(start 0 -3.9116)
			(mid 2.415689 -2.910989)
			(end 3.4163 -0.4953)
			(stroke
				(width 0.1524)
				(type default)
			)
			(layer "F.SilkS")
		)
		(fp_arc
			(start 0 3.9116)
			(mid -2.415689 2.910989)
			(end -3.4163 0.4953)
			(stroke
				(width 0.1524)
				(type default)
			)
			(layer "F.SilkS")
		)
		(fp_arc
			(start 3.4163 0.4953)
			(mid 2.415689 2.910989)
			(end 0 3.9116)
			(stroke
				(width 0.1524)
				(type default)
			)
			(layer "F.SilkS")
		)
		(fp_line
			(start -3.4163 0)
			(end -3.4163 -0.4953)
			(stroke
				(width 0.1524)
				(type default)
			)
			(layer "B.SilkS")
		)
		(fp_line
			(start -3.4163 0.4953)
			(end -3.4163 0)
			(stroke
				(width 0.1524)
				(type default)
			)
			(layer "B.SilkS")
		)
		(fp_line
			(start 3.4163 -0.4953)
			(end 3.4163 0.4953)
			(stroke
				(width 0.1524)
				(type default)
			)
			(layer "B.SilkS")
		)
		(fp_arc
			(start -3.4163 -0.4953)
			(mid -2.415689 -2.910989)
			(end 0 -3.9116)
			(stroke
				(width 0.1524)
				(type default)
			)
			(layer "B.SilkS")
		)
		(fp_arc
			(start 0 -3.9116)
			(mid 2.415689 -2.910989)
			(end 3.4163 -0.4953)
			(stroke
				(width 0.1524)
				(type default)
			)
			(layer "B.SilkS")
		)
		(fp_arc
			(start 0 3.9116)
			(mid -2.415689 2.910989)
			(end -3.4163 0.4953)
			(stroke
				(width 0.1524)
				(type default)
			)
			(layer "B.SilkS")
		)
		(fp_arc
			(start 3.4163 0.4953)
			(mid 2.415689 2.910989)
			(end 0 3.9116)
			(stroke
				(width 0.1524)
				(type default)
			)
			(layer "B.SilkS")
		)
		(fp_poly
			(pts
				(arc
					(start -2.853944 -0.499872)
					(mid 0 -3.353816)
					(end 2.853944 -0.499872)
				)
				(arc
					(start 2.853944 0.499872)
					(mid 0 3.35407)
					(end -2.853944 0.499872)
				)
			)
			(stroke
				(width 0)
				(type default)
			)
			(fill no)
			(layer "B.CrtYd")
		)
		(fp_poly
			(pts
				(arc
					(start -2.853944 -0.499872)
					(mid 0 -3.353816)
					(end 2.853944 -0.499872)
				)
				(arc
					(start 2.853944 0.499872)
					(mid 0 3.35407)
					(end -2.853944 0.499872)
				)
			)
			(stroke
				(width 0)
				(type default)
			)
			(fill no)
			(layer "F.CrtYd")
		)
		(pad "" np_thru_hole oval
			(at 0 0)
			(size 5.207 6.1976)
			(drill oval 5.207 6.1976)
			(layers "*.Cu" "*.Mask")
			(clearance 0.381)
			(thermal_gap 0.381)
		)
		(zone
			(layers "F.Cu" "B.Cu" "In1.Cu" "In2.Cu" "In3.Cu" "In4.Cu" "In5.Cu" "In6.Cu")
			(hatch none 0.5)
			(connect_pads
				(clearance 0)
			)
			(min_thickness 0.25)
			(keepout
				(tracks not_allowed)
				(vias allowed)
				(pads allowed)
				(copperpour not_allowed)
				(footprints allowed)
			)
			(placement
				(enabled no)
				(sheetname "")
			)
			(fill
				(thermal_gap 0.5)
				(thermal_bridge_width 0.5)
				(island_removal_mode 0)
			)
			(polygon
				(pts
					(xy 74.888344 -478.300034)
					(arc
						(start 74.888344 -478.795334)
						(mid 75.799681 -480.995497)
						(end 77.999844 -481.906834)
					)
					(arc
						(start 77.999844 -481.906834)
						(mid 80.200007 -480.995497)
						(end 81.111344 -478.795334)
					)
					(arc
						(start 81.111344 -477.804734)
						(mid 80.200007 -475.604571)
						(end 77.999844 -474.693234)
					)
					(arc
						(start 77.999844 -474.693234)
						(mid 75.799681 -475.604571)
						(end 74.888344 -477.804734)
					)
				)
			)
		)
	)
	(footprint ""
		(layer "F.Cu")
		(at 50.478944 -329.972416 180)
		(property "Reference" "CE15"
			(at 1.661922 5.89026 0)
			(unlocked yes)
			(layer "F.SilkS")
			(effects
				(font
					(size 0.7874 0.5842)
					(thickness 0.1524)
				)
				(justify left)
			)
		)
		(property "Value" ""
			(at 0 0 180)
			(layer "F.Fab")
			(effects
				(font
					(size 1.27 1.27)
				)
			)
		)
		(duplicate_pad_numbers_are_jumpers no)
		(fp_line
			(start 0 -4.2672)
			(end 0 4.2672)
			(stroke
				(width 0.1524)
				(type default)
			)
			(layer "F.SilkS")
		)
		(fp_circle
			(center 0 0)
			(end -4.2672 0)
			(stroke
				(width 0.1524)
				(type default)
			)
			(fill no)
			(layer "F.SilkS")
		)
		(fp_poly
			(pts
				(arc
					(start 0 -4.2672)
					(mid 4.2672 0)
					(end 0 4.2672)
				)
			)
			(stroke
				(width 0)
				(type default)
			)
			(fill yes)
			(layer "F.SilkS")
		)
		(fp_poly
			(pts
				(xy -2.5146 -0.762) (xy -0.9906 -0.762) (xy -0.9906 0.762) (xy -2.5146 0.762)
			)
			(stroke
				(width 0)
				(type default)
			)
			(fill no)
			(layer "B.CrtYd")
		)
		(fp_poly
			(pts
				(arc
					(start 1.7526 0.762)
					(mid 2.291415 -0.538815)
					(end 0.9906 0)
				)
				(arc
					(start 0.9906 0.0254)
					(mid 1.206345 0.546255)
					(end 1.7272 0.762)
				)
			)
			(stroke
				(width 0)
				(type default)
			)
			(fill no)
			(layer "B.CrtYd")
		)
		(fp_poly
			(pts
				(arc
					(start -4.2672 0)
					(mid 4.2672 0)
					(end -4.2672 0)
				)
			)
			(stroke
				(width 0)
				(type default)
			)
			(fill no)
			(layer "F.CrtYd")
		)
		(fp_circle
			(center 0 0)
			(end -4.2672 0)
			(stroke
				(width 0.1)
				(type default)
			)
			(fill no)
			(layer "F.Fab")
		)
		(fp_text user "+"
			(at -5.080762 -0.360426 180)
			(unlocked yes)
			(layer "F.SilkS")
			(effects
				(font
					(size 0.7874 0.5842)
					(thickness 0.1524)
				)
				(justify left)
			)
		)
		(fp_text user "+"
			(at -5.6642 -0.34925 180)
			(unlocked yes)
			(layer "F.Fab")
			(effects
				(font
					(size 1.905 1.4224)
					(thickness 0.000001)
				)
				(justify left)
			)
		)
		(pad "1" thru_hole rect
			(at -1.75006 0 180)
			(size 1.397 1.397)
			(drill 0.9144)
			(layers "*.Cu" "*.Mask")
			(remove_unused_layers no)
			(net "P12V")
			(clearance 0.0127)
			(thermal_gap 0.0127)
			(padstack
				(mode front_inner_back)
				(layer "Inner"
					(shape circle)
					(size 1.397 1.397)
					(clearance 0.0127)
				)
				(layer "B.Cu"
					(shape rect)
					(size 1.397 1.397)
					(clearance 0.0127)
				)
			)
		)
		(pad "2" thru_hole circle
			(at 1.75006 0 180)
			(size 1.397 1.397)
			(drill 0.9144)
			(layers "*.Cu" "*.Mask")
			(remove_unused_layers no)
			(net "GND")
			(clearance 0.0127)
			(thermal_gap 0.0127)
		)
	)
	(footprint ""
		(layer "F.Cu")
		(at 26.226008 -453.535034)
		(property "Reference" "R60"
			(at -3.597402 -0.121666 0)
			(unlocked yes)
			(layer "F.SilkS")
			(effects
				(font
					(size 0.7874 0.5842)
					(thickness 0.1524)
				)
				(justify left)
			)
		)
		(property "Value" ""
			(at 0 0 0)
			(layer "F.Fab")
			(effects
				(font
					(size 1.27 1.27)
				)
			)
		)
		(duplicate_pad_numbers_are_jumpers no)
		(fp_line
			(start -0.7874 -0.4064)
			(end 0.7874 -0.4064)
			(stroke
				(width 0.1524)
				(type default)
			)
			(layer "F.SilkS")
		)
		(fp_line
			(start -0.7874 0.4064)
			(end -0.7874 -0.4064)
			(stroke
				(width 0.1524)
				(type default)
			)
			(layer "F.SilkS")
		)
		(fp_line
			(start 0.7874 -0.4064)
			(end 0.7874 0.4064)
			(stroke
				(width 0.1524)
				(type default)
			)
			(layer "F.SilkS")
		)
		(fp_line
			(start 0.7874 0.4064)
			(end -0.7874 0.4064)
			(stroke
				(width 0.1524)
				(type default)
			)
			(layer "F.SilkS")
		)
		(fp_poly
			(pts
				(xy -0.508 0.2794) (xy -0.508 0.2286) (xy -0.635 0.2286) (xy -0.635 -0.254) (xy -0.5334 -0.254)
				(xy -0.5334 -0.2794) (xy 0.5334 -0.2794) (xy 0.5334 -0.254) (xy 0.635 -0.254) (xy 0.635 0.254) (xy 0.5334 0.254)
				(xy 0.5334 0.2794)
			)
			(stroke
				(width 0)
				(type default)
			)
			(fill no)
			(layer "F.CrtYd")
		)
		(pad "1" smd rect
			(at 0.40005 0)
			(size 0.4572 0.508)
			(layers "F.Cu" "F.Mask" "F.Paste")
			(net "PSU6_PS_KILL")
		)
		(pad "2" smd rect
			(at -0.40005 0)
			(size 0.4572 0.508)
			(layers "F.Cu" "F.Mask" "F.Paste")
			(net "GND")
		)
	)
	(footprint ""
		(layer "F.Cu")
		(at 50.100738 -62.882272 180)
		(property "Reference" "CE3"
			(at -4.025646 2.458974 0)
			(unlocked yes)
			(layer "F.SilkS")
			(effects
				(font
					(size 0.7874 0.5842)
					(thickness 0.1524)
				)
				(justify left)
			)
		)
		(property "Value" ""
			(at 0 0 180)
			(layer "F.Fab")
			(effects
				(font
					(size 1.27 1.27)
				)
			)
		)
		(duplicate_pad_numbers_are_jumpers no)
		(fp_line
			(start 0 -4.2672)
			(end 0 4.2672)
			(stroke
				(width 0.1524)
				(type default)
			)
			(layer "F.SilkS")
		)
		(fp_circle
			(center 0 0)
			(end -4.2672 0)
			(stroke
				(width 0.1524)
				(type default)
			)
			(fill no)
			(layer "F.SilkS")
		)
		(fp_poly
			(pts
				(arc
					(start 0 -4.2672)
					(mid 4.2672 0)
					(end 0 4.2672)
				)
			)
			(stroke
				(width 0)
				(type default)
			)
			(fill yes)
			(layer "F.SilkS")
		)
		(fp_poly
			(pts
				(xy -2.5146 -0.762) (xy -0.9906 -0.762) (xy -0.9906 0.762) (xy -2.5146 0.762)
			)
			(stroke
				(width 0)
				(type default)
			)
			(fill no)
			(layer "B.CrtYd")
		)
		(fp_poly
			(pts
				(arc
					(start 1.7526 0.762)
					(mid 2.291415 -0.538815)
					(end 0.9906 0)
				)
				(arc
					(start 0.9906 0.0254)
					(mid 1.206345 0.546255)
					(end 1.7272 0.762)
				)
			)
			(stroke
				(width 0)
				(type default)
			)
			(fill no)
			(layer "B.CrtYd")
		)
		(fp_poly
			(pts
				(arc
					(start -4.2672 0)
					(mid 4.2672 0)
					(end -4.2672 0)
				)
			)
			(stroke
				(width 0)
				(type default)
			)
			(fill no)
			(layer "F.CrtYd")
		)
		(fp_circle
			(center 0 0)
			(end -4.2672 0)
			(stroke
				(width 0.1)
				(type default)
			)
			(fill no)
			(layer "F.Fab")
		)
		(fp_text user "+"
			(at -5.750306 -0.11303 180)
			(unlocked yes)
			(layer "F.SilkS")
			(effects
				(font
					(size 0.7874 0.5842)
					(thickness 0.1524)
				)
				(justify left)
			)
		)
		(fp_text user "+"
			(at -5.6642 -0.34925 180)
			(unlocked yes)
			(layer "F.Fab")
			(effects
				(font
					(size 1.905 1.4224)
					(thickness 0.000001)
				)
				(justify left)
			)
		)
		(pad "1" thru_hole rect
			(at -1.75006 0 180)
			(size 1.397 1.397)
			(drill 0.9144)
			(layers "*.Cu" "*.Mask")
			(remove_unused_layers no)
			(net "P12V")
			(clearance 0.0127)
			(thermal_gap 0.0127)
			(padstack
				(mode front_inner_back)
				(layer "Inner"
					(shape circle)
					(size 1.397 1.397)
					(clearance 0.0127)
				)
				(layer "B.Cu"
					(shape rect)
					(size 1.397 1.397)
					(clearance 0.0127)
				)
			)
		)
		(pad "2" thru_hole circle
			(at 1.75006 0 180)
			(size 1.397 1.397)
			(drill 0.9144)
			(layers "*.Cu" "*.Mask")
			(remove_unused_layers no)
			(net "GND")
			(clearance 0.0127)
			(thermal_gap 0.0127)
		)
	)
	(footprint ""
		(layer "F.Cu")
		(at 46.472856 -247.282716 180)
		(property "Reference" "R96"
			(at -0.980186 -0.54483 0)
			(unlocked yes)
			(layer "F.SilkS")
			(effects
				(font
					(size 0.7874 0.5842)
					(thickness 0.1524)
				)
				(justify left)
			)
		)
		(property "Value" ""
			(at 0 0 180)
			(layer "F.Fab")
			(effects
				(font
					(size 1.27 1.27)
				)
			)
		)
		(duplicate_pad_numbers_are_jumpers no)
		(fp_line
			(start 0.7874 0.4064)
			(end -0.7874 0.4064)
			(stroke
				(width 0.1524)
				(type default)
			)
			(layer "F.SilkS")
		)
		(fp_line
			(start 0.7874 -0.4064)
			(end 0.7874 0.4064)
			(stroke
				(width 0.1524)
				(type default)
			)
			(layer "F.SilkS")
		)
		(fp_line
			(start -0.7874 0.4064)
			(end -0.7874 -0.4064)
			(stroke
				(width 0.1524)
				(type default)
			)
			(layer "F.SilkS")
		)
		(fp_line
			(start -0.7874 -0.4064)
			(end 0.7874 -0.4064)
			(stroke
				(width 0.1524)
				(type default)
			)
			(layer "F.SilkS")
		)
		(fp_poly
			(pts
				(xy -0.508 0.2794) (xy -0.508 0.2286) (xy -0.635 0.2286) (xy -0.635 -0.254) (xy -0.5334 -0.254)
				(xy -0.5334 -0.2794) (xy 0.5334 -0.2794) (xy 0.5334 -0.254) (xy 0.635 -0.254) (xy 0.635 0.254) (xy 0.5334 0.254)
				(xy 0.5334 0.2794)
			)
			(stroke
				(width 0)
				(type default)
			)
			(fill no)
			(layer "F.CrtYd")
		)
		(pad "1" smd rect
			(at 0.40005 0 180)
			(size 0.4572 0.508)
			(layers "F.Cu" "F.Mask" "F.Paste")
			(net "PSU3_REMOTE_R_P")
		)
		(pad "2" smd rect
			(at -0.40005 0 180)
			(size 0.4572 0.508)
			(layers "F.Cu" "F.Mask" "F.Paste")
			(net "P12V")
		)
	)
	(footprint ""
		(layer "F.Cu")
		(at 30.45968 -436.930038)
		(property "Reference" "J5"
			(at -4.20243 -2.774188 0)
			(unlocked yes)
			(layer "F.SilkS")
			(effects
				(font
					(size 0.7874 0.5842)
					(thickness 0.1524)
				)
				(justify left)
			)
		)
		(property "Value" ""
			(at 0 0 0)
			(layer "F.Fab")
			(effects
				(font
					(size 1.27 1.27)
				)
			)
		)
		(duplicate_pad_numbers_are_jumpers no)
		(fp_line
			(start -2.135124 -4.560062)
			(end -2.135124 83.300062)
			(stroke
				(width 0.1524)
				(type default)
			)
			(layer "F.SilkS")
		)
		(fp_line
			(start -2.135124 83.300062)
			(end 7.215124 83.300062)
			(stroke
				(width 0.1524)
				(type default)
			)
			(layer "F.SilkS")
		)
		(fp_line
			(start 7.215124 -4.560062)
			(end -2.135124 -4.560062)
			(stroke
				(width 0.1524)
				(type default)
			)
			(layer "F.SilkS")
		)
		(fp_line
			(start 7.215124 83.300062)
			(end 7.215124 -4.560062)
			(stroke
				(width 0.1524)
				(type default)
			)
			(layer "F.SilkS")
		)
		(fp_poly
			(pts
				(xy -2.74447 -0.00889) (xy -5.44449 -0.708914) (xy -5.44449 0.691134)
			)
			(stroke
				(width 0)
				(type default)
			)
			(fill yes)
			(layer "F.SilkS")
		)
		(fp_poly
			(pts
				(xy -2.28219 -0.127) (xy -4.98221 -0.827024) (xy -4.98221 0.573024)
			)
			(stroke
				(width 0)
				(type default)
			)
			(fill yes)
			(layer "B.SilkS")
		)
		(fp_poly
			(pts
				(xy -0.8636 -0.8636) (xy -0.8636 79.6036) (xy -0.8636 79.629) (xy 5.9436 79.629) (xy 5.9436 79.6036)
				(xy 5.9436 -0.8636) (xy 5.9436 -0.889) (xy -0.8636 -0.889)
			)
			(stroke
				(width 0)
				(type default)
			)
			(fill no)
			(layer "B.CrtYd")
		)
		(fp_rect
			(start -2.135124 -4.560062)
			(end 7.21487 83.300062)
			(stroke
				(width 0)
				(type default)
			)
			(fill no)
			(layer "F.CrtYd")
		)
		(fp_line
			(start -2.135124 -4.560062)
			(end 7.215124 -4.560062)
			(stroke
				(width 0.1)
				(type default)
			)
			(layer "F.Fab")
		)
		(fp_line
			(start -2.135124 83.300062)
			(end -2.135124 -4.560062)
			(stroke
				(width 0.1)
				(type default)
			)
			(layer "F.Fab")
		)
		(fp_line
			(start 7.215124 -4.560062)
			(end 7.215124 83.300062)
			(stroke
				(width 0.1)
				(type default)
			)
			(layer "F.Fab")
		)
		(fp_line
			(start 7.215124 83.300062)
			(end -2.135124 83.300062)
			(stroke
				(width 0.1)
				(type default)
			)
			(layer "F.Fab")
		)
		(fp_text user "32"
			(at -3.655568 78.848458 0)
			(unlocked yes)
			(layer "F.SilkS")
			(effects
				(font
					(size 0.7874 0.5842)
					(thickness 0.1524)
				)
				(justify left)
			)
		)
		(fp_text user "1"
			(at -3.370834 -1.059434 0)
			(unlocked yes)
			(layer "F.SilkS")
			(effects
				(font
					(size 0.7874 0.5842)
					(thickness 0.1524)
				)
				(justify left)
			)
		)
		(fp_text user "33"
			(at 7.649464 81.833466 0)
			(unlocked yes)
			(layer "F.SilkS")
			(effects
				(font
					(size 0.7874 0.5842)
					(thickness 0.1524)
				)
				(justify left)
			)
		)
		(fp_text user "64"
			(at 7.771638 -0.257048 0)
			(unlocked yes)
			(layer "F.SilkS")
			(effects
				(font
					(size 0.7874 0.5842)
					(thickness 0.1524)
				)
				(justify left)
			)
		)
		(fp_text user "32"
			(at -1.12649 78.817216 0)
			(unlocked yes)
			(layer "B.SilkS")
			(effects
				(font
					(size 0.7874 0.5842)
					(thickness 0.1524)
				)
				(justify left mirror)
			)
		)
		(fp_text user "1"
			(at -1.029208 -1.200912 0)
			(unlocked yes)
			(layer "B.SilkS")
			(effects
				(font
					(size 0.7874 0.5842)
					(thickness 0.1524)
				)
				(justify left mirror)
			)
		)
		(fp_text user "33"
			(at 5.666486 81.833466 0)
			(unlocked yes)
			(layer "B.SilkS")
			(effects
				(font
					(size 0.7874 0.5842)
					(thickness 0.1524)
				)
				(justify left mirror)
			)
		)
		(fp_text user "64"
			(at 5.904992 -1.819148 0)
			(unlocked yes)
			(layer "B.SilkS")
			(effects
				(font
					(size 0.7874 0.5842)
					(thickness 0.1524)
				)
				(justify left mirror)
			)
		)
		(pad "1" thru_hole rect
			(at 0 0 270)
			(size 1.6256 1.6256)
			(drill 1.1176)
			(layers "*.Cu" "*.Mask")
			(remove_unused_layers no)
			(net "P12V")
			(clearance 0)
			(padstack
				(mode front_inner_back)
				(layer "Inner"
					(shape circle)
					(size 1.6256 1.6256)
					(clearance 0)
				)
				(layer "B.Cu"
					(shape rect)
					(size 1.6256 1.6256)
					(clearance 0)
				)
			)
		)
		(pad "2" thru_hole circle
			(at 0 2.54 270)
			(size 1.6256 1.6256)
			(drill 1.1176)
			(layers "*.Cu" "*.Mask")
			(remove_unused_layers no)
			(net "P12V")
			(clearance 0)
		)
		(pad "3" thru_hole circle
			(at 0 5.08 270)
			(size 1.6256 1.6256)
			(drill 1.1176)
			(layers "*.Cu" "*.Mask")
			(remove_unused_layers no)
			(net "P12V")
			(clearance 0)
		)
		(pad "4" thru_hole circle
			(at 0 7.62 270)
			(size 1.6256 1.6256)
			(drill 1.1176)
			(layers "*.Cu" "*.Mask")
			(remove_unused_layers no)
			(net "P12V")
			(clearance 0)
		)
		(pad "5" thru_hole circle
			(at 0 10.16 270)
			(size 1.6256 1.6256)
			(drill 1.1176)
			(layers "*.Cu" "*.Mask")
			(remove_unused_layers no)
			(net "P12V")
			(clearance 0)
		)
		(pad "6" thru_hole circle
			(at 0 12.7 270)
			(size 1.6256 1.6256)
			(drill 1.1176)
			(layers "*.Cu" "*.Mask")
			(remove_unused_layers no)
			(net "P12V")
			(clearance 0)
		)
		(pad "7" thru_hole circle
			(at 0 15.24 270)
			(size 1.6256 1.6256)
			(drill 1.1176)
			(layers "*.Cu" "*.Mask")
			(remove_unused_layers no)
			(net "P12V")
			(clearance 0)
		)
		(pad "8" thru_hole circle
			(at 0 17.78 270)
			(size 1.6256 1.6256)
			(drill 1.1176)
			(layers "*.Cu" "*.Mask")
			(remove_unused_layers no)
			(net "P12V")
			(clearance 0)
		)
		(pad "9" thru_hole circle
			(at 0 20.32 270)
			(size 1.6256 1.6256)
			(drill 1.1176)
			(layers "*.Cu" "*.Mask")
			(remove_unused_layers no)
			(net "P12V")
			(clearance 0)
		)
		(pad "10" thru_hole circle
			(at 0 22.86 270)
			(size 1.6256 1.6256)
			(drill 1.1176)
			(layers "*.Cu" "*.Mask")
			(remove_unused_layers no)
			(net "P12V")
			(clearance 0)
		)
		(pad "11" thru_hole circle
			(at 0 25.4 270)
			(size 1.6256 1.6256)
			(drill 1.1176)
			(layers "*.Cu" "*.Mask")
			(remove_unused_layers no)
			(net "P12V")
			(clearance 0)
		)
		(pad "12" thru_hole circle
			(at 0 27.94 270)
			(size 1.6256 1.6256)
			(drill 1.1176)
			(layers "*.Cu" "*.Mask")
			(remove_unused_layers no)
			(net "P12V")
			(clearance 0)
		)
		(pad "13" thru_hole circle
			(at 0 30.48 270)
			(size 1.6256 1.6256)
			(drill 1.1176)
			(layers "*.Cu" "*.Mask")
			(remove_unused_layers no)
			(net "GND")
			(clearance 0)
		)
		(pad "14" thru_hole circle
			(at 0 33.02 270)
			(size 1.6256 1.6256)
			(drill 1.1176)
			(layers "*.Cu" "*.Mask")
			(remove_unused_layers no)
			(net "GND")
			(clearance 0)
		)
		(pad "15" thru_hole circle
			(at 0 35.56 270)
			(size 1.6256 1.6256)
			(drill 1.1176)
			(layers "*.Cu" "*.Mask")
			(remove_unused_layers no)
			(net "GND")
			(clearance 0)
		)
		(pad "16" thru_hole circle
			(at 0 38.1 270)
			(size 1.6256 1.6256)
			(drill 1.1176)
			(layers "*.Cu" "*.Mask")
			(remove_unused_layers no)
			(net "GND")
			(clearance 0)
		)
		(pad "17" thru_hole circle
			(at 0 40.64 270)
			(size 1.6256 1.6256)
			(drill 1.1176)
			(layers "*.Cu" "*.Mask")
			(remove_unused_layers no)
			(net "GND")
			(clearance 0)
		)
		(pad "18" thru_hole circle
			(at 0 43.18 270)
			(size 1.6256 1.6256)
			(drill 1.1176)
			(layers "*.Cu" "*.Mask")
			(remove_unused_layers no)
			(net "GND")
			(clearance 0)
		)
		(pad "19" thru_hole circle
			(at 0 45.72 270)
			(size 1.6256 1.6256)
			(drill 1.1176)
			(layers "*.Cu" "*.Mask")
			(remove_unused_layers no)
			(net "GND")
			(clearance 0)
		)
		(pad "20" thru_hole circle
			(at 0 48.26 270)
			(size 1.6256 1.6256)
			(drill 1.1176)
			(layers "*.Cu" "*.Mask")
			(remove_unused_layers no)
			(net "GND")
			(clearance 0)
		)
		(pad "21" thru_hole circle
			(at 0 50.8 270)
			(size 1.6256 1.6256)
			(drill 1.1176)
			(layers "*.Cu" "*.Mask")
			(remove_unused_layers no)
			(net "GND")
			(clearance 0)
		)
		(pad "22" thru_hole circle
			(at 0 53.34 270)
			(size 1.6256 1.6256)
			(drill 1.1176)
			(layers "*.Cu" "*.Mask")
			(remove_unused_layers no)
			(net "GND")
			(clearance 0)
		)
		(pad "23" thru_hole circle
			(at 0 55.88 270)
			(size 1.6256 1.6256)
			(drill 1.1176)
			(layers "*.Cu" "*.Mask")
			(remove_unused_layers no)
			(net "GND")
			(clearance 0)
		)
		(pad "24" thru_hole circle
			(at 0 58.42 270)
			(size 1.6256 1.6256)
			(drill 1.1176)
			(layers "*.Cu" "*.Mask")
			(remove_unused_layers no)
			(net "GND")
			(clearance 0)
		)
		(pad "25" thru_hole circle
			(at 0 60.96 270)
			(size 1.6256 1.6256)
			(drill 1.1176)
			(layers "*.Cu" "*.Mask")
			(remove_unused_layers no)
			(net "Net_399")
			(clearance 0)
		)
		(pad "26" thru_hole circle
			(at 0 63.5 270)
			(size 1.6256 1.6256)
			(drill 1.1176)
			(layers "*.Cu" "*.Mask")
			(remove_unused_layers no)
			(net "PSU5_REMOTE_N")
			(clearance 0)
		)
		(pad "27" thru_hole circle
			(at 0 66.04 270)
			(size 1.6256 1.6256)
			(drill 1.1176)
			(layers "*.Cu" "*.Mask")
			(remove_unused_layers no)
			(net "PSU5_AC_OK")
			(clearance 0)
		)
		(pad "28" thru_hole circle
			(at 0 68.58 270)
			(size 1.6256 1.6256)
			(drill 1.1176)
			(layers "*.Cu" "*.Mask")
			(remove_unused_layers no)
			(net "PSU5_CSAHRE")
			(clearance 0)
		)
		(pad "29" thru_hole circle
			(at 0 71.12 270)
			(size 1.6256 1.6256)
			(drill 1.1176)
			(layers "*.Cu" "*.Mask")
			(remove_unused_layers no)
			(net "PSU5_PS_ON_N")
			(clearance 0)
		)
		(pad "30" thru_hole circle
			(at 0 73.66 270)
			(size 1.6256 1.6256)
			(drill 1.1176)
			(layers "*.Cu" "*.Mask")
			(remove_unused_layers no)
			(net "PSU5_PS_KILL")
			(clearance 0)
		)
		(pad "31" thru_hole circle
			(at 0 76.2 270)
			(size 1.6256 1.6256)
			(drill 1.1176)
			(layers "*.Cu" "*.Mask")
			(remove_unused_layers no)
			(net "PSU5_RESET")
			(clearance 0)
		)
		(pad "32" thru_hole circle
			(at 0 78.74 270)
			(size 1.6256 1.6256)
			(drill 1.1176)
			(layers "*.Cu" "*.Mask")
			(remove_unused_layers no)
			(net "PSU_ALERT_N")
			(clearance 0)
		)
		(pad "33" thru_hole circle
			(at 5.08 78.74 270)
			(size 1.6256 1.6256)
			(drill 1.1176)
			(layers "*.Cu" "*.Mask")
			(remove_unused_layers no)
			(net "I2C_PSU3_SDA")
			(clearance 0)
		)
		(pad "34" thru_hole circle
			(at 5.08 76.2 270)
			(size 1.6256 1.6256)
			(drill 1.1176)
			(layers "*.Cu" "*.Mask")
			(remove_unused_layers no)
			(net "Net_400")
			(clearance 0)
		)
		(pad "35" thru_hole circle
			(at 5.08 73.66 270)
			(size 1.6256 1.6256)
			(drill 1.1176)
			(layers "*.Cu" "*.Mask")
			(remove_unused_layers no)
			(net "I2C_PSU3_SCL")
			(clearance 0)
		)
		(pad "36" thru_hole circle
			(at 5.08 71.12 270)
			(size 1.6256 1.6256)
			(drill 1.1176)
			(layers "*.Cu" "*.Mask")
			(remove_unused_layers no)
			(net "PSU5_RETURN")
			(clearance 0)
		)
		(pad "37" thru_hole circle
			(at 5.08 68.58 270)
			(size 1.6256 1.6256)
			(drill 1.1176)
			(layers "*.Cu" "*.Mask")
			(remove_unused_layers no)
			(net "PSU5_DC_OK")
			(clearance 0)
		)
		(pad "38" thru_hole circle
			(at 5.08 66.04 270)
			(size 1.6256 1.6256)
			(drill 1.1176)
			(layers "*.Cu" "*.Mask")
			(remove_unused_layers no)
			(net "PSU5_AD0")
			(clearance 0)
		)
		(pad "39" thru_hole circle
			(at 5.08 63.5 270)
			(size 1.6256 1.6256)
			(drill 1.1176)
			(layers "*.Cu" "*.Mask")
			(remove_unused_layers no)
			(net "P12V_STBY")
			(clearance 0)
		)
		(pad "40" thru_hole circle
			(at 5.08 60.96 270)
			(size 1.6256 1.6256)
			(drill 1.1176)
			(layers "*.Cu" "*.Mask")
			(remove_unused_layers no)
			(net "PSU5_REMOTE_P")
			(clearance 0)
		)
		(pad "41" thru_hole circle
			(at 5.08 58.42 270)
			(size 1.6256 1.6256)
			(drill 1.1176)
			(layers "*.Cu" "*.Mask")
			(remove_unused_layers no)
			(net "GND")
			(clearance 0)
		)
		(pad "42" thru_hole circle
			(at 5.08 55.88 270)
			(size 1.6256 1.6256)
			(drill 1.1176)
			(layers "*.Cu" "*.Mask")
			(remove_unused_layers no)
			(net "GND")
			(clearance 0)
		)
		(pad "43" thru_hole circle
			(at 5.08 53.34 270)
			(size 1.6256 1.6256)
			(drill 1.1176)
			(layers "*.Cu" "*.Mask")
			(remove_unused_layers no)
			(net "GND")
			(clearance 0)
		)
		(pad "44" thru_hole circle
			(at 5.08 50.8 270)
			(size 1.6256 1.6256)
			(drill 1.1176)
			(layers "*.Cu" "*.Mask")
			(remove_unused_layers no)
			(net "GND")
			(clearance 0)
		)
		(pad "45" thru_hole circle
			(at 5.08 48.26 270)
			(size 1.6256 1.6256)
			(drill 1.1176)
			(layers "*.Cu" "*.Mask")
			(remove_unused_layers no)
			(net "GND")
			(clearance 0)
		)
		(pad "46" thru_hole circle
			(at 5.08 45.72 270)
			(size 1.6256 1.6256)
			(drill 1.1176)
			(layers "*.Cu" "*.Mask")
			(remove_unused_layers no)
			(net "GND")
			(clearance 0)
		)
		(pad "47" thru_hole circle
			(at 5.08 43.18 270)
			(size 1.6256 1.6256)
			(drill 1.1176)
			(layers "*.Cu" "*.Mask")
			(remove_unused_layers no)
			(net "GND")
			(clearance 0)
		)
		(pad "48" thru_hole circle
			(at 5.08 40.64 270)
			(size 1.6256 1.6256)
			(drill 1.1176)
			(layers "*.Cu" "*.Mask")
			(remove_unused_layers no)
			(net "GND")
			(clearance 0)
		)
		(pad "49" thru_hole circle
			(at 5.08 38.1 270)
			(size 1.6256 1.6256)
			(drill 1.1176)
			(layers "*.Cu" "*.Mask")
			(remove_unused_layers no)
			(net "GND")
			(clearance 0)
		)
		(pad "50" thru_hole circle
			(at 5.08 35.56 270)
			(size 1.6256 1.6256)
			(drill 1.1176)
			(layers "*.Cu" "*.Mask")
			(remove_unused_layers no)
			(net "GND")
			(clearance 0)
		)
		(pad "51" thru_hole circle
			(at 5.08 33.02 270)
			(size 1.6256 1.6256)
			(drill 1.1176)
			(layers "*.Cu" "*.Mask")
			(remove_unused_layers no)
			(net "GND")
			(clearance 0)
		)
		(pad "52" thru_hole circle
			(at 5.08 30.48 270)
			(size 1.6256 1.6256)
			(drill 1.1176)
			(layers "*.Cu" "*.Mask")
			(remove_unused_layers no)
			(net "GND")
			(clearance 0)
		)
		(pad "53" thru_hole circle
			(at 5.08 27.94 270)
			(size 1.6256 1.6256)
			(drill 1.1176)
			(layers "*.Cu" "*.Mask")
			(remove_unused_layers no)
			(net "P12V")
			(clearance 0)
		)
		(pad "54" thru_hole circle
			(at 5.08 25.4 270)
			(size 1.6256 1.6256)
			(drill 1.1176)
			(layers "*.Cu" "*.Mask")
			(remove_unused_layers no)
			(net "P12V")
			(clearance 0)
		)
		(pad "55" thru_hole circle
			(at 5.08 22.86 270)
			(size 1.6256 1.6256)
			(drill 1.1176)
			(layers "*.Cu" "*.Mask")
			(remove_unused_layers no)
			(net "P12V")
			(clearance 0)
		)
		(pad "56" thru_hole circle
			(at 5.08 20.32 270)
			(size 1.6256 1.6256)
			(drill 1.1176)
			(layers "*.Cu" "*.Mask")
			(remove_unused_layers no)
			(net "P12V")
			(clearance 0)
		)
		(pad "57" thru_hole circle
			(at 5.08 17.78 270)
			(size 1.6256 1.6256)
			(drill 1.1176)
			(layers "*.Cu" "*.Mask")
			(remove_unused_layers no)
			(net "P12V")
			(clearance 0)
		)
		(pad "58" thru_hole circle
			(at 5.08 15.24 270)
			(size 1.6256 1.6256)
			(drill 1.1176)
			(layers "*.Cu" "*.Mask")
			(remove_unused_layers no)
			(net "P12V")
			(clearance 0)
		)
		(pad "59" thru_hole circle
			(at 5.08 12.7 270)
			(size 1.6256 1.6256)
			(drill 1.1176)
			(layers "*.Cu" "*.Mask")
			(remove_unused_layers no)
			(net "P12V")
			(clearance 0)
		)
		(pad "60" thru_hole circle
			(at 5.08 10.16 270)
			(size 1.6256 1.6256)
			(drill 1.1176)
			(layers "*.Cu" "*.Mask")
			(remove_unused_layers no)
			(net "P12V")
			(clearance 0)
		)
		(pad "61" thru_hole circle
			(at 5.08 7.62 270)
			(size 1.6256 1.6256)
			(drill 1.1176)
			(layers "*.Cu" "*.Mask")
			(remove_unused_layers no)
			(net "P12V")
			(clearance 0)
		)
		(pad "62" thru_hole circle
			(at 5.08 5.08 270)
			(size 1.6256 1.6256)
			(drill 1.1176)
			(layers "*.Cu" "*.Mask")
			(remove_unused_layers no)
			(net "P12V")
			(clearance 0)
		)
		(pad "63" thru_hole circle
			(at 5.08 2.54 270)
			(size 1.6256 1.6256)
			(drill 1.1176)
			(layers "*.Cu" "*.Mask")
			(remove_unused_layers no)
			(net "P12V")
			(clearance 0)
		)
		(pad "64" thru_hole circle
			(at 5.08 0 270)
			(size 1.6256 1.6256)
			(drill 1.1176)
			(layers "*.Cu" "*.Mask")
			(remove_unused_layers no)
			(net "P12V")
			(clearance 0)
		)
	)
	(footprint ""
		(layer "F.Cu")
		(at 14.923008 -330.497434 -90)
		(property "Reference" "R35"
			(at 3.685032 -0.234188 90)
			(unlocked yes)
			(layer "F.SilkS")
			(effects
				(font
					(size 0.7874 0.5842)
					(thickness 0.1524)
				)
				(justify left)
			)
		)
		(property "Value" ""
			(at 0 0 270)
			(layer "F.Fab")
			(effects
				(font
					(size 1.27 1.27)
				)
			)
		)
		(duplicate_pad_numbers_are_jumpers no)
		(fp_line
			(start -0.7874 0.4064)
			(end -0.7874 -0.4064)
			(stroke
				(width 0.1524)
				(type default)
			)
			(layer "F.SilkS")
		)
		(fp_line
			(start 0.7874 0.4064)
			(end -0.7874 0.4064)
			(stroke
				(width 0.1524)
				(type default)
			)
			(layer "F.SilkS")
		)
		(fp_line
			(start -0.7874 -0.4064)
			(end 0.7874 -0.4064)
			(stroke
				(width 0.1524)
				(type default)
			)
			(layer "F.SilkS")
		)
		(fp_line
			(start 0.7874 -0.4064)
			(end 0.7874 0.4064)
			(stroke
				(width 0.1524)
				(type default)
			)
			(layer "F.SilkS")
		)
		(fp_poly
			(pts
				(xy -0.508 0.2794) (xy -0.508 0.2286) (xy -0.635 0.2286) (xy -0.635 -0.254) (xy -0.5334 -0.254)
				(xy -0.5334 -0.2794) (xy 0.5334 -0.2794) (xy 0.5334 -0.254) (xy 0.635 -0.254) (xy 0.635 0.254) (xy 0.5334 0.254)
				(xy 0.5334 0.2794)
			)
			(stroke
				(width 0)
				(type default)
			)
			(fill no)
			(layer "F.CrtYd")
		)
		(pad "1" smd rect
			(at 0.40005 0 270)
			(size 0.4572 0.508)
			(layers "F.Cu" "F.Mask" "F.Paste")
			(net "P3V3")
		)
		(pad "2" smd rect
			(at -0.40005 0 270)
			(size 0.4572 0.508)
			(layers "F.Cu" "F.Mask" "F.Paste")
			(net "FRU_A1")
		)
	)
	(footprint ""
		(layer "F.Cu")
		(at 71.392796 -87.145368 90)
		(property "Reference" "C21"
			(at -4.3307 -0.164846 90)
			(unlocked yes)
			(layer "F.SilkS")
			(effects
				(font
					(size 0.7874 0.5842)
					(thickness 0.1524)
				)
				(justify left)
			)
		)
		(property "Value" ""
			(at 0 0 90)
			(layer "F.Fab")
			(effects
				(font
					(size 1.27 1.27)
				)
			)
		)
		(duplicate_pad_numbers_are_jumpers no)
		(fp_line
			(start 0.7874 -0.4064)
			(end 0.7874 0.4064)
			(stroke
				(width 0.1524)
				(type default)
			)
			(layer "F.SilkS")
		)
		(fp_line
			(start -0.7874 -0.4064)
			(end 0.7874 -0.4064)
			(stroke
				(width 0.1524)
				(type default)
			)
			(layer "F.SilkS")
		)
		(fp_line
			(start 0 0.381)
			(end 0 -0.381)
			(stroke
				(width 0.1524)
				(type default)
			)
			(layer "F.SilkS")
		)
		(fp_line
			(start 0.7874 0.4064)
			(end -0.7874 0.4064)
			(stroke
				(width 0.1524)
				(type default)
			)
			(layer "F.SilkS")
		)
		(fp_line
			(start -0.7874 0.4064)
			(end -0.7874 -0.4064)
			(stroke
				(width 0.1524)
				(type default)
			)
			(layer "F.SilkS")
		)
		(fp_poly
			(pts
				(xy -0.5334 0.254) (xy -0.635 0.254) (xy -0.635 0.2286) (xy -0.635 -0.254) (xy -0.5334 -0.254) (xy -0.5334 -0.2794)
				(xy 0.5334 -0.2794) (xy 0.5334 -0.254) (xy 0.635 -0.254) (xy 0.635 0.254) (xy 0.5334 0.254) (xy 0.5334 0.2794)
				(xy -0.508 0.2794) (xy -0.5334 0.2794)
			)
			(stroke
				(width 0)
				(type default)
			)
			(fill no)
			(layer "F.CrtYd")
		)
		(pad "1" smd rect
			(at 0.40005 0 90)
			(size 0.4572 0.508)
			(layers "F.Cu" "F.Mask" "F.Paste")
			(net "P12V")
		)
		(pad "2" smd rect
			(at -0.40005 0 90)
			(size 0.4572 0.508)
			(layers "F.Cu" "F.Mask" "F.Paste")
			(net "GND")
		)
	)
	(footprint ""
		(layer "F.Cu")
		(at 50.350928 -306.383182 180)
		(property "Reference" "CE14"
			(at 8.029448 2.021078 0)
			(unlocked yes)
			(layer "F.SilkS")
			(effects
				(font
					(size 0.7874 0.5842)
					(thickness 0.1524)
				)
				(justify left)
			)
		)
		(property "Value" ""
			(at 0 0 180)
			(layer "F.Fab")
			(effects
				(font
					(size 1.27 1.27)
				)
			)
		)
		(duplicate_pad_numbers_are_jumpers no)
		(fp_line
			(start 0 -4.2672)
			(end 0 4.2672)
			(stroke
				(width 0.1524)
				(type default)
			)
			(layer "F.SilkS")
		)
		(fp_circle
			(center 0 0)
			(end -4.2672 0)
			(stroke
				(width 0.1524)
				(type default)
			)
			(fill no)
			(layer "F.SilkS")
		)
		(fp_poly
			(pts
				(arc
					(start 0 -4.2672)
					(mid 4.2672 0)
					(end 0 4.2672)
				)
			)
			(stroke
				(width 0)
				(type default)
			)
			(fill yes)
			(layer "F.SilkS")
		)
		(fp_poly
			(pts
				(xy -2.5146 -0.762) (xy -0.9906 -0.762) (xy -0.9906 0.762) (xy -2.5146 0.762)
			)
			(stroke
				(width 0)
				(type default)
			)
			(fill no)
			(layer "B.CrtYd")
		)
		(fp_poly
			(pts
				(arc
					(start 1.7526 0.762)
					(mid 2.291415 -0.538815)
					(end 0.9906 0)
				)
				(arc
					(start 0.9906 0.0254)
					(mid 1.206345 0.546255)
					(end 1.7272 0.762)
				)
			)
			(stroke
				(width 0)
				(type default)
			)
			(fill no)
			(layer "B.CrtYd")
		)
		(fp_poly
			(pts
				(arc
					(start -4.2672 0)
					(mid 4.2672 0)
					(end -4.2672 0)
				)
			)
			(stroke
				(width 0)
				(type default)
			)
			(fill no)
			(layer "F.CrtYd")
		)
		(fp_circle
			(center 0 0)
			(end -4.2672 0)
			(stroke
				(width 0.1)
				(type default)
			)
			(fill no)
			(layer "F.Fab")
		)
		(fp_text user "+"
			(at -5.6642 0.15367 180)
			(unlocked yes)
			(layer "F.SilkS")
			(effects
				(font
					(size 0.7874 0.5842)
					(thickness 0.1524)
				)
				(justify left)
			)
		)
		(fp_text user "+"
			(at -5.6642 -0.34925 180)
			(unlocked yes)
			(layer "F.Fab")
			(effects
				(font
					(size 1.905 1.4224)
					(thickness 0.000001)
				)
				(justify left)
			)
		)
		(pad "1" thru_hole rect
			(at -1.75006 0 180)
			(size 1.397 1.397)
			(drill 0.9144)
			(layers "*.Cu" "*.Mask")
			(remove_unused_layers no)
			(net "P12V")
			(clearance 0.0127)
			(thermal_gap 0.0127)
			(padstack
				(mode front_inner_back)
				(layer "Inner"
					(shape circle)
					(size 1.397 1.397)
					(clearance 0.0127)
				)
				(layer "B.Cu"
					(shape rect)
					(size 1.397 1.397)
					(clearance 0.0127)
				)
			)
		)
		(pad "2" thru_hole circle
			(at 1.75006 0 180)
			(size 1.397 1.397)
			(drill 0.9144)
			(layers "*.Cu" "*.Mask")
			(remove_unused_layers no)
			(net "GND")
			(clearance 0.0127)
			(thermal_gap 0.0127)
		)
	)
	(footprint ""
		(layer "F.Cu")
		(at 68.457064 -131.443476 90)
		(property "Reference" "C28"
			(at -3.793744 -0.09398 90)
			(unlocked yes)
			(layer "F.SilkS")
			(effects
				(font
					(size 0.7874 0.5842)
					(thickness 0.1524)
				)
				(justify left)
			)
		)
		(property "Value" ""
			(at 0 0 90)
			(layer "F.Fab")
			(effects
				(font
					(size 1.27 1.27)
				)
			)
		)
		(duplicate_pad_numbers_are_jumpers no)
		(fp_line
			(start 0.7874 -0.4064)
			(end 0.7874 0.4064)
			(stroke
				(width 0.1524)
				(type default)
			)
			(layer "F.SilkS")
		)
		(fp_line
			(start -0.7874 -0.4064)
			(end 0.7874 -0.4064)
			(stroke
				(width 0.1524)
				(type default)
			)
			(layer "F.SilkS")
		)
		(fp_line
			(start 0 0.381)
			(end 0 -0.381)
			(stroke
				(width 0.1524)
				(type default)
			)
			(layer "F.SilkS")
		)
		(fp_line
			(start 0.7874 0.4064)
			(end -0.7874 0.4064)
			(stroke
				(width 0.1524)
				(type default)
			)
			(layer "F.SilkS")
		)
		(fp_line
			(start -0.7874 0.4064)
			(end -0.7874 -0.4064)
			(stroke
				(width 0.1524)
				(type default)
			)
			(layer "F.SilkS")
		)
		(fp_poly
			(pts
				(xy -0.5334 0.254) (xy -0.635 0.254) (xy -0.635 0.2286) (xy -0.635 -0.254) (xy -0.5334 -0.254) (xy -0.5334 -0.2794)
				(xy 0.5334 -0.2794) (xy 0.5334 -0.254) (xy 0.635 -0.254) (xy 0.635 0.254) (xy 0.5334 0.254) (xy 0.5334 0.2794)
				(xy -0.508 0.2794) (xy -0.5334 0.2794)
			)
			(stroke
				(width 0)
				(type default)
			)
			(fill no)
			(layer "F.CrtYd")
		)
		(pad "1" smd rect
			(at 0.40005 0 90)
			(size 0.4572 0.508)
			(layers "F.Cu" "F.Mask" "F.Paste")
			(net "P12V")
		)
		(pad "2" smd rect
			(at -0.40005 0 90)
			(size 0.4572 0.508)
			(layers "F.Cu" "F.Mask" "F.Paste")
			(net "GND")
		)
	)
	(footprint ""
		(layer "F.Cu")
		(at 27.28468 -4.025138)
		(property "Reference" "R65"
			(at -1.676146 2.569972 0)
			(unlocked yes)
			(layer "F.SilkS")
			(effects
				(font
					(size 0.7874 0.5842)
					(thickness 0.1524)
				)
				(justify left)
			)
		)
		(property "Value" ""
			(at 0 0 0)
			(layer "F.Fab")
			(effects
				(font
					(size 1.27 1.27)
				)
			)
		)
		(duplicate_pad_numbers_are_jumpers no)
		(fp_line
			(start -0.7874 -0.4064)
			(end 0.7874 -0.4064)
			(stroke
				(width 0.1524)
				(type default)
			)
			(layer "F.SilkS")
		)
		(fp_line
			(start -0.7874 0.4064)
			(end -0.7874 -0.4064)
			(stroke
				(width 0.1524)
				(type default)
			)
			(layer "F.SilkS")
		)
		(fp_line
			(start 0.7874 -0.4064)
			(end 0.7874 0.4064)
			(stroke
				(width 0.1524)
				(type default)
			)
			(layer "F.SilkS")
		)
		(fp_line
			(start 0.7874 0.4064)
			(end -0.7874 0.4064)
			(stroke
				(width 0.1524)
				(type default)
			)
			(layer "F.SilkS")
		)
		(fp_poly
			(pts
				(xy -0.508 0.2794) (xy -0.508 0.2286) (xy -0.635 0.2286) (xy -0.635 -0.254) (xy -0.5334 -0.254)
				(xy -0.5334 -0.2794) (xy 0.5334 -0.2794) (xy 0.5334 -0.254) (xy 0.635 -0.254) (xy 0.635 0.254) (xy 0.5334 0.254)
				(xy 0.5334 0.2794)
			)
			(stroke
				(width 0)
				(type default)
			)
			(fill no)
			(layer "F.CrtYd")
		)
		(pad "1" smd rect
			(at 0.40005 0)
			(size 0.4572 0.508)
			(layers "F.Cu" "F.Mask" "F.Paste")
			(net "PSU1_RESET")
		)
		(pad "2" smd rect
			(at -0.40005 0)
			(size 0.4572 0.508)
			(layers "F.Cu" "F.Mask" "F.Paste")
			(net "GND")
		)
	)
	(footprint ""
		(layer "F.Cu")
		(at 2.439924 -159.325056 90)
		(property "Reference" "J30"
			(at -1.364488 4.743704 90)
			(unlocked yes)
			(layer "F.SilkS")
			(effects
				(font
					(size 0.7874 0.5842)
					(thickness 0.1524)
				)
				(justify left)
			)
		)
		(property "Value" ""
			(at 0 0 90)
			(layer "F.Fab")
			(effects
				(font
					(size 1.27 1.27)
				)
			)
		)
		(duplicate_pad_numbers_are_jumpers no)
		(fp_line
			(start 1.849882 -1.999996)
			(end -3.02006 -1.999996)
			(stroke
				(width 0.1524)
				(type default)
			)
			(layer "F.SilkS")
		)
		(fp_line
			(start -3.02006 -1.999996)
			(end -3.02006 3.999992)
			(stroke
				(width 0.1524)
				(type default)
			)
			(layer "F.SilkS")
		)
		(fp_line
			(start 1.35001 -1.500124)
			(end -2.519934 -1.500124)
			(stroke
				(width 0.1524)
				(type default)
			)
			(layer "F.SilkS")
		)
		(fp_line
			(start -2.519934 -1.500124)
			(end -2.519934 3.50012)
			(stroke
				(width 0.1524)
				(type default)
			)
			(layer "F.SilkS")
		)
		(fp_line
			(start 1.849882 0.500126)
			(end 1.35001 0.500126)
			(stroke
				(width 0.1524)
				(type default)
			)
			(layer "F.SilkS")
		)
		(fp_line
			(start 1.35001 0.500126)
			(end 1.35001 -1.500124)
			(stroke
				(width 0.1524)
				(type default)
			)
			(layer "F.SilkS")
		)
		(fp_line
			(start 1.35001 1.500124)
			(end 1.849882 1.500124)
			(stroke
				(width 0.1524)
				(type default)
			)
			(layer "F.SilkS")
		)
		(fp_line
			(start 1.35001 3.50012)
			(end 1.35001 1.500124)
			(stroke
				(width 0.1524)
				(type default)
			)
			(layer "F.SilkS")
		)
		(fp_line
			(start -2.519934 3.50012)
			(end 1.35001 3.50012)
			(stroke
				(width 0.1524)
				(type default)
			)
			(layer "F.SilkS")
		)
		(fp_line
			(start 1.849882 3.999992)
			(end 1.849882 -1.999996)
			(stroke
				(width 0.1524)
				(type default)
			)
			(layer "F.SilkS")
		)
		(fp_line
			(start -3.02006 3.999992)
			(end 1.849882 3.999992)
			(stroke
				(width 0.1524)
				(type default)
			)
			(layer "F.SilkS")
		)
		(fp_poly
			(pts
				(xy 2.01041 0) (xy 3.06959 -0.52959) (xy 3.06959 0.52959)
			)
			(stroke
				(width 0)
				(type default)
			)
			(fill yes)
			(layer "F.SilkS")
		)
		(fp_poly
			(pts
				(xy -0.8382 2.8194) (xy 0.8382 2.8194) (xy 0.8382 -0.8382) (xy -0.8382 -0.8382)
			)
			(stroke
				(width 0)
				(type default)
			)
			(fill no)
			(layer "B.CrtYd")
		)
		(fp_poly
			(pts
				(xy -3.02006 3.999992) (xy 1.849882 3.999992) (xy 1.849882 -1.999996) (xy -3.02006 -1.999996)
			)
			(stroke
				(width 0)
				(type default)
			)
			(fill no)
			(layer "F.CrtYd")
		)
		(fp_line
			(start 1.849882 -1.999996)
			(end -3.02006 -1.999996)
			(stroke
				(width 0.1)
				(type default)
			)
			(layer "F.Fab")
		)
		(fp_line
			(start -3.02006 -1.999996)
			(end -3.02006 3.999992)
			(stroke
				(width 0.1)
				(type default)
			)
			(layer "F.Fab")
		)
		(fp_line
			(start 1.849882 3.999992)
			(end 1.849882 -1.999996)
			(stroke
				(width 0.1)
				(type default)
			)
			(layer "F.Fab")
		)
		(fp_line
			(start -3.02006 3.999992)
			(end 1.849882 3.999992)
			(stroke
				(width 0.1)
				(type default)
			)
			(layer "F.Fab")
		)
		(fp_poly
			(pts
				(xy 2.01041 0) (xy 3.06959 -0.52959) (xy 3.06959 0.52959)
			)
			(stroke
				(width 0)
				(type default)
			)
			(fill yes)
			(layer "F.Fab")
		)
		(fp_text user "2"
			(at 2.5527 2.16535 90)
			(unlocked yes)
			(layer "F.SilkS")
			(effects
				(font
					(size 0.7874 0.5842)
					(thickness 0.1524)
				)
			)
		)
		(fp_text user "1"
			(at 1.2192 0.00127 90)
			(unlocked yes)
			(layer "B.SilkS")
			(effects
				(font
					(size 0.7874 0.5842)
					(thickness 0.1524)
				)
				(justify mirror)
			)
		)
		(fp_text user "2"
			(at 1.2192 2.001266 90)
			(unlocked yes)
			(layer "B.SilkS")
			(effects
				(font
					(size 0.7874 0.5842)
					(thickness 0.1524)
				)
				(justify mirror)
			)
		)
		(fp_text user "1"
			(at 1.2192 0.00127 90)
			(unlocked yes)
			(layer "B.Fab")
			(effects
				(font
					(size 0.7874 0.5842)
					(thickness 0.1524)
				)
				(justify mirror)
			)
		)
		(fp_text user "2"
			(at 1.2192 2.001266 90)
			(unlocked yes)
			(layer "B.Fab")
			(effects
				(font
					(size 0.7874 0.5842)
					(thickness 0.1524)
				)
				(justify mirror)
			)
		)
		(fp_text user "2"
			(at 2.5527 2.16535 90)
			(unlocked yes)
			(layer "F.Fab")
			(effects
				(font
					(size 0.7874 0.5842)
					(thickness 0.1524)
				)
			)
		)
		(pad "1" thru_hole rect
			(at 0 0 90)
			(size 1.524 1.524)
			(drill 1.016)
			(layers "*.Cu" "*.Mask")
			(remove_unused_layers no)
			(net "POWER_SW3_PWR_CTR_12V")
			(clearance 0)
			(padstack
				(mode front_inner_back)
				(layer "Inner"
					(shape circle)
					(size 1.524 1.524)
					(clearance 0)
				)
				(layer "B.Cu"
					(shape rect)
					(size 1.524 1.524)
					(clearance 0)
				)
			)
		)
		(pad "2" thru_hole circle
			(at 0 1.999996 90)
			(size 1.524 1.524)
			(drill 1.016)
			(layers "*.Cu" "*.Mask")
			(remove_unused_layers no)
			(net "GND")
			(clearance 0)
		)
	)
	(footprint ""
		(layer "F.Cu")
		(at 73.199752 -282.156154 -90)
		(property "Reference" "C44"
			(at 0.870204 -4.091432 90)
			(unlocked yes)
			(layer "F.SilkS")
			(effects
				(font
					(size 0.7874 0.5842)
					(thickness 0.1524)
				)
				(justify left)
			)
		)
		(property "Value" ""
			(at 0 0 270)
			(layer "F.Fab")
			(effects
				(font
					(size 1.27 1.27)
				)
			)
		)
		(duplicate_pad_numbers_are_jumpers no)
		(fp_line
			(start -0.7874 0.4064)
			(end -0.7874 -0.4064)
			(stroke
				(width 0.1524)
				(type default)
			)
			(layer "F.SilkS")
		)
		(fp_line
			(start 0.7874 0.4064)
			(end -0.7874 0.4064)
			(stroke
				(width 0.1524)
				(type default)
			)
			(layer "F.SilkS")
		)
		(fp_line
			(start 0 0.381)
			(end 0 -0.381)
			(stroke
				(width 0.1524)
				(type default)
			)
			(layer "F.SilkS")
		)
		(fp_line
			(start -0.7874 -0.4064)
			(end 0.7874 -0.4064)
			(stroke
				(width 0.1524)
				(type default)
			)
			(layer "F.SilkS")
		)
		(fp_line
			(start 0.7874 -0.4064)
			(end 0.7874 0.4064)
			(stroke
				(width 0.1524)
				(type default)
			)
			(layer "F.SilkS")
		)
		(fp_poly
			(pts
				(xy -0.5334 0.254) (xy -0.635 0.254) (xy -0.635 0.2286) (xy -0.635 -0.254) (xy -0.5334 -0.254) (xy -0.5334 -0.2794)
				(xy 0.5334 -0.2794) (xy 0.5334 -0.254) (xy 0.635 -0.254) (xy 0.635 0.254) (xy 0.5334 0.254) (xy 0.5334 0.2794)
				(xy -0.508 0.2794) (xy -0.5334 0.2794)
			)
			(stroke
				(width 0)
				(type default)
			)
			(fill no)
			(layer "F.CrtYd")
		)
		(pad "1" smd rect
			(at 0.40005 0 270)
			(size 0.4572 0.508)
			(layers "F.Cu" "F.Mask" "F.Paste")
			(net "P12V")
		)
		(pad "2" smd rect
			(at -0.40005 0 270)
			(size 0.4572 0.508)
			(layers "F.Cu" "F.Mask" "F.Paste")
			(net "GND")
		)
	)
	(footprint ""
		(layer "F.Cu")
		(at 72.157844 -415.986722 -90)
		(property "Reference" "C64"
			(at -3.59029 -0.092202 90)
			(unlocked yes)
			(layer "F.SilkS")
			(effects
				(font
					(size 0.7874 0.5842)
					(thickness 0.1524)
				)
			)
		)
		(property "Value" ""
			(at 0 0 270)
			(layer "F.Fab")
			(effects
				(font
					(size 1.27 1.27)
				)
			)
		)
		(duplicate_pad_numbers_are_jumpers no)
		(fp_line
			(start -1.2954 0.5842)
			(end -1.2954 -0.5842)
			(stroke
				(width 0.1524)
				(type default)
			)
			(layer "F.SilkS")
		)
		(fp_line
			(start 1.2954 0.5842)
			(end -1.2954 0.5842)
			(stroke
				(width 0.1524)
				(type default)
			)
			(layer "F.SilkS")
		)
		(fp_line
			(start -1.2954 -0.5842)
			(end 1.2954 -0.5842)
			(stroke
				(width 0.1524)
				(type default)
			)
			(layer "F.SilkS")
		)
		(fp_line
			(start 0 -0.5842)
			(end 0 0.5842)
			(stroke
				(width 0.1524)
				(type default)
			)
			(layer "F.SilkS")
		)
		(fp_line
			(start 1.2954 -0.5842)
			(end 1.2954 0.5842)
			(stroke
				(width 0.1524)
				(type default)
			)
			(layer "F.SilkS")
		)
		(fp_poly
			(pts
				(xy 0.8636 -0.4572) (xy 0.8636 -0.3556) (xy 1.143 -0.3556) (xy 1.143 0.3556) (xy 0.8636 0.3556)
				(xy 0.8636 0.4572) (xy -0.8636 0.4572) (xy -0.8636 0.3556) (xy -1.143 0.3556) (xy -1.143 -0.3556)
				(xy -0.8636 -0.3556) (xy -0.8636 -0.4572)
			)
			(stroke
				(width 0)
				(type default)
			)
			(fill no)
			(layer "F.CrtYd")
		)
		(fp_line
			(start -0.884936 0.504952)
			(end -0.884936 -0.504952)
			(stroke
				(width 0.1)
				(type default)
			)
			(layer "F.Fab")
		)
		(fp_line
			(start 0.884936 0.504952)
			(end -0.884936 0.504952)
			(stroke
				(width 0.1)
				(type default)
			)
			(layer "F.Fab")
		)
		(fp_line
			(start -0.884936 -0.504952)
			(end 0.884936 -0.504952)
			(stroke
				(width 0.1)
				(type default)
			)
			(layer "F.Fab")
		)
		(fp_line
			(start 0.884936 -0.504952)
			(end 0.884936 0.504952)
			(stroke
				(width 0.1)
				(type default)
			)
			(layer "F.Fab")
		)
		(pad "1" smd rect
			(at 0.7366 0)
			(size 0.7112 0.8128)
			(layers "F.Cu" "F.Mask" "F.Paste")
			(net "P12V")
		)
		(pad "2" smd rect
			(at -0.7366 0)
			(size 0.7112 0.8128)
			(layers "F.Cu" "F.Mask" "F.Paste")
			(net "GND")
		)
	)
	(footprint ""
		(layer "F.Cu")
		(at 72.953626 -472.101672 180)
		(property "Reference" "R132"
			(at 1.12141 -1.136904 0)
			(unlocked yes)
			(layer "F.SilkS")
			(effects
				(font
					(size 0.7874 0.5842)
					(thickness 0.1524)
				)
				(justify left)
			)
		)
		(property "Value" ""
			(at 0 0 180)
			(layer "F.Fab")
			(effects
				(font
					(size 1.27 1.27)
				)
			)
		)
		(duplicate_pad_numbers_are_jumpers no)
		(fp_line
			(start 0.7874 0.4064)
			(end -0.7874 0.4064)
			(stroke
				(width 0.1524)
				(type default)
			)
			(layer "F.SilkS")
		)
		(fp_line
			(start 0.7874 -0.4064)
			(end 0.7874 0.4064)
			(stroke
				(width 0.1524)
				(type default)
			)
			(layer "F.SilkS")
		)
		(fp_line
			(start -0.7874 0.4064)
			(end -0.7874 -0.4064)
			(stroke
				(width 0.1524)
				(type default)
			)
			(layer "F.SilkS")
		)
		(fp_line
			(start -0.7874 -0.4064)
			(end 0.7874 -0.4064)
			(stroke
				(width 0.1524)
				(type default)
			)
			(layer "F.SilkS")
		)
		(fp_poly
			(pts
				(xy -0.508 0.2794) (xy -0.508 0.2286) (xy -0.635 0.2286) (xy -0.635 -0.254) (xy -0.5334 -0.254)
				(xy -0.5334 -0.2794) (xy 0.5334 -0.2794) (xy 0.5334 -0.254) (xy 0.635 -0.254) (xy 0.635 0.254) (xy 0.5334 0.254)
				(xy 0.5334 0.2794)
			)
			(stroke
				(width 0)
				(type default)
			)
			(fill no)
			(layer "F.CrtYd")
		)
		(pad "1" smd rect
			(at 0.40005 0 180)
			(size 0.4572 0.508)
			(layers "F.Cu" "F.Mask" "F.Paste")
			(net "PSU6_REMOTE_R2_N")
		)
		(pad "2" smd rect
			(at -0.40005 0 180)
			(size 0.4572 0.508)
			(layers "F.Cu" "F.Mask" "F.Paste")
			(net "GND")
		)
	)
	(footprint ""
		(layer "F.Cu")
		(at 18.264886 -330.45527 -90)
		(property "Reference" "R36"
			(at 3.685032 -0.234188 90)
			(unlocked yes)
			(layer "F.SilkS")
			(effects
				(font
					(size 0.7874 0.5842)
					(thickness 0.1524)
				)
				(justify left)
			)
		)
		(property "Value" ""
			(at 0 0 270)
			(layer "F.Fab")
			(effects
				(font
					(size 1.27 1.27)
				)
			)
		)
		(duplicate_pad_numbers_are_jumpers no)
		(fp_line
			(start -0.7874 0.4064)
			(end -0.7874 -0.4064)
			(stroke
				(width 0.1524)
				(type default)
			)
			(layer "F.SilkS")
		)
		(fp_line
			(start 0.7874 0.4064)
			(end -0.7874 0.4064)
			(stroke
				(width 0.1524)
				(type default)
			)
			(layer "F.SilkS")
		)
		(fp_line
			(start -0.7874 -0.4064)
			(end 0.7874 -0.4064)
			(stroke
				(width 0.1524)
				(type default)
			)
			(layer "F.SilkS")
		)
		(fp_line
			(start 0.7874 -0.4064)
			(end 0.7874 0.4064)
			(stroke
				(width 0.1524)
				(type default)
			)
			(layer "F.SilkS")
		)
		(fp_poly
			(pts
				(xy -0.508 0.2794) (xy -0.508 0.2286) (xy -0.635 0.2286) (xy -0.635 -0.254) (xy -0.5334 -0.254)
				(xy -0.5334 -0.2794) (xy 0.5334 -0.2794) (xy 0.5334 -0.254) (xy 0.635 -0.254) (xy 0.635 0.254) (xy 0.5334 0.254)
				(xy 0.5334 0.2794)
			)
			(stroke
				(width 0)
				(type default)
			)
			(fill no)
			(layer "F.CrtYd")
		)
		(pad "1" smd rect
			(at 0.40005 0 270)
			(size 0.4572 0.508)
			(layers "F.Cu" "F.Mask" "F.Paste")
			(net "P3V3")
		)
		(pad "2" smd rect
			(at -0.40005 0 270)
			(size 0.4572 0.508)
			(layers "F.Cu" "F.Mask" "F.Paste")
			(net "FRU_A2")
		)
	)
	(footprint ""
		(layer "F.Cu")
		(at 39.85641 -103.52405 180)
		(property "Reference" "R11"
			(at -1.627124 0.025908 0)
			(unlocked yes)
			(layer "F.SilkS")
			(effects
				(font
					(size 0.7874 0.5842)
					(thickness 0.1524)
				)
				(justify left)
			)
		)
		(property "Value" ""
			(at 0 0 180)
			(layer "F.Fab")
			(effects
				(font
					(size 1.27 1.27)
				)
			)
		)
		(duplicate_pad_numbers_are_jumpers no)
		(fp_line
			(start 0.7874 0.4064)
			(end -0.7874 0.4064)
			(stroke
				(width 0.1524)
				(type default)
			)
			(layer "F.SilkS")
		)
		(fp_line
			(start 0.7874 -0.4064)
			(end 0.7874 0.4064)
			(stroke
				(width 0.1524)
				(type default)
			)
			(layer "F.SilkS")
		)
		(fp_line
			(start -0.7874 0.4064)
			(end -0.7874 -0.4064)
			(stroke
				(width 0.1524)
				(type default)
			)
			(layer "F.SilkS")
		)
		(fp_line
			(start -0.7874 -0.4064)
			(end 0.7874 -0.4064)
			(stroke
				(width 0.1524)
				(type default)
			)
			(layer "F.SilkS")
		)
		(fp_poly
			(pts
				(xy -0.508 0.2794) (xy -0.508 0.2286) (xy -0.635 0.2286) (xy -0.635 -0.254) (xy -0.5334 -0.254)
				(xy -0.5334 -0.2794) (xy 0.5334 -0.2794) (xy 0.5334 -0.254) (xy 0.635 -0.254) (xy 0.635 0.254) (xy 0.5334 0.254)
				(xy 0.5334 0.2794)
			)
			(stroke
				(width 0)
				(type default)
			)
			(fill no)
			(layer "F.CrtYd")
		)
		(pad "1" smd rect
			(at 0.40005 0 180)
			(size 0.4572 0.508)
			(layers "F.Cu" "F.Mask" "F.Paste")
			(net "PSU2_RETURN")
		)
		(pad "2" smd rect
			(at -0.40005 0 180)
			(size 0.4572 0.508)
			(layers "F.Cu" "F.Mask" "F.Paste")
			(net "GND")
		)
	)
	(footprint ""
		(layer "F.Cu")
		(at 13.429234 -326.145652 180)
		(property "Reference" "R145"
			(at -1.184148 -0.042164 0)
			(unlocked yes)
			(layer "F.SilkS")
			(effects
				(font
					(size 0.7874 0.5842)
					(thickness 0.1524)
				)
				(justify left)
			)
		)
		(property "Value" ""
			(at 0 0 180)
			(layer "F.Fab")
			(effects
				(font
					(size 1.27 1.27)
				)
			)
		)
		(duplicate_pad_numbers_are_jumpers no)
		(fp_line
			(start 0.7874 0.4064)
			(end -0.7874 0.4064)
			(stroke
				(width 0.1524)
				(type default)
			)
			(layer "F.SilkS")
		)
		(fp_line
			(start 0.7874 -0.4064)
			(end 0.7874 0.4064)
			(stroke
				(width 0.1524)
				(type default)
			)
			(layer "F.SilkS")
		)
		(fp_line
			(start -0.7874 0.4064)
			(end -0.7874 -0.4064)
			(stroke
				(width 0.1524)
				(type default)
			)
			(layer "F.SilkS")
		)
		(fp_line
			(start -0.7874 -0.4064)
			(end 0.7874 -0.4064)
			(stroke
				(width 0.1524)
				(type default)
			)
			(layer "F.SilkS")
		)
		(fp_poly
			(pts
				(xy -0.508 0.2794) (xy -0.508 0.2286) (xy -0.635 0.2286) (xy -0.635 -0.254) (xy -0.5334 -0.254)
				(xy -0.5334 -0.2794) (xy 0.5334 -0.2794) (xy 0.5334 -0.254) (xy 0.635 -0.254) (xy 0.635 0.254) (xy 0.5334 0.254)
				(xy 0.5334 0.2794)
			)
			(stroke
				(width 0)
				(type default)
			)
			(fill no)
			(layer "F.CrtYd")
		)
		(pad "1" smd rect
			(at 0.40005 0 180)
			(size 0.4572 0.508)
			(layers "F.Cu" "F.Mask" "F.Paste")
			(net "FAN4_TACH")
		)
		(pad "2" smd rect
			(at -0.40005 0 180)
			(size 0.4572 0.508)
			(layers "F.Cu" "F.Mask" "F.Paste")
			(net "P12V")
		)
	)
	(footprint ""
		(layer "F.Cu")
		(at 50.083466 -482.70668 180)
		(property "Reference" "CE21"
			(at -4.321048 2.407666 0)
			(unlocked yes)
			(layer "F.SilkS")
			(effects
				(font
					(size 0.7874 0.5842)
					(thickness 0.1524)
				)
				(justify left)
			)
		)
		(property "Value" ""
			(at 0 0 180)
			(layer "F.Fab")
			(effects
				(font
					(size 1.27 1.27)
				)
			)
		)
		(duplicate_pad_numbers_are_jumpers no)
		(fp_line
			(start 0 -4.2672)
			(end 0 4.2672)
			(stroke
				(width 0.1524)
				(type default)
			)
			(layer "F.SilkS")
		)
		(fp_circle
			(center 0 0)
			(end -4.2672 0)
			(stroke
				(width 0.1524)
				(type default)
			)
			(fill no)
			(layer "F.SilkS")
		)
		(fp_poly
			(pts
				(arc
					(start 0 -4.2672)
					(mid 4.2672 0)
					(end 0 4.2672)
				)
			)
			(stroke
				(width 0)
				(type default)
			)
			(fill yes)
			(layer "F.SilkS")
		)
		(fp_poly
			(pts
				(xy -2.5146 -0.762) (xy -0.9906 -0.762) (xy -0.9906 0.762) (xy -2.5146 0.762)
			)
			(stroke
				(width 0)
				(type default)
			)
			(fill no)
			(layer "B.CrtYd")
		)
		(fp_poly
			(pts
				(arc
					(start 1.7526 0.762)
					(mid 2.291415 -0.538815)
					(end 0.9906 0)
				)
				(arc
					(start 0.9906 0.0254)
					(mid 1.206345 0.546255)
					(end 1.7272 0.762)
				)
			)
			(stroke
				(width 0)
				(type default)
			)
			(fill no)
			(layer "B.CrtYd")
		)
		(fp_poly
			(pts
				(arc
					(start -4.2672 0)
					(mid 4.2672 0)
					(end -4.2672 0)
				)
			)
			(stroke
				(width 0)
				(type default)
			)
			(fill no)
			(layer "F.CrtYd")
		)
		(fp_circle
			(center 0 0)
			(end -4.2672 0)
			(stroke
				(width 0.1)
				(type default)
			)
			(fill no)
			(layer "F.Fab")
		)
		(fp_text user "+"
			(at -5.247386 0.635 180)
			(unlocked yes)
			(layer "F.SilkS")
			(effects
				(font
					(size 0.7874 0.5842)
					(thickness 0.1524)
				)
				(justify left)
			)
		)
		(fp_text user "+"
			(at -5.6642 -0.34925 180)
			(unlocked yes)
			(layer "F.Fab")
			(effects
				(font
					(size 1.905 1.4224)
					(thickness 0.000001)
				)
				(justify left)
			)
		)
		(pad "1" thru_hole rect
			(at -1.75006 0 180)
			(size 1.397 1.397)
			(drill 0.9144)
			(layers "*.Cu" "*.Mask")
			(remove_unused_layers no)
			(net "P12V")
			(clearance 0.0127)
			(thermal_gap 0.0127)
			(padstack
				(mode front_inner_back)
				(layer "Inner"
					(shape circle)
					(size 1.397 1.397)
					(clearance 0.0127)
				)
				(layer "B.Cu"
					(shape rect)
					(size 1.397 1.397)
					(clearance 0.0127)
				)
			)
		)
		(pad "2" thru_hole circle
			(at 1.75006 0 180)
			(size 1.397 1.397)
			(drill 0.9144)
			(layers "*.Cu" "*.Mask")
			(remove_unused_layers no)
			(net "GND")
			(clearance 0.0127)
			(thermal_gap 0.0127)
		)
	)
	(footprint ""
		(layer "F.Cu")
		(at 26.25217 -454.646538 180)
		(property "Reference" "R54"
			(at 3.704336 0.165608 0)
			(unlocked yes)
			(layer "F.SilkS")
			(effects
				(font
					(size 0.7874 0.5842)
					(thickness 0.1524)
				)
				(justify left)
			)
		)
		(property "Value" ""
			(at 0 0 180)
			(layer "F.Fab")
			(effects
				(font
					(size 1.27 1.27)
				)
			)
		)
		(duplicate_pad_numbers_are_jumpers no)
		(fp_line
			(start 0.7874 0.4064)
			(end -0.7874 0.4064)
			(stroke
				(width 0.1524)
				(type default)
			)
			(layer "F.SilkS")
		)
		(fp_line
			(start 0.7874 -0.4064)
			(end 0.7874 0.4064)
			(stroke
				(width 0.1524)
				(type default)
			)
			(layer "F.SilkS")
		)
		(fp_line
			(start -0.7874 0.4064)
			(end -0.7874 -0.4064)
			(stroke
				(width 0.1524)
				(type default)
			)
			(layer "F.SilkS")
		)
		(fp_line
			(start -0.7874 -0.4064)
			(end 0.7874 -0.4064)
			(stroke
				(width 0.1524)
				(type default)
			)
			(layer "F.SilkS")
		)
		(fp_poly
			(pts
				(xy -0.508 0.2794) (xy -0.508 0.2286) (xy -0.635 0.2286) (xy -0.635 -0.254) (xy -0.5334 -0.254)
				(xy -0.5334 -0.2794) (xy 0.5334 -0.2794) (xy 0.5334 -0.254) (xy 0.635 -0.254) (xy 0.635 0.254) (xy 0.5334 0.254)
				(xy 0.5334 0.2794)
			)
			(stroke
				(width 0)
				(type default)
			)
			(fill no)
			(layer "F.CrtYd")
		)
		(pad "1" smd rect
			(at 0.40005 0 180)
			(size 0.4572 0.508)
			(layers "F.Cu" "F.Mask" "F.Paste")
			(net "GND")
		)
		(pad "2" smd rect
			(at -0.40005 0 180)
			(size 0.4572 0.508)
			(layers "F.Cu" "F.Mask" "F.Paste")
			(net "PSU6_PS_ON_N")
		)
	)
	(footprint ""
		(layer "F.Cu")
		(at 39.979854 -375.988326 180)
		(property "Reference" "R14"
			(at -2.032762 0.011938 0)
			(unlocked yes)
			(layer "F.SilkS")
			(effects
				(font
					(size 0.7874 0.5842)
					(thickness 0.1524)
				)
				(justify left)
			)
		)
		(property "Value" ""
			(at 0 0 180)
			(layer "F.Fab")
			(effects
				(font
					(size 1.27 1.27)
				)
			)
		)
		(duplicate_pad_numbers_are_jumpers no)
		(fp_line
			(start 0.7874 0.4064)
			(end -0.7874 0.4064)
			(stroke
				(width 0.1524)
				(type default)
			)
			(layer "F.SilkS")
		)
		(fp_line
			(start 0.7874 -0.4064)
			(end 0.7874 0.4064)
			(stroke
				(width 0.1524)
				(type default)
			)
			(layer "F.SilkS")
		)
		(fp_line
			(start -0.7874 0.4064)
			(end -0.7874 -0.4064)
			(stroke
				(width 0.1524)
				(type default)
			)
			(layer "F.SilkS")
		)
		(fp_line
			(start -0.7874 -0.4064)
			(end 0.7874 -0.4064)
			(stroke
				(width 0.1524)
				(type default)
			)
			(layer "F.SilkS")
		)
		(fp_poly
			(pts
				(xy -0.508 0.2794) (xy -0.508 0.2286) (xy -0.635 0.2286) (xy -0.635 -0.254) (xy -0.5334 -0.254)
				(xy -0.5334 -0.2794) (xy 0.5334 -0.2794) (xy 0.5334 -0.254) (xy 0.635 -0.254) (xy 0.635 0.254) (xy 0.5334 0.254)
				(xy 0.5334 0.2794)
			)
			(stroke
				(width 0)
				(type default)
			)
			(fill no)
			(layer "F.CrtYd")
		)
		(pad "1" smd rect
			(at 0.40005 0 180)
			(size 0.4572 0.508)
			(layers "F.Cu" "F.Mask" "F.Paste")
			(net "PSU5_REMOTE_P")
		)
		(pad "2" smd rect
			(at -0.40005 0 180)
			(size 0.4572 0.508)
			(layers "F.Cu" "F.Mask" "F.Paste")
			(net "P12V")
		)
	)
	(footprint ""
		(layer "F.Cu")
		(at 72.478392 -149.621748 -90)
		(property "Reference" "C22"
			(at -3.210052 -0.035814 90)
			(unlocked yes)
			(layer "F.SilkS")
			(effects
				(font
					(size 0.7874 0.5842)
					(thickness 0.1524)
				)
			)
		)
		(property "Value" ""
			(at 0 0 270)
			(layer "F.Fab")
			(effects
				(font
					(size 1.27 1.27)
				)
			)
		)
		(duplicate_pad_numbers_are_jumpers no)
		(fp_line
			(start -1.2954 0.5842)
			(end -1.2954 -0.5842)
			(stroke
				(width 0.1524)
				(type default)
			)
			(layer "F.SilkS")
		)
		(fp_line
			(start 1.2954 0.5842)
			(end -1.2954 0.5842)
			(stroke
				(width 0.1524)
				(type default)
			)
			(layer "F.SilkS")
		)
		(fp_line
			(start -1.2954 -0.5842)
			(end 1.2954 -0.5842)
			(stroke
				(width 0.1524)
				(type default)
			)
			(layer "F.SilkS")
		)
		(fp_line
			(start 0 -0.5842)
			(end 0 0.5842)
			(stroke
				(width 0.1524)
				(type default)
			)
			(layer "F.SilkS")
		)
		(fp_line
			(start 1.2954 -0.5842)
			(end 1.2954 0.5842)
			(stroke
				(width 0.1524)
				(type default)
			)
			(layer "F.SilkS")
		)
		(fp_poly
			(pts
				(xy 0.8636 -0.4572) (xy 0.8636 -0.3556) (xy 1.143 -0.3556) (xy 1.143 0.3556) (xy 0.8636 0.3556)
				(xy 0.8636 0.4572) (xy -0.8636 0.4572) (xy -0.8636 0.3556) (xy -1.143 0.3556) (xy -1.143 -0.3556)
				(xy -0.8636 -0.3556) (xy -0.8636 -0.4572)
			)
			(stroke
				(width 0)
				(type default)
			)
			(fill no)
			(layer "F.CrtYd")
		)
		(fp_line
			(start -0.884936 0.504952)
			(end -0.884936 -0.504952)
			(stroke
				(width 0.1)
				(type default)
			)
			(layer "F.Fab")
		)
		(fp_line
			(start 0.884936 0.504952)
			(end -0.884936 0.504952)
			(stroke
				(width 0.1)
				(type default)
			)
			(layer "F.Fab")
		)
		(fp_line
			(start -0.884936 -0.504952)
			(end 0.884936 -0.504952)
			(stroke
				(width 0.1)
				(type default)
			)
			(layer "F.Fab")
		)
		(fp_line
			(start 0.884936 -0.504952)
			(end 0.884936 0.504952)
			(stroke
				(width 0.1)
				(type default)
			)
			(layer "F.Fab")
		)
		(pad "1" smd rect
			(at 0.7366 0)
			(size 0.7112 0.8128)
			(layers "F.Cu" "F.Mask" "F.Paste")
			(net "P12V")
		)
		(pad "2" smd rect
			(at -0.7366 0)
			(size 0.7112 0.8128)
			(layers "F.Cu" "F.Mask" "F.Paste")
			(net "GND")
		)
	)
	(footprint ""
		(layer "F.Cu")
		(at 25.857708 -363.01553)
		(property "Reference" "R80"
			(at -3.917442 -0.225298 0)
			(unlocked yes)
			(layer "F.SilkS")
			(effects
				(font
					(size 0.7874 0.5842)
					(thickness 0.1524)
				)
				(justify left)
			)
		)
		(property "Value" ""
			(at 0 0 0)
			(layer "F.Fab")
			(effects
				(font
					(size 1.27 1.27)
				)
			)
		)
		(duplicate_pad_numbers_are_jumpers no)
		(fp_line
			(start -0.7874 -0.4064)
			(end 0.7874 -0.4064)
			(stroke
				(width 0.1524)
				(type default)
			)
			(layer "F.SilkS")
		)
		(fp_line
			(start -0.7874 0.4064)
			(end -0.7874 -0.4064)
			(stroke
				(width 0.1524)
				(type default)
			)
			(layer "F.SilkS")
		)
		(fp_line
			(start 0.7874 -0.4064)
			(end 0.7874 0.4064)
			(stroke
				(width 0.1524)
				(type default)
			)
			(layer "F.SilkS")
		)
		(fp_line
			(start 0.7874 0.4064)
			(end -0.7874 0.4064)
			(stroke
				(width 0.1524)
				(type default)
			)
			(layer "F.SilkS")
		)
		(fp_poly
			(pts
				(xy -0.508 0.2794) (xy -0.508 0.2286) (xy -0.635 0.2286) (xy -0.635 -0.254) (xy -0.5334 -0.254)
				(xy -0.5334 -0.2794) (xy 0.5334 -0.2794) (xy 0.5334 -0.254) (xy 0.635 -0.254) (xy 0.635 0.254) (xy 0.5334 0.254)
				(xy 0.5334 0.2794)
			)
			(stroke
				(width 0)
				(type default)
			)
			(fill no)
			(layer "F.CrtYd")
		)
		(pad "1" smd rect
			(at 0.40005 0)
			(size 0.4572 0.508)
			(layers "F.Cu" "F.Mask" "F.Paste")
			(net "PSU5_RESET")
		)
		(pad "2" smd rect
			(at -0.40005 0)
			(size 0.4572 0.508)
			(layers "F.Cu" "F.Mask" "F.Paste")
			(net "P12V_STBY")
		)
	)
	(footprint ""
		(layer "F.Cu")
		(at 39.653718 -283.096208 -90)
		(property "Reference" "R16"
			(at 0.95885 -2.95783 90)
			(unlocked yes)
			(layer "F.SilkS")
			(effects
				(font
					(size 0.7874 0.5842)
					(thickness 0.1524)
				)
				(justify left)
			)
		)
		(property "Value" ""
			(at 0 0 270)
			(layer "F.Fab")
			(effects
				(font
					(size 1.27 1.27)
				)
			)
		)
		(duplicate_pad_numbers_are_jumpers no)
		(fp_line
			(start -0.7874 0.4064)
			(end -0.7874 -0.4064)
			(stroke
				(width 0.1524)
				(type default)
			)
			(layer "F.SilkS")
		)
		(fp_line
			(start 0.7874 0.4064)
			(end -0.7874 0.4064)
			(stroke
				(width 0.1524)
				(type default)
			)
			(layer "F.SilkS")
		)
		(fp_line
			(start -0.7874 -0.4064)
			(end 0.7874 -0.4064)
			(stroke
				(width 0.1524)
				(type default)
			)
			(layer "F.SilkS")
		)
		(fp_line
			(start 0.7874 -0.4064)
			(end 0.7874 0.4064)
			(stroke
				(width 0.1524)
				(type default)
			)
			(layer "F.SilkS")
		)
		(fp_poly
			(pts
				(xy -0.508 0.2794) (xy -0.508 0.2286) (xy -0.635 0.2286) (xy -0.635 -0.254) (xy -0.5334 -0.254)
				(xy -0.5334 -0.2794) (xy 0.5334 -0.2794) (xy 0.5334 -0.254) (xy 0.635 -0.254) (xy 0.635 0.254) (xy 0.5334 0.254)
				(xy 0.5334 0.2794)
			)
			(stroke
				(width 0)
				(type default)
			)
			(fill no)
			(layer "F.CrtYd")
		)
		(pad "1" smd rect
			(at 0.40005 0 270)
			(size 0.4572 0.508)
			(layers "F.Cu" "F.Mask" "F.Paste")
			(net "PSU4_AD0")
		)
		(pad "2" smd rect
			(at -0.40005 0 270)
			(size 0.4572 0.508)
			(layers "F.Cu" "F.Mask" "F.Paste")
			(net "P12V_STBY")
		)
	)
	(footprint ""
		(layer "F.Cu")
		(at 40.11422 -371.513354 180)
		(property "Reference" "R27"
			(at -1.756918 -0.348742 0)
			(unlocked yes)
			(layer "F.SilkS")
			(effects
				(font
					(size 0.7874 0.5842)
					(thickness 0.1524)
				)
				(justify left)
			)
		)
		(property "Value" ""
			(at 0 0 180)
			(layer "F.Fab")
			(effects
				(font
					(size 1.27 1.27)
				)
			)
		)
		(duplicate_pad_numbers_are_jumpers no)
		(fp_line
			(start 0.7874 0.4064)
			(end -0.7874 0.4064)
			(stroke
				(width 0.1524)
				(type default)
			)
			(layer "F.SilkS")
		)
		(fp_line
			(start 0.7874 -0.4064)
			(end 0.7874 0.4064)
			(stroke
				(width 0.1524)
				(type default)
			)
			(layer "F.SilkS")
		)
		(fp_line
			(start -0.7874 0.4064)
			(end -0.7874 -0.4064)
			(stroke
				(width 0.1524)
				(type default)
			)
			(layer "F.SilkS")
		)
		(fp_line
			(start -0.7874 -0.4064)
			(end 0.7874 -0.4064)
			(stroke
				(width 0.1524)
				(type default)
			)
			(layer "F.SilkS")
		)
		(fp_poly
			(pts
				(xy -0.508 0.2794) (xy -0.508 0.2286) (xy -0.635 0.2286) (xy -0.635 -0.254) (xy -0.5334 -0.254)
				(xy -0.5334 -0.2794) (xy 0.5334 -0.2794) (xy 0.5334 -0.254) (xy 0.635 -0.254) (xy 0.635 0.254) (xy 0.5334 0.254)
				(xy 0.5334 0.2794)
			)
			(stroke
				(width 0)
				(type default)
			)
			(fill no)
			(layer "F.CrtYd")
		)
		(pad "1" smd rect
			(at 0.40005 0 180)
			(size 0.4572 0.508)
			(layers "F.Cu" "F.Mask" "F.Paste")
			(net "PSU5_AD0")
		)
		(pad "2" smd rect
			(at -0.40005 0 180)
			(size 0.4572 0.508)
			(layers "F.Cu" "F.Mask" "F.Paste")
			(net "GND")
		)
	)
	(footprint ""
		(layer "F.Cu")
		(at 26.001726 -101.689408)
		(property "Reference" "R135"
			(at -4.183888 -0.051562 0)
			(unlocked yes)
			(layer "F.SilkS")
			(effects
				(font
					(size 0.7874 0.5842)
					(thickness 0.1524)
				)
				(justify left)
			)
		)
		(property "Value" ""
			(at 0 0 0)
			(layer "F.Fab")
			(effects
				(font
					(size 1.27 1.27)
				)
			)
		)
		(duplicate_pad_numbers_are_jumpers no)
		(fp_line
			(start -0.7874 -0.4064)
			(end 0.7874 -0.4064)
			(stroke
				(width 0.1524)
				(type default)
			)
			(layer "F.SilkS")
		)
		(fp_line
			(start -0.7874 0.4064)
			(end -0.7874 -0.4064)
			(stroke
				(width 0.1524)
				(type default)
			)
			(layer "F.SilkS")
		)
		(fp_line
			(start 0.7874 -0.4064)
			(end 0.7874 0.4064)
			(stroke
				(width 0.1524)
				(type default)
			)
			(layer "F.SilkS")
		)
		(fp_line
			(start 0.7874 0.4064)
			(end -0.7874 0.4064)
			(stroke
				(width 0.1524)
				(type default)
			)
			(layer "F.SilkS")
		)
		(fp_poly
			(pts
				(xy -0.508 0.2794) (xy -0.508 0.2286) (xy -0.635 0.2286) (xy -0.635 -0.254) (xy -0.5334 -0.254)
				(xy -0.5334 -0.2794) (xy 0.5334 -0.2794) (xy 0.5334 -0.254) (xy 0.635 -0.254) (xy 0.635 0.254) (xy 0.5334 0.254)
				(xy 0.5334 0.2794)
			)
			(stroke
				(width 0)
				(type default)
			)
			(fill no)
			(layer "F.CrtYd")
		)
		(pad "1" smd rect
			(at 0.40005 0)
			(size 0.4572 0.508)
			(layers "F.Cu" "F.Mask" "F.Paste")
			(net "PSU2_CSAHRE")
		)
		(pad "2" smd rect
			(at -0.40005 0)
			(size 0.4572 0.508)
			(layers "F.Cu" "F.Mask" "F.Paste")
			(net "PSU_CSAHRE")
		)
	)
	(footprint ""
		(layer "F.Cu")
		(at 26.492708 -14.7955)
		(property "Reference" "R134"
			(at -3.978148 -0.004826 0)
			(unlocked yes)
			(layer "F.SilkS")
			(effects
				(font
					(size 0.7874 0.5842)
					(thickness 0.1524)
				)
				(justify left)
			)
		)
		(property "Value" ""
			(at 0 0 0)
			(layer "F.Fab")
			(effects
				(font
					(size 1.27 1.27)
				)
			)
		)
		(duplicate_pad_numbers_are_jumpers no)
		(fp_line
			(start -0.7874 -0.4064)
			(end 0.7874 -0.4064)
			(stroke
				(width 0.1524)
				(type default)
			)
			(layer "F.SilkS")
		)
		(fp_line
			(start -0.7874 0.4064)
			(end -0.7874 -0.4064)
			(stroke
				(width 0.1524)
				(type default)
			)
			(layer "F.SilkS")
		)
		(fp_line
			(start 0.7874 -0.4064)
			(end 0.7874 0.4064)
			(stroke
				(width 0.1524)
				(type default)
			)
			(layer "F.SilkS")
		)
		(fp_line
			(start 0.7874 0.4064)
			(end -0.7874 0.4064)
			(stroke
				(width 0.1524)
				(type default)
			)
			(layer "F.SilkS")
		)
		(fp_poly
			(pts
				(xy -0.508 0.2794) (xy -0.508 0.2286) (xy -0.635 0.2286) (xy -0.635 -0.254) (xy -0.5334 -0.254)
				(xy -0.5334 -0.2794) (xy 0.5334 -0.2794) (xy 0.5334 -0.254) (xy 0.635 -0.254) (xy 0.635 0.254) (xy 0.5334 0.254)
				(xy 0.5334 0.2794)
			)
			(stroke
				(width 0)
				(type default)
			)
			(fill no)
			(layer "F.CrtYd")
		)
		(pad "1" smd rect
			(at 0.40005 0)
			(size 0.4572 0.508)
			(layers "F.Cu" "F.Mask" "F.Paste")
			(net "PSU1_CSAHRE")
		)
		(pad "2" smd rect
			(at -0.40005 0)
			(size 0.4572 0.508)
			(layers "F.Cu" "F.Mask" "F.Paste")
			(net "PSU_CSAHRE")
		)
	)
	(footprint ""
		(layer "F.Cu")
		(at 74.345292 -282.156154 -90)
		(property "Reference" "C45"
			(at 0.870204 -4.132834 90)
			(unlocked yes)
			(layer "F.SilkS")
			(effects
				(font
					(size 0.7874 0.5842)
					(thickness 0.1524)
				)
				(justify left)
			)
		)
		(property "Value" ""
			(at 0 0 270)
			(layer "F.Fab")
			(effects
				(font
					(size 1.27 1.27)
				)
			)
		)
		(duplicate_pad_numbers_are_jumpers no)
		(fp_line
			(start -0.7874 0.4064)
			(end -0.7874 -0.4064)
			(stroke
				(width 0.1524)
				(type default)
			)
			(layer "F.SilkS")
		)
		(fp_line
			(start 0.7874 0.4064)
			(end -0.7874 0.4064)
			(stroke
				(width 0.1524)
				(type default)
			)
			(layer "F.SilkS")
		)
		(fp_line
			(start 0 0.381)
			(end 0 -0.381)
			(stroke
				(width 0.1524)
				(type default)
			)
			(layer "F.SilkS")
		)
		(fp_line
			(start -0.7874 -0.4064)
			(end 0.7874 -0.4064)
			(stroke
				(width 0.1524)
				(type default)
			)
			(layer "F.SilkS")
		)
		(fp_line
			(start 0.7874 -0.4064)
			(end 0.7874 0.4064)
			(stroke
				(width 0.1524)
				(type default)
			)
			(layer "F.SilkS")
		)
		(fp_poly
			(pts
				(xy -0.5334 0.254) (xy -0.635 0.254) (xy -0.635 0.2286) (xy -0.635 -0.254) (xy -0.5334 -0.254) (xy -0.5334 -0.2794)
				(xy 0.5334 -0.2794) (xy 0.5334 -0.254) (xy 0.635 -0.254) (xy 0.635 0.254) (xy 0.5334 0.254) (xy 0.5334 0.2794)
				(xy -0.508 0.2794) (xy -0.5334 0.2794)
			)
			(stroke
				(width 0)
				(type default)
			)
			(fill no)
			(layer "F.CrtYd")
		)
		(pad "1" smd rect
			(at 0.40005 0 270)
			(size 0.4572 0.508)
			(layers "F.Cu" "F.Mask" "F.Paste")
			(net "P12V")
		)
		(pad "2" smd rect
			(at -0.40005 0 270)
			(size 0.4572 0.508)
			(layers "F.Cu" "F.Mask" "F.Paste")
			(net "GND")
		)
	)
	(footprint ""
		(layer "F.Cu")
		(at 26.102056 -274.774914)
		(property "Reference" "R74"
			(at -4.037838 -0.005334 0)
			(unlocked yes)
			(layer "F.SilkS")
			(effects
				(font
					(size 0.7874 0.5842)
					(thickness 0.1524)
				)
				(justify left)
			)
		)
		(property "Value" ""
			(at 0 0 0)
			(layer "F.Fab")
			(effects
				(font
					(size 1.27 1.27)
				)
			)
		)
		(duplicate_pad_numbers_are_jumpers no)
		(fp_line
			(start -0.7874 -0.4064)
			(end 0.7874 -0.4064)
			(stroke
				(width 0.1524)
				(type default)
			)
			(layer "F.SilkS")
		)
		(fp_line
			(start -0.7874 0.4064)
			(end -0.7874 -0.4064)
			(stroke
				(width 0.1524)
				(type default)
			)
			(layer "F.SilkS")
		)
		(fp_line
			(start 0.7874 -0.4064)
			(end 0.7874 0.4064)
			(stroke
				(width 0.1524)
				(type default)
			)
			(layer "F.SilkS")
		)
		(fp_line
			(start 0.7874 0.4064)
			(end -0.7874 0.4064)
			(stroke
				(width 0.1524)
				(type default)
			)
			(layer "F.SilkS")
		)
		(fp_poly
			(pts
				(xy -0.508 0.2794) (xy -0.508 0.2286) (xy -0.635 0.2286) (xy -0.635 -0.254) (xy -0.5334 -0.254)
				(xy -0.5334 -0.2794) (xy 0.5334 -0.2794) (xy 0.5334 -0.254) (xy 0.635 -0.254) (xy 0.635 0.254) (xy 0.5334 0.254)
				(xy 0.5334 0.2794)
			)
			(stroke
				(width 0)
				(type default)
			)
			(fill no)
			(layer "F.CrtYd")
		)
		(pad "1" smd rect
			(at 0.40005 0)
			(size 0.4572 0.508)
			(layers "F.Cu" "F.Mask" "F.Paste")
			(net "PSU4_PS_KILL")
		)
		(pad "2" smd rect
			(at -0.40005 0)
			(size 0.4572 0.508)
			(layers "F.Cu" "F.Mask" "F.Paste")
			(net "P12V_STBY")
		)
	)
	(footprint ""
		(layer "F.Cu")
		(at 6.448806 -261.670546)
		(property "Reference" "J26"
			(at 6.660642 8.995918 90)
			(unlocked yes)
			(layer "F.SilkS")
			(effects
				(font
					(size 0.7874 0.5842)
					(thickness 0.1524)
				)
				(justify left)
			)
		)
		(property "Value" ""
			(at 0 0 0)
			(layer "F.Fab")
			(effects
				(font
					(size 1.27 1.27)
				)
			)
		)
		(duplicate_pad_numbers_are_jumpers no)
		(fp_line
			(start -9.400032 -5.999988)
			(end -9.400032 89.229946)
			(stroke
				(width 0.1524)
				(type default)
			)
			(layer "F.SilkS")
		)
		(fp_line
			(start -9.400032 89.229946)
			(end 5.649976 89.229946)
			(stroke
				(width 0.1524)
				(type default)
			)
			(layer "F.SilkS")
		)
		(fp_line
			(start -6.400038 -2.999994)
			(end 2.649982 -2.999994)
			(stroke
				(width 0.1524)
				(type default)
			)
			(layer "F.SilkS")
		)
		(fp_line
			(start -6.400038 86.229952)
			(end -6.400038 -2.999994)
			(stroke
				(width 0.1524)
				(type default)
			)
			(layer "F.SilkS")
		)
		(fp_line
			(start -2.265172 86.229952)
			(end -6.400038 86.229952)
			(stroke
				(width 0.1524)
				(type default)
			)
			(layer "F.SilkS")
		)
		(fp_line
			(start 2.649982 -2.999994)
			(end 2.649982 86.229952)
			(stroke
				(width 0.1524)
				(type default)
			)
			(layer "F.SilkS")
		)
		(fp_line
			(start 2.649982 86.229952)
			(end -0.334772 86.229952)
			(stroke
				(width 0.1524)
				(type default)
			)
			(layer "F.SilkS")
		)
		(fp_line
			(start 5.649976 -5.999988)
			(end -9.400032 -5.999988)
			(stroke
				(width 0.1524)
				(type default)
			)
			(layer "F.SilkS")
		)
		(fp_line
			(start 5.649976 89.229946)
			(end 5.649976 -5.999988)
			(stroke
				(width 0.1524)
				(type default)
			)
			(layer "F.SilkS")
		)
		(fp_poly
			(pts
				(xy -0.360426 -0.83439) (xy -0.60325 -2.871724) (xy -1.941322 -2.142236)
			)
			(stroke
				(width 0)
				(type default)
			)
			(fill yes)
			(layer "F.SilkS")
		)
		(fp_line
			(start -9.400032 -5.999988)
			(end -9.400032 89.229946)
			(stroke
				(width 0.1524)
				(type default)
			)
			(layer "B.SilkS")
		)
		(fp_line
			(start -9.400032 89.229946)
			(end 5.649976 89.229946)
			(stroke
				(width 0.1524)
				(type default)
			)
			(layer "B.SilkS")
		)
		(fp_line
			(start -6.400038 -2.999994)
			(end 2.649982 -2.999994)
			(stroke
				(width 0.1524)
				(type default)
			)
			(layer "B.SilkS")
		)
		(fp_line
			(start -6.400038 86.229952)
			(end -6.400038 -2.999994)
			(stroke
				(width 0.1524)
				(type default)
			)
			(layer "B.SilkS")
		)
		(fp_line
			(start -2.265172 86.229952)
			(end -6.400038 86.229952)
			(stroke
				(width 0.1524)
				(type default)
			)
			(layer "B.SilkS")
		)
		(fp_line
			(start 2.649982 -2.999994)
			(end 2.649982 86.229952)
			(stroke
				(width 0.1524)
				(type default)
			)
			(layer "B.SilkS")
		)
		(fp_line
			(start 2.649982 86.229952)
			(end -0.334772 86.229952)
			(stroke
				(width 0.1524)
				(type default)
			)
			(layer "B.SilkS")
		)
		(fp_line
			(start 5.649976 -5.999988)
			(end -9.400032 -5.999988)
			(stroke
				(width 0.1524)
				(type default)
			)
			(layer "B.SilkS")
		)
		(fp_line
			(start 5.649976 89.229946)
			(end 5.649976 -5.999988)
			(stroke
				(width 0.1524)
				(type default)
			)
			(layer "B.SilkS")
		)
		(fp_poly
			(pts
				(xy 0.127 -6.569456) (xy 0.889 -8.474456) (xy -0.635 -8.474456)
			)
			(stroke
				(width 0)
				(type default)
			)
			(fill yes)
			(layer "B.SilkS")
		)
		(fp_poly
			(pts
				(xy 2.5654 -0.5842) (xy -5.08 -0.5842) (xy -5.08 86.2838) (xy 2.5654 86.2838)
			)
			(stroke
				(width 0)
				(type default)
			)
			(fill no)
			(layer "B.CrtYd")
		)
		(fp_poly
			(pts
				(xy -6.400038 -2.999994) (xy -6.400038 86.229952) (xy -1.624838 86.229952) (xy -1.624838 86.2838)
				(xy -0.964438 86.2838) (xy -0.964438 86.229952) (xy 2.649982 86.229952) (xy 2.649982 -2.999994)
			)
			(stroke
				(width 0)
				(type default)
			)
			(fill no)
			(layer "F.CrtYd")
		)
		(fp_line
			(start -6.400038 -2.999994)
			(end -6.400038 86.229952)
			(stroke
				(width 0.1)
				(type default)
			)
			(layer "F.Fab")
		)
		(fp_line
			(start -6.400038 86.229952)
			(end 2.649982 86.229952)
			(stroke
				(width 0.1)
				(type default)
			)
			(layer "F.Fab")
		)
		(fp_line
			(start 2.649982 -2.999994)
			(end -6.400038 -2.999994)
			(stroke
				(width 0.1)
				(type default)
			)
			(layer "F.Fab")
		)
		(fp_line
			(start 2.649982 86.229952)
			(end 2.649982 -2.999994)
			(stroke
				(width 0.1)
				(type default)
			)
			(layer "F.Fab")
		)
		(fp_text user "B82"
			(at -4.50723 88.688418 90)
			(unlocked yes)
			(layer "F.SilkS")
			(effects
				(font
					(size 0.7874 0.5842)
					(thickness 0.1524)
				)
				(justify left)
			)
		)
		(fp_text user "B2"
			(at -4.239006 -0.867918 90)
			(unlocked yes)
			(layer "F.SilkS")
			(effects
				(font
					(size 0.7874 0.5842)
					(thickness 0.1524)
				)
				(justify left)
			)
		)
		(fp_text user "B1"
			(at -2.661666 -0.948436 90)
			(unlocked yes)
			(layer "F.SilkS")
			(effects
				(font
					(size 0.7874 0.5842)
					(thickness 0.1524)
				)
				(justify left)
			)
		)
		(fp_text user "B81"
			(at -2.507234 88.688418 90)
			(unlocked yes)
			(layer "F.SilkS")
			(effects
				(font
					(size 0.7874 0.5842)
					(thickness 0.1524)
				)
				(justify left)
			)
		)
		(fp_text user "A81"
			(at -0.007366 88.688418 90)
			(unlocked yes)
			(layer "F.SilkS")
			(effects
				(font
					(size 0.7874 0.5842)
					(thickness 0.1524)
				)
				(justify left)
			)
		)
		(fp_text user "A1"
			(at 0.225298 -0.747776 90)
			(unlocked yes)
			(layer "F.SilkS")
			(effects
				(font
					(size 0.7874 0.5842)
					(thickness 0.1524)
				)
				(justify left)
			)
		)
		(fp_text user "A2"
			(at 1.592326 -0.784606 90)
			(unlocked yes)
			(layer "F.SilkS")
			(effects
				(font
					(size 0.7874 0.5842)
					(thickness 0.1524)
				)
				(justify left)
			)
		)
		(fp_text user "A82"
			(at 1.992884 88.688418 90)
			(unlocked yes)
			(layer "F.SilkS")
			(effects
				(font
					(size 0.7874 0.5842)
					(thickness 0.1524)
				)
				(justify left)
			)
		)
		(fp_text user "PRESS  FIT"
			(at 7.575042 33.997138 90)
			(unlocked yes)
			(layer "F.SilkS")
			(effects
				(font
					(size 1.905 1.4224)
					(thickness 0.1524)
				)
				(justify left)
			)
		)
		(fp_text user "B2"
			(at -4.534662 -0.56388 270)
			(unlocked yes)
			(layer "B.SilkS")
			(effects
				(font
					(size 0.7874 0.5842)
					(thickness 0.1524)
				)
				(justify left mirror)
			)
		)
		(fp_text user "B82"
			(at -4.462526 85.889592 270)
			(unlocked yes)
			(layer "B.SilkS")
			(effects
				(font
					(size 0.7874 0.5842)
					(thickness 0.1524)
				)
				(justify left mirror)
			)
		)
		(fp_text user "B81"
			(at -3.170174 84.489544 270)
			(unlocked yes)
			(layer "B.SilkS")
			(effects
				(font
					(size 0.7874 0.5842)
					(thickness 0.1524)
				)
				(justify left mirror)
			)
		)
		(fp_text user "B1"
			(at -2.408174 -0.867156 270)
			(unlocked yes)
			(layer "B.SilkS")
			(effects
				(font
					(size 0.7874 0.5842)
					(thickness 0.1524)
				)
				(justify left mirror)
			)
		)
		(fp_text user "A1"
			(at 0.091694 -0.867156 270)
			(unlocked yes)
			(layer "B.SilkS")
			(effects
				(font
					(size 0.7874 0.5842)
					(thickness 0.1524)
				)
				(justify left mirror)
			)
		)
		(fp_text user "A81"
			(at 0.663194 84.489544 270)
			(unlocked yes)
			(layer "B.SilkS")
			(effects
				(font
					(size 0.7874 0.5842)
					(thickness 0.1524)
				)
				(justify left mirror)
			)
		)
		(fp_text user "A2"
			(at 1.981962 -0.213106 270)
			(unlocked yes)
			(layer "B.SilkS")
			(effects
				(font
					(size 0.7874 0.5842)
					(thickness 0.1524)
				)
				(justify left mirror)
			)
		)
		(fp_text user "A82"
			(at 2.091944 86.013544 270)
			(unlocked yes)
			(layer "B.SilkS")
			(effects
				(font
					(size 0.7874 0.5842)
					(thickness 0.1524)
				)
				(justify left mirror)
			)
		)
		(fp_text user "PRESS  FIT"
			(at 8.267954 35.40633 270)
			(unlocked yes)
			(layer "B.SilkS")
			(effects
				(font
					(size 1.6002 1.1938)
					(thickness 0.000001)
				)
				(justify left mirror)
			)
		)
		(pad "" np_thru_hole circle
			(at -1.249934 11.649964 270)
			(size 2.413 2.413)
			(drill 2.413)
			(layers "*.Cu" "*.Mask")
			(clearance 0.381)
			(thermal_gap 0.381)
		)
		(pad "" np_thru_hole circle
			(at -1.249934 84.799932 270)
			(size 2.413 2.413)
			(drill 2.413)
			(layers "*.Cu" "*.Mask")
			(clearance 0.381)
			(thermal_gap 0.381)
		)
		(pad "A1" thru_hole rect
			(at 0 0 270)
			(size 1.016 1.016)
			(drill 0.7112)
			(layers "*.Cu" "*.Mask")
			(remove_unused_layers no)
			(net "GND")
			(clearance 0.1016)
			(thermal_gap 0.1016)
			(padstack
				(mode front_inner_back)
				(layer "Inner"
					(shape circle)
					(size 1.016 1.016)
					(clearance 0.1016)
				)
				(layer "B.Cu"
					(shape rect)
					(size 1.016 1.016)
					(clearance 0.1016)
				)
			)
		)
		(pad "A2" thru_hole circle
			(at 1.999996 0.999998 270)
			(size 1.016 1.016)
			(drill 0.7112)
			(layers "*.Cu" "*.Mask")
			(remove_unused_layers no)
			(net "T5_BLAD3_EN")
			(clearance 0.1016)
			(thermal_gap 0.1016)
		)
		(pad "A3" thru_hole circle
			(at 0 1.999996 270)
			(size 1.016 1.016)
			(drill 0.7112)
			(layers "*.Cu" "*.Mask")
			(remove_unused_layers no)
			(net "T5_BLAD4_EN")
			(clearance 0.1016)
			(thermal_gap 0.1016)
		)
		(pad "A4" thru_hole circle
			(at 1.999996 2.999994 270)
			(size 1.016 1.016)
			(drill 0.7112)
			(layers "*.Cu" "*.Mask")
			(remove_unused_layers no)
			(net "GND")
			(clearance 0.1016)
			(thermal_gap 0.1016)
		)
		(pad "A5" thru_hole circle
			(at 0 3.999992 270)
			(size 1.016 1.016)
			(drill 0.7112)
			(layers "*.Cu" "*.Mask")
			(remove_unused_layers no)
			(net "T5_BLAD1_RXD")
			(clearance 0.1016)
			(thermal_gap 0.1016)
		)
		(pad "A6" thru_hole circle
			(at 1.999996 4.99999 270)
			(size 1.016 1.016)
			(drill 0.7112)
			(layers "*.Cu" "*.Mask")
			(remove_unused_layers no)
			(net "T5_BLAD1_TXD")
			(clearance 0.1016)
			(thermal_gap 0.1016)
		)
		(pad "A7" thru_hole circle
			(at 0 5.999988 270)
			(size 1.016 1.016)
			(drill 0.7112)
			(layers "*.Cu" "*.Mask")
			(remove_unused_layers no)
			(net "GND")
			(clearance 0.1016)
			(thermal_gap 0.1016)
		)
		(pad "A8" thru_hole circle
			(at 1.999996 6.999986 270)
			(size 1.016 1.016)
			(drill 0.7112)
			(layers "*.Cu" "*.Mask")
			(remove_unused_layers no)
			(net "T5_BLAD2_RXD")
			(clearance 0.1016)
			(thermal_gap 0.1016)
		)
		(pad "A9" thru_hole circle
			(at 0 7.999984 270)
			(size 1.016 1.016)
			(drill 0.7112)
			(layers "*.Cu" "*.Mask")
			(remove_unused_layers no)
			(net "T5_BLAD2_TXD")
			(clearance 0.1016)
			(thermal_gap 0.1016)
		)
		(pad "A10" thru_hole circle
			(at 1.999996 8.999982 270)
			(size 1.016 1.016)
			(drill 0.7112)
			(layers "*.Cu" "*.Mask")
			(remove_unused_layers no)
			(net "T5_BLAD3_RXD")
			(clearance 0.1016)
			(thermal_gap 0.1016)
		)
		(pad "A11" thru_hole circle
			(at 0 9.99998 270)
			(size 1.016 1.016)
			(drill 0.7112)
			(layers "*.Cu" "*.Mask")
			(remove_unused_layers no)
			(net "T5_BLAD3_TXD")
			(clearance 0.1016)
			(thermal_gap 0.1016)
		)
		(pad "A12" thru_hole circle
			(at 1.999996 12.999974 270)
			(size 1.016 1.016)
			(drill 0.7112)
			(layers "*.Cu" "*.Mask")
			(remove_unused_layers no)
			(net "T5_BLAD4_RXD")
			(clearance 0.1016)
			(thermal_gap 0.1016)
		)
		(pad "A13" thru_hole circle
			(at 0 13.999972 270)
			(size 1.016 1.016)
			(drill 0.7112)
			(layers "*.Cu" "*.Mask")
			(remove_unused_layers no)
			(net "T5_BLAD4_TXD")
			(clearance 0.1016)
			(thermal_gap 0.1016)
		)
		(pad "A14" thru_hole circle
			(at 1.999996 14.99997 270)
			(size 1.016 1.016)
			(drill 0.7112)
			(layers "*.Cu" "*.Mask")
			(remove_unused_layers no)
			(net "GND")
			(clearance 0.1016)
			(thermal_gap 0.1016)
		)
		(pad "A15" thru_hole circle
			(at 0 15.999968 270)
			(size 1.016 1.016)
			(drill 0.7112)
			(layers "*.Cu" "*.Mask")
			(remove_unused_layers no)
			(net "T3_BLAD1_EN")
			(clearance 0.1016)
			(thermal_gap 0.1016)
		)
		(pad "A16" thru_hole circle
			(at 1.999996 16.999966 270)
			(size 1.016 1.016)
			(drill 0.7112)
			(layers "*.Cu" "*.Mask")
			(remove_unused_layers no)
			(net "T3_BLAD2_EN")
			(clearance 0.1016)
			(thermal_gap 0.1016)
		)
		(pad "A17" thru_hole circle
			(at 0 17.999964 270)
			(size 1.016 1.016)
			(drill 0.7112)
			(layers "*.Cu" "*.Mask")
			(remove_unused_layers no)
			(net "T3_BLAD3_EN")
			(clearance 0.1016)
			(thermal_gap 0.1016)
		)
		(pad "A18" thru_hole circle
			(at 1.999996 18.999962 270)
			(size 1.016 1.016)
			(drill 0.7112)
			(layers "*.Cu" "*.Mask")
			(remove_unused_layers no)
			(net "T3_BLAD4_EN")
			(clearance 0.1016)
			(thermal_gap 0.1016)
		)
		(pad "A19" thru_hole circle
			(at 0 19.99996 270)
			(size 1.016 1.016)
			(drill 0.7112)
			(layers "*.Cu" "*.Mask")
			(remove_unused_layers no)
			(net "GND")
			(clearance 0.1016)
			(thermal_gap 0.1016)
		)
		(pad "A20" thru_hole circle
			(at 1.999996 20.999958 270)
			(size 1.016 1.016)
			(drill 0.7112)
			(layers "*.Cu" "*.Mask")
			(remove_unused_layers no)
			(net "T3_BLAD1_RXD")
			(clearance 0.1016)
			(thermal_gap 0.1016)
		)
		(pad "A21" thru_hole circle
			(at 0 21.999956 270)
			(size 1.016 1.016)
			(drill 0.7112)
			(layers "*.Cu" "*.Mask")
			(remove_unused_layers no)
			(net "T3_BLAD1_TXD")
			(clearance 0.1016)
			(thermal_gap 0.1016)
		)
		(pad "A22" thru_hole circle
			(at 1.999996 22.999954 270)
			(size 1.016 1.016)
			(drill 0.7112)
			(layers "*.Cu" "*.Mask")
			(remove_unused_layers no)
			(net "T3_BLAD2_RXD")
			(clearance 0.1016)
			(thermal_gap 0.1016)
		)
		(pad "A23" thru_hole circle
			(at 0 23.999952 270)
			(size 1.016 1.016)
			(drill 0.7112)
			(layers "*.Cu" "*.Mask")
			(remove_unused_layers no)
			(net "T3_BLAD2_TXD")
			(clearance 0.1016)
			(thermal_gap 0.1016)
		)
		(pad "A24" thru_hole circle
			(at 1.999996 24.99995 270)
			(size 1.016 1.016)
			(drill 0.7112)
			(layers "*.Cu" "*.Mask")
			(remove_unused_layers no)
			(net "GND")
			(clearance 0.1016)
			(thermal_gap 0.1016)
		)
		(pad "A25" thru_hole circle
			(at 0 25.999948 270)
			(size 1.016 1.016)
			(drill 0.7112)
			(layers "*.Cu" "*.Mask")
			(remove_unused_layers no)
			(net "T3_BLAD3_RXD")
			(clearance 0.1016)
			(thermal_gap 0.1016)
		)
		(pad "A26" thru_hole circle
			(at 1.999996 26.999946 270)
			(size 1.016 1.016)
			(drill 0.7112)
			(layers "*.Cu" "*.Mask")
			(remove_unused_layers no)
			(net "T3_BLAD3_TXD")
			(clearance 0.1016)
			(thermal_gap 0.1016)
		)
		(pad "A27" thru_hole circle
			(at 0 27.999944 270)
			(size 1.016 1.016)
			(drill 0.7112)
			(layers "*.Cu" "*.Mask")
			(remove_unused_layers no)
			(net "T3_BLAD4_RXD")
			(clearance 0.1016)
			(thermal_gap 0.1016)
		)
		(pad "A28" thru_hole circle
			(at 1.999996 28.999942 270)
			(size 1.016 1.016)
			(drill 0.7112)
			(layers "*.Cu" "*.Mask")
			(remove_unused_layers no)
			(net "T3_BLAD4_TXD")
			(clearance 0.1016)
			(thermal_gap 0.1016)
		)
		(pad "A29" thru_hole circle
			(at 0 29.99994 270)
			(size 1.016 1.016)
			(drill 0.7112)
			(layers "*.Cu" "*.Mask")
			(remove_unused_layers no)
			(net "GND")
			(clearance 0.1016)
			(thermal_gap 0.1016)
		)
		(pad "A30" thru_hole circle
			(at 1.999996 30.999938 270)
			(size 1.016 1.016)
			(drill 0.7112)
			(layers "*.Cu" "*.Mask")
			(remove_unused_layers no)
			(net "T1_BLAD1_EN")
			(clearance 0.1016)
			(thermal_gap 0.1016)
		)
		(pad "A31" thru_hole circle
			(at 0 31.999936 270)
			(size 1.016 1.016)
			(drill 0.7112)
			(layers "*.Cu" "*.Mask")
			(remove_unused_layers no)
			(net "T1_BLAD2_EN")
			(clearance 0.1016)
			(thermal_gap 0.1016)
		)
		(pad "A32" thru_hole circle
			(at 1.999996 32.999934 270)
			(size 1.016 1.016)
			(drill 0.7112)
			(layers "*.Cu" "*.Mask")
			(remove_unused_layers no)
			(net "T1_BLAD3_EN")
			(clearance 0.1016)
			(thermal_gap 0.1016)
		)
		(pad "A33" thru_hole circle
			(at 0 33.999932 270)
			(size 1.016 1.016)
			(drill 0.7112)
			(layers "*.Cu" "*.Mask")
			(remove_unused_layers no)
			(net "T1_BLAD4_EN")
			(clearance 0.1016)
			(thermal_gap 0.1016)
		)
		(pad "A34" thru_hole circle
			(at 1.999996 34.99993 270)
			(size 1.016 1.016)
			(drill 0.7112)
			(layers "*.Cu" "*.Mask")
			(remove_unused_layers no)
			(net "GND")
			(clearance 0.1016)
			(thermal_gap 0.1016)
		)
		(pad "A35" thru_hole circle
			(at 0 35.999928 270)
			(size 1.016 1.016)
			(drill 0.7112)
			(layers "*.Cu" "*.Mask")
			(remove_unused_layers no)
			(net "T1_BLAD2_RXD")
			(clearance 0.1016)
			(thermal_gap 0.1016)
		)
		(pad "A36" thru_hole circle
			(at 1.999996 36.999926 270)
			(size 1.016 1.016)
			(drill 0.7112)
			(layers "*.Cu" "*.Mask")
			(remove_unused_layers no)
			(net "T1_BLAD2_TXD")
			(clearance 0.1016)
			(thermal_gap 0.1016)
		)
		(pad "A37" thru_hole circle
			(at 0 37.999924 270)
			(size 1.016 1.016)
			(drill 0.7112)
			(layers "*.Cu" "*.Mask")
			(remove_unused_layers no)
			(net "T1_BLAD3_RXD")
			(clearance 0.1016)
			(thermal_gap 0.1016)
		)
		(pad "A38" thru_hole circle
			(at 1.999996 38.999922 270)
			(size 1.016 1.016)
			(drill 0.7112)
			(layers "*.Cu" "*.Mask")
			(remove_unused_layers no)
			(net "T1_BLAD3_TXD")
			(clearance 0.1016)
			(thermal_gap 0.1016)
		)
		(pad "A39" thru_hole circle
			(at 0 39.99992 270)
			(size 1.016 1.016)
			(drill 0.7112)
			(layers "*.Cu" "*.Mask")
			(remove_unused_layers no)
			(net "GND")
			(clearance 0.1016)
			(thermal_gap 0.1016)
		)
		(pad "A40" thru_hole circle
			(at 1.999996 40.999918 270)
			(size 1.016 1.016)
			(drill 0.7112)
			(layers "*.Cu" "*.Mask")
			(remove_unused_layers no)
			(net "T1_BLAD4_RXD")
			(clearance 0.1016)
			(thermal_gap 0.1016)
		)
		(pad "A41" thru_hole circle
			(at 0 41.999916 270)
			(size 1.016 1.016)
			(drill 0.7112)
			(layers "*.Cu" "*.Mask")
			(remove_unused_layers no)
			(net "T1_BLAD4_TXD")
			(clearance 0.1016)
			(thermal_gap 0.1016)
		)
		(pad "A42" thru_hole circle
			(at 1.999996 42.999914 270)
			(size 1.016 1.016)
			(drill 0.7112)
			(layers "*.Cu" "*.Mask")
			(remove_unused_layers no)
			(net "T1_BLAD1_RXD")
			(clearance 0.1016)
			(thermal_gap 0.1016)
		)
		(pad "A43" thru_hole circle
			(at 0 43.999912 270)
			(size 1.016 1.016)
			(drill 0.7112)
			(layers "*.Cu" "*.Mask")
			(remove_unused_layers no)
			(net "T1_BLAD1_TXD")
			(clearance 0.1016)
			(thermal_gap 0.1016)
		)
		(pad "A44" thru_hole circle
			(at 1.999996 44.99991 270)
			(size 1.016 1.016)
			(drill 0.7112)
			(layers "*.Cu" "*.Mask")
			(remove_unused_layers no)
			(net "GND")
			(clearance 0.1016)
			(thermal_gap 0.1016)
		)
		(pad "A45" thru_hole circle
			(at 0 45.999908 270)
			(size 1.016 1.016)
			(drill 0.7112)
			(layers "*.Cu" "*.Mask")
			(remove_unused_layers no)
			(net "PSU1_DC_OK")
			(clearance 0.1016)
			(thermal_gap 0.1016)
		)
		(pad "A46" thru_hole circle
			(at 1.999996 46.999906 270)
			(size 1.016 1.016)
			(drill 0.7112)
			(layers "*.Cu" "*.Mask")
			(remove_unused_layers no)
			(net "PSU2_DC_OK")
			(clearance 0.1016)
			(thermal_gap 0.1016)
		)
		(pad "A47" thru_hole circle
			(at 0 47.999904 270)
			(size 1.016 1.016)
			(drill 0.7112)
			(layers "*.Cu" "*.Mask")
			(remove_unused_layers no)
			(net "PSU3_DC_OK")
			(clearance 0.1016)
			(thermal_gap 0.1016)
		)
		(pad "A48" thru_hole circle
			(at 1.999996 48.999902 270)
			(size 1.016 1.016)
			(drill 0.7112)
			(layers "*.Cu" "*.Mask")
			(remove_unused_layers no)
			(net "PSU4_DC_OK")
			(clearance 0.1016)
			(thermal_gap 0.1016)
		)
		(pad "A49" thru_hole circle
			(at 0 49.9999 270)
			(size 1.016 1.016)
			(drill 0.7112)
			(layers "*.Cu" "*.Mask")
			(remove_unused_layers no)
			(net "PSU5_DC_OK")
			(clearance 0.1016)
			(thermal_gap 0.1016)
		)
		(pad "A50" thru_hole circle
			(at 1.999996 50.999898 270)
			(size 1.016 1.016)
			(drill 0.7112)
			(layers "*.Cu" "*.Mask")
			(remove_unused_layers no)
			(net "PSU6_DC_OK")
			(clearance 0.1016)
			(thermal_gap 0.1016)
		)
		(pad "A51" thru_hole circle
			(at 0 51.999896 270)
			(size 1.016 1.016)
			(drill 0.7112)
			(layers "*.Cu" "*.Mask")
			(remove_unused_layers no)
			(net "GND")
			(clearance 0.1016)
			(thermal_gap 0.1016)
		)
		(pad "A52" thru_hole circle
			(at 1.999996 52.999894 270)
			(size 1.016 1.016)
			(drill 0.7112)
			(layers "*.Cu" "*.Mask")
			(remove_unused_layers no)
			(net "UART_RTS_P6_L_N")
			(clearance 0.1016)
			(thermal_gap 0.1016)
		)
		(pad "A53" thru_hole circle
			(at 0 53.999892 270)
			(size 1.016 1.016)
			(drill 0.7112)
			(layers "*.Cu" "*.Mask")
			(remove_unused_layers no)
			(net "UART_DSR_P6_L_N")
			(clearance 0.1016)
			(thermal_gap 0.1016)
		)
		(pad "A54" thru_hole circle
			(at 1.999996 54.99989 270)
			(size 1.016 1.016)
			(drill 0.7112)
			(layers "*.Cu" "*.Mask")
			(remove_unused_layers no)
			(net "UART_RX_P6_L")
			(clearance 0.1016)
			(thermal_gap 0.1016)
		)
		(pad "A55" thru_hole circle
			(at 0 55.999888 270)
			(size 1.016 1.016)
			(drill 0.7112)
			(layers "*.Cu" "*.Mask")
			(remove_unused_layers no)
			(net "UART_TX_P6_L")
			(clearance 0.1016)
			(thermal_gap 0.1016)
		)
		(pad "A56" thru_hole circle
			(at 1.999996 56.999886 270)
			(size 1.016 1.016)
			(drill 0.7112)
			(layers "*.Cu" "*.Mask")
			(remove_unused_layers no)
			(net "UART_DTR_P6_L_N")
			(clearance 0.1016)
			(thermal_gap 0.1016)
		)
		(pad "A57" thru_hole circle
			(at 0 57.999884 270)
			(size 1.016 1.016)
			(drill 0.7112)
			(layers "*.Cu" "*.Mask")
			(remove_unused_layers no)
			(net "UART_CTS_P6_L_N")
			(clearance 0.1016)
			(thermal_gap 0.1016)
		)
		(pad "A58" thru_hole circle
			(at 1.999996 59.000136 270)
			(size 1.016 1.016)
			(drill 0.7112)
			(layers "*.Cu" "*.Mask")
			(remove_unused_layers no)
			(net "UART_RI_P6_L_N")
			(clearance 0.1016)
			(thermal_gap 0.1016)
		)
		(pad "A59" thru_hole circle
			(at 0 59.99988 270)
			(size 1.016 1.016)
			(drill 0.7112)
			(layers "*.Cu" "*.Mask")
			(remove_unused_layers no)
			(net "GND")
			(clearance 0.1016)
			(thermal_gap 0.1016)
		)
		(pad "A60" thru_hole circle
			(at 1.999996 61.000132 270)
			(size 1.016 1.016)
			(drill 0.7112)
			(layers "*.Cu" "*.Mask")
			(remove_unused_layers no)
			(net "UART_RTS_P2_L_N")
			(clearance 0.1016)
			(thermal_gap 0.1016)
		)
		(pad "A61" thru_hole circle
			(at 0 61.999876 270)
			(size 1.016 1.016)
			(drill 0.7112)
			(layers "*.Cu" "*.Mask")
			(remove_unused_layers no)
			(net "UART_DSR_P2_L_N")
			(clearance 0.1016)
			(thermal_gap 0.1016)
		)
		(pad "A62" thru_hole circle
			(at 1.999996 63.000128 270)
			(size 1.016 1.016)
			(drill 0.7112)
			(layers "*.Cu" "*.Mask")
			(remove_unused_layers no)
			(net "UART_RX_P2_L")
			(clearance 0.1016)
			(thermal_gap 0.1016)
		)
		(pad "A63" thru_hole circle
			(at 0 63.999872 270)
			(size 1.016 1.016)
			(drill 0.7112)
			(layers "*.Cu" "*.Mask")
			(remove_unused_layers no)
			(net "UART_TX_P2_L")
			(clearance 0.1016)
			(thermal_gap 0.1016)
		)
		(pad "A64" thru_hole circle
			(at 1.999996 65.000124 270)
			(size 1.016 1.016)
			(drill 0.7112)
			(layers "*.Cu" "*.Mask")
			(remove_unused_layers no)
			(net "UART_DTR_P2_L_N")
			(clearance 0.1016)
			(thermal_gap 0.1016)
		)
		(pad "A65" thru_hole circle
			(at 0 65.999868 270)
			(size 1.016 1.016)
			(drill 0.7112)
			(layers "*.Cu" "*.Mask")
			(remove_unused_layers no)
			(net "UART_CTS_P2_L_N")
			(clearance 0.1016)
			(thermal_gap 0.1016)
		)
		(pad "A66" thru_hole circle
			(at 1.999996 67.00012 270)
			(size 1.016 1.016)
			(drill 0.7112)
			(layers "*.Cu" "*.Mask")
			(remove_unused_layers no)
			(net "GND")
			(clearance 0.1016)
			(thermal_gap 0.1016)
		)
		(pad "A67" thru_hole circle
			(at 0 67.999864 270)
			(size 1.016 1.016)
			(drill 0.7112)
			(layers "*.Cu" "*.Mask")
			(remove_unused_layers no)
			(net "Net_409")
			(clearance 0.1016)
			(thermal_gap 0.1016)
		)
		(pad "A68" thru_hole circle
			(at 1.999996 69.000116 270)
			(size 1.016 1.016)
			(drill 0.7112)
			(layers "*.Cu" "*.Mask")
			(remove_unused_layers no)
			(net "Net_413")
			(clearance 0.1016)
			(thermal_gap 0.1016)
		)
		(pad "A69" thru_hole circle
			(at 0 70.000114 270)
			(size 1.016 1.016)
			(drill 0.7112)
			(layers "*.Cu" "*.Mask")
			(remove_unused_layers no)
			(net "Net_412")
			(clearance 0.1016)
			(thermal_gap 0.1016)
		)
		(pad "A70" thru_hole circle
			(at 1.999996 71.000112 270)
			(size 1.016 1.016)
			(drill 0.7112)
			(layers "*.Cu" "*.Mask")
			(remove_unused_layers no)
			(net "GND61")
			(clearance 0.1016)
			(thermal_gap 0.1016)
		)
		(pad "A71" thru_hole circle
			(at 0 72.00011 270)
			(size 1.016 1.016)
			(drill 0.7112)
			(layers "*.Cu" "*.Mask")
			(remove_unused_layers no)
			(net "GND")
			(clearance 0.1016)
			(thermal_gap 0.1016)
		)
		(pad "A72" thru_hole circle
			(at 1.999996 73.000108 270)
			(size 1.016 1.016)
			(drill 0.7112)
			(layers "*.Cu" "*.Mask")
			(remove_unused_layers no)
			(net "LAN1_P1_P")
			(clearance 0.1016)
			(thermal_gap 0.1016)
		)
		(pad "A73" thru_hole circle
			(at 0 74.000106 270)
			(size 1.016 1.016)
			(drill 0.7112)
			(layers "*.Cu" "*.Mask")
			(remove_unused_layers no)
			(net "LAN1_P1_N")
			(clearance 0.1016)
			(thermal_gap 0.1016)
		)
		(pad "A74" thru_hole circle
			(at 1.999996 75.000104 270)
			(size 1.016 1.016)
			(drill 0.7112)
			(layers "*.Cu" "*.Mask")
			(remove_unused_layers no)
			(net "GND")
			(clearance 0.1016)
			(thermal_gap 0.1016)
		)
		(pad "A75" thru_hole circle
			(at 0 76.000102 270)
			(size 1.016 1.016)
			(drill 0.7112)
			(layers "*.Cu" "*.Mask")
			(remove_unused_layers no)
			(net "LAN1_P2_P")
			(clearance 0.1016)
			(thermal_gap 0.1016)
		)
		(pad "A76" thru_hole circle
			(at 1.999996 77.0001 270)
			(size 1.016 1.016)
			(drill 0.7112)
			(layers "*.Cu" "*.Mask")
			(remove_unused_layers no)
			(net "LAN1_P2_N")
			(clearance 0.1016)
			(thermal_gap 0.1016)
		)
		(pad "A77" thru_hole circle
			(at 0 78.000098 270)
			(size 1.016 1.016)
			(drill 0.7112)
			(layers "*.Cu" "*.Mask")
			(remove_unused_layers no)
			(net "GND")
			(clearance 0.1016)
			(thermal_gap 0.1016)
		)
		(pad "A78" thru_hole circle
			(at 1.999996 79.000096 270)
			(size 1.016 1.016)
			(drill 0.7112)
			(layers "*.Cu" "*.Mask")
			(remove_unused_layers no)
			(net "P12V")
			(clearance 0.1016)
			(thermal_gap 0.1016)
		)
		(pad "A79" thru_hole circle
			(at 0 80.000094 270)
			(size 1.016 1.016)
			(drill 0.7112)
			(layers "*.Cu" "*.Mask")
			(remove_unused_layers no)
			(net "P12V")
			(clearance 0.1016)
			(thermal_gap 0.1016)
		)
		(pad "A80" thru_hole circle
			(at 1.999996 81.000092 270)
			(size 1.016 1.016)
			(drill 0.7112)
			(layers "*.Cu" "*.Mask")
			(remove_unused_layers no)
			(net "P12V")
			(clearance 0.1016)
			(thermal_gap 0.1016)
		)
		(pad "A81" thru_hole circle
			(at 0 82.00009 270)
			(size 1.016 1.016)
			(drill 0.7112)
			(layers "*.Cu" "*.Mask")
			(remove_unused_layers no)
			(net "P12V")
			(clearance 0.1016)
			(thermal_gap 0.1016)
		)
		(pad "A82" thru_hole circle
			(at 1.999996 83.000088 270)
			(size 1.016 1.016)
			(drill 0.7112)
			(layers "*.Cu" "*.Mask")
			(remove_unused_layers no)
			(net "P12V")
			(clearance 0.1016)
			(thermal_gap 0.1016)
		)
		(pad "B1" thru_hole circle
			(at -2.499868 0 270)
			(size 1.016 1.016)
			(drill 0.7112)
			(layers "*.Cu" "*.Mask")
			(remove_unused_layers no)
			(net "GND")
			(clearance 0.1016)
			(thermal_gap 0.1016)
		)
		(pad "B2" thru_hole circle
			(at -4.499864 0.999998 270)
			(size 1.016 1.016)
			(drill 0.7112)
			(layers "*.Cu" "*.Mask")
			(remove_unused_layers no)
			(net "T6_BLAD2_RXD")
			(clearance 0.1016)
			(thermal_gap 0.1016)
		)
		(pad "B3" thru_hole circle
			(at -2.499868 1.999996 270)
			(size 1.016 1.016)
			(drill 0.7112)
			(layers "*.Cu" "*.Mask")
			(remove_unused_layers no)
			(net "T6_BLAD2_TXD")
			(clearance 0.1016)
			(thermal_gap 0.1016)
		)
		(pad "B4" thru_hole circle
			(at -4.499864 2.999994 270)
			(size 1.016 1.016)
			(drill 0.7112)
			(layers "*.Cu" "*.Mask")
			(remove_unused_layers no)
			(net "GND")
			(clearance 0.1016)
			(thermal_gap 0.1016)
		)
		(pad "B5" thru_hole circle
			(at -2.499868 3.999992 270)
			(size 1.016 1.016)
			(drill 0.7112)
			(layers "*.Cu" "*.Mask")
			(remove_unused_layers no)
			(net "T6_BLAD3_RXD")
			(clearance 0.1016)
			(thermal_gap 0.1016)
		)
		(pad "B6" thru_hole circle
			(at -4.499864 4.99999 270)
			(size 1.016 1.016)
			(drill 0.7112)
			(layers "*.Cu" "*.Mask")
			(remove_unused_layers no)
			(net "T6_BLAD3_TXD")
			(clearance 0.1016)
			(thermal_gap 0.1016)
		)
		(pad "B7" thru_hole circle
			(at -2.499868 5.999988 270)
			(size 1.016 1.016)
			(drill 0.7112)
			(layers "*.Cu" "*.Mask")
			(remove_unused_layers no)
			(net "T6_BLAD4_RXD")
			(clearance 0.1016)
			(thermal_gap 0.1016)
		)
		(pad "B8" thru_hole circle
			(at -4.499864 6.999986 270)
			(size 1.016 1.016)
			(drill 0.7112)
			(layers "*.Cu" "*.Mask")
			(remove_unused_layers no)
			(net "T6_BLAD4_TXD")
			(clearance 0.1016)
			(thermal_gap 0.1016)
		)
		(pad "B9" thru_hole circle
			(at -2.499868 7.999984 270)
			(size 1.016 1.016)
			(drill 0.7112)
			(layers "*.Cu" "*.Mask")
			(remove_unused_layers no)
			(net "GND")
			(clearance 0.1016)
			(thermal_gap 0.1016)
		)
		(pad "B10" thru_hole circle
			(at -4.499864 8.999982 270)
			(size 1.016 1.016)
			(drill 0.7112)
			(layers "*.Cu" "*.Mask")
			(remove_unused_layers no)
			(net "I2C_PSU2_SCL")
			(clearance 0.1016)
			(thermal_gap 0.1016)
		)
		(pad "B11" thru_hole circle
			(at -2.499868 9.99998 270)
			(size 1.016 1.016)
			(drill 0.7112)
			(layers "*.Cu" "*.Mask")
			(remove_unused_layers no)
			(net "I2C_PSU2_SDA")
			(clearance 0.1016)
			(thermal_gap 0.1016)
		)
		(pad "B12" thru_hole circle
			(at -4.499864 12.999974 270)
			(size 1.016 1.016)
			(drill 0.7112)
			(layers "*.Cu" "*.Mask")
			(remove_unused_layers no)
			(net "T4_BLAD1_EN")
			(clearance 0.1016)
			(thermal_gap 0.1016)
		)
		(pad "B13" thru_hole circle
			(at -2.499868 13.999972 270)
			(size 1.016 1.016)
			(drill 0.7112)
			(layers "*.Cu" "*.Mask")
			(remove_unused_layers no)
			(net "T4_BLAD2_EN")
			(clearance 0.1016)
			(thermal_gap 0.1016)
		)
		(pad "B14" thru_hole circle
			(at -4.499864 14.99997 270)
			(size 1.016 1.016)
			(drill 0.7112)
			(layers "*.Cu" "*.Mask")
			(remove_unused_layers no)
			(net "T4_BLAD3_EN")
			(clearance 0.1016)
			(thermal_gap 0.1016)
		)
		(pad "B15" thru_hole circle
			(at -2.499868 15.999968 270)
			(size 1.016 1.016)
			(drill 0.7112)
			(layers "*.Cu" "*.Mask")
			(remove_unused_layers no)
			(net "T4_BLAD4_EN")
			(clearance 0.1016)
			(thermal_gap 0.1016)
		)
		(pad "B16" thru_hole circle
			(at -4.499864 16.999966 270)
			(size 1.016 1.016)
			(drill 0.7112)
			(layers "*.Cu" "*.Mask")
			(remove_unused_layers no)
			(net "GND")
			(clearance 0.1016)
			(thermal_gap 0.1016)
		)
		(pad "B17" thru_hole circle
			(at -2.499868 17.999964 270)
			(size 1.016 1.016)
			(drill 0.7112)
			(layers "*.Cu" "*.Mask")
			(remove_unused_layers no)
			(net "T4_BLAD1_RXD")
			(clearance 0.1016)
			(thermal_gap 0.1016)
		)
		(pad "B18" thru_hole circle
			(at -4.499864 18.999962 270)
			(size 1.016 1.016)
			(drill 0.7112)
			(layers "*.Cu" "*.Mask")
			(remove_unused_layers no)
			(net "T4_BLAD1_TXD")
			(clearance 0.1016)
			(thermal_gap 0.1016)
		)
		(pad "B19" thru_hole circle
			(at -2.499868 19.99996 270)
			(size 1.016 1.016)
			(drill 0.7112)
			(layers "*.Cu" "*.Mask")
			(remove_unused_layers no)
			(net "T4_BLAD2_RXD")
			(clearance 0.1016)
			(thermal_gap 0.1016)
		)
		(pad "B20" thru_hole circle
			(at -4.499864 20.999958 270)
			(size 1.016 1.016)
			(drill 0.7112)
			(layers "*.Cu" "*.Mask")
			(remove_unused_layers no)
			(net "T4_BLAD2_TXD")
			(clearance 0.1016)
			(thermal_gap 0.1016)
		)
		(pad "B21" thru_hole circle
			(at -2.499868 21.999956 270)
			(size 1.016 1.016)
			(drill 0.7112)
			(layers "*.Cu" "*.Mask")
			(remove_unused_layers no)
			(net "GND")
			(clearance 0.1016)
			(thermal_gap 0.1016)
		)
		(pad "B22" thru_hole circle
			(at -4.499864 22.999954 270)
			(size 1.016 1.016)
			(drill 0.7112)
			(layers "*.Cu" "*.Mask")
			(remove_unused_layers no)
			(net "T4_BLAD3_RXD")
			(clearance 0.1016)
			(thermal_gap 0.1016)
		)
		(pad "B23" thru_hole circle
			(at -2.499868 23.999952 270)
			(size 1.016 1.016)
			(drill 0.7112)
			(layers "*.Cu" "*.Mask")
			(remove_unused_layers no)
			(net "T4_BLAD3_TXD")
			(clearance 0.1016)
			(thermal_gap 0.1016)
		)
		(pad "B24" thru_hole circle
			(at -4.499864 24.99995 270)
			(size 1.016 1.016)
			(drill 0.7112)
			(layers "*.Cu" "*.Mask")
			(remove_unused_layers no)
			(net "T4_BLAD4_RXD")
			(clearance 0.1016)
			(thermal_gap 0.1016)
		)
		(pad "B25" thru_hole circle
			(at -2.499868 25.999948 270)
			(size 1.016 1.016)
			(drill 0.7112)
			(layers "*.Cu" "*.Mask")
			(remove_unused_layers no)
			(net "T4_BLAD4_TXD")
			(clearance 0.1016)
			(thermal_gap 0.1016)
		)
		(pad "B26" thru_hole circle
			(at -4.499864 26.999946 270)
			(size 1.016 1.016)
			(drill 0.7112)
			(layers "*.Cu" "*.Mask")
			(remove_unused_layers no)
			(net "GND")
			(clearance 0.1016)
			(thermal_gap 0.1016)
		)
		(pad "B27" thru_hole circle
			(at -2.499868 27.999944 270)
			(size 1.016 1.016)
			(drill 0.7112)
			(layers "*.Cu" "*.Mask")
			(remove_unused_layers no)
			(net "T2_BLAD1_EN")
			(clearance 0.1016)
			(thermal_gap 0.1016)
		)
		(pad "B28" thru_hole circle
			(at -4.499864 28.999942 270)
			(size 1.016 1.016)
			(drill 0.7112)
			(layers "*.Cu" "*.Mask")
			(remove_unused_layers no)
			(net "T2_BLAD2_EN")
			(clearance 0.1016)
			(thermal_gap 0.1016)
		)
		(pad "B29" thru_hole circle
			(at -2.499868 29.99994 270)
			(size 1.016 1.016)
			(drill 0.7112)
			(layers "*.Cu" "*.Mask")
			(remove_unused_layers no)
			(net "T2_BLAD3_EN")
			(clearance 0.1016)
			(thermal_gap 0.1016)
		)
		(pad "B30" thru_hole circle
			(at -4.499864 30.999938 270)
			(size 1.016 1.016)
			(drill 0.7112)
			(layers "*.Cu" "*.Mask")
			(remove_unused_layers no)
			(net "T2_BLAD4_EN")
			(clearance 0.1016)
			(thermal_gap 0.1016)
		)
		(pad "B31" thru_hole circle
			(at -2.499868 31.999936 270)
			(size 1.016 1.016)
			(drill 0.7112)
			(layers "*.Cu" "*.Mask")
			(remove_unused_layers no)
			(net "GND")
			(clearance 0.1016)
			(thermal_gap 0.1016)
		)
		(pad "B32" thru_hole circle
			(at -4.499864 32.999934 270)
			(size 1.016 1.016)
			(drill 0.7112)
			(layers "*.Cu" "*.Mask")
			(remove_unused_layers no)
			(net "T2_BLAD1_RXD")
			(clearance 0.1016)
			(thermal_gap 0.1016)
		)
		(pad "B33" thru_hole circle
			(at -2.499868 33.999932 270)
			(size 1.016 1.016)
			(drill 0.7112)
			(layers "*.Cu" "*.Mask")
			(remove_unused_layers no)
			(net "T2_BLAD1_TXD")
			(clearance 0.1016)
			(thermal_gap 0.1016)
		)
		(pad "B34" thru_hole circle
			(at -4.499864 34.99993 270)
			(size 1.016 1.016)
			(drill 0.7112)
			(layers "*.Cu" "*.Mask")
			(remove_unused_layers no)
			(net "T2_BLAD2_RXD")
			(clearance 0.1016)
			(thermal_gap 0.1016)
		)
		(pad "B35" thru_hole circle
			(at -2.499868 35.999928 270)
			(size 1.016 1.016)
			(drill 0.7112)
			(layers "*.Cu" "*.Mask")
			(remove_unused_layers no)
			(net "T2_BLAD2_TXD")
			(clearance 0.1016)
			(thermal_gap 0.1016)
		)
		(pad "B36" thru_hole circle
			(at -4.499864 36.999926 270)
			(size 1.016 1.016)
			(drill 0.7112)
			(layers "*.Cu" "*.Mask")
			(remove_unused_layers no)
			(net "GND")
			(clearance 0.1016)
			(thermal_gap 0.1016)
		)
		(pad "B37" thru_hole circle
			(at -2.499868 37.999924 270)
			(size 1.016 1.016)
			(drill 0.7112)
			(layers "*.Cu" "*.Mask")
			(remove_unused_layers no)
			(net "T2_BLAD3_RXD")
			(clearance 0.1016)
			(thermal_gap 0.1016)
		)
		(pad "B38" thru_hole circle
			(at -4.499864 38.999922 270)
			(size 1.016 1.016)
			(drill 0.7112)
			(layers "*.Cu" "*.Mask")
			(remove_unused_layers no)
			(net "T2_BLAD3_TXD")
			(clearance 0.1016)
			(thermal_gap 0.1016)
		)
		(pad "B39" thru_hole circle
			(at -2.499868 39.99992 270)
			(size 1.016 1.016)
			(drill 0.7112)
			(layers "*.Cu" "*.Mask")
			(remove_unused_layers no)
			(net "T2_BLAD4_RXD")
			(clearance 0.1016)
			(thermal_gap 0.1016)
		)
		(pad "B40" thru_hole circle
			(at -4.499864 40.999918 270)
			(size 1.016 1.016)
			(drill 0.7112)
			(layers "*.Cu" "*.Mask")
			(remove_unused_layers no)
			(net "T2_BLAD4_TXD")
			(clearance 0.1016)
			(thermal_gap 0.1016)
		)
		(pad "B41" thru_hole circle
			(at -2.499868 41.999916 270)
			(size 1.016 1.016)
			(drill 0.7112)
			(layers "*.Cu" "*.Mask")
			(remove_unused_layers no)
			(net "GND")
			(clearance 0.1016)
			(thermal_gap 0.1016)
		)
		(pad "B42" thru_hole circle
			(at -4.499864 42.999914 270)
			(size 1.016 1.016)
			(drill 0.7112)
			(layers "*.Cu" "*.Mask")
			(remove_unused_layers no)
			(net "I2C_PSU1_SCL")
			(clearance 0.1016)
			(thermal_gap 0.1016)
		)
		(pad "B43" thru_hole circle
			(at -2.499868 43.999912 270)
			(size 1.016 1.016)
			(drill 0.7112)
			(layers "*.Cu" "*.Mask")
			(remove_unused_layers no)
			(net "I2C_PSU1_SDA")
			(clearance 0.1016)
			(thermal_gap 0.1016)
		)
		(pad "B44" thru_hole circle
			(at -4.499864 44.99991 270)
			(size 1.016 1.016)
			(drill 0.7112)
			(layers "*.Cu" "*.Mask")
			(remove_unused_layers no)
			(net "GND")
			(clearance 0.1016)
			(thermal_gap 0.1016)
		)
		(pad "B45" thru_hole circle
			(at -2.499868 45.999908 270)
			(size 1.016 1.016)
			(drill 0.7112)
			(layers "*.Cu" "*.Mask")
			(remove_unused_layers no)
			(net "PSU1_AC_OK")
			(clearance 0.1016)
			(thermal_gap 0.1016)
		)
		(pad "B46" thru_hole circle
			(at -4.499864 46.999906 270)
			(size 1.016 1.016)
			(drill 0.7112)
			(layers "*.Cu" "*.Mask")
			(remove_unused_layers no)
			(net "PSU2_AC_OK")
			(clearance 0.1016)
			(thermal_gap 0.1016)
		)
		(pad "B47" thru_hole circle
			(at -2.499868 47.999904 270)
			(size 1.016 1.016)
			(drill 0.7112)
			(layers "*.Cu" "*.Mask")
			(remove_unused_layers no)
			(net "PSU3_AC_OK")
			(clearance 0.1016)
			(thermal_gap 0.1016)
		)
		(pad "B48" thru_hole circle
			(at -4.499864 48.999902 270)
			(size 1.016 1.016)
			(drill 0.7112)
			(layers "*.Cu" "*.Mask")
			(remove_unused_layers no)
			(net "PSU4_AC_OK")
			(clearance 0.1016)
			(thermal_gap 0.1016)
		)
		(pad "B49" thru_hole circle
			(at -2.499868 49.9999 270)
			(size 1.016 1.016)
			(drill 0.7112)
			(layers "*.Cu" "*.Mask")
			(remove_unused_layers no)
			(net "PSU5_AC_OK")
			(clearance 0.1016)
			(thermal_gap 0.1016)
		)
		(pad "B50" thru_hole circle
			(at -4.499864 50.999898 270)
			(size 1.016 1.016)
			(drill 0.7112)
			(layers "*.Cu" "*.Mask")
			(remove_unused_layers no)
			(net "PSU6_AC_OK")
			(clearance 0.1016)
			(thermal_gap 0.1016)
		)
		(pad "B51" thru_hole circle
			(at -2.499868 51.999896 270)
			(size 1.016 1.016)
			(drill 0.7112)
			(layers "*.Cu" "*.Mask")
			(remove_unused_layers no)
			(net "GND")
			(clearance 0.1016)
			(thermal_gap 0.1016)
		)
		(pad "B52" thru_hole circle
			(at -4.499864 52.999894 270)
			(size 1.016 1.016)
			(drill 0.7112)
			(layers "*.Cu" "*.Mask")
			(remove_unused_layers no)
			(net "UART_RTS_P5_L_N")
			(clearance 0.1016)
			(thermal_gap 0.1016)
		)
		(pad "B53" thru_hole circle
			(at -2.499868 53.999892 270)
			(size 1.016 1.016)
			(drill 0.7112)
			(layers "*.Cu" "*.Mask")
			(remove_unused_layers no)
			(net "UART_DSR_P5_L_N")
			(clearance 0.1016)
			(thermal_gap 0.1016)
		)
		(pad "B54" thru_hole circle
			(at -4.499864 54.99989 270)
			(size 1.016 1.016)
			(drill 0.7112)
			(layers "*.Cu" "*.Mask")
			(remove_unused_layers no)
			(net "UART_RX_P5_L")
			(clearance 0.1016)
			(thermal_gap 0.1016)
		)
		(pad "B55" thru_hole circle
			(at -2.499868 55.999888 270)
			(size 1.016 1.016)
			(drill 0.7112)
			(layers "*.Cu" "*.Mask")
			(remove_unused_layers no)
			(net "UART_TX_P5_L")
			(clearance 0.1016)
			(thermal_gap 0.1016)
		)
		(pad "B56" thru_hole circle
			(at -4.499864 56.999886 270)
			(size 1.016 1.016)
			(drill 0.7112)
			(layers "*.Cu" "*.Mask")
			(remove_unused_layers no)
			(net "UART_DTR_P5_L_N")
			(clearance 0.1016)
			(thermal_gap 0.1016)
		)
		(pad "B57" thru_hole circle
			(at -2.499868 57.999884 270)
			(size 1.016 1.016)
			(drill 0.7112)
			(layers "*.Cu" "*.Mask")
			(remove_unused_layers no)
			(net "UART_CTS_P5_L_N")
			(clearance 0.1016)
			(thermal_gap 0.1016)
		)
		(pad "B58" thru_hole circle
			(at -4.499864 59.000136 270)
			(size 1.016 1.016)
			(drill 0.7112)
			(layers "*.Cu" "*.Mask")
			(remove_unused_layers no)
			(net "UART_RI_P5_L_N")
			(clearance 0.1016)
			(thermal_gap 0.1016)
		)
		(pad "B59" thru_hole circle
			(at -2.499868 59.99988 270)
			(size 1.016 1.016)
			(drill 0.7112)
			(layers "*.Cu" "*.Mask")
			(remove_unused_layers no)
			(net "GND")
			(clearance 0.1016)
			(thermal_gap 0.1016)
		)
		(pad "B60" thru_hole circle
			(at -4.499864 61.000132 270)
			(size 1.016 1.016)
			(drill 0.7112)
			(layers "*.Cu" "*.Mask")
			(remove_unused_layers no)
			(net "UART_RTS_P1_L_N")
			(clearance 0.1016)
			(thermal_gap 0.1016)
		)
		(pad "B61" thru_hole circle
			(at -2.499868 61.999876 270)
			(size 1.016 1.016)
			(drill 0.7112)
			(layers "*.Cu" "*.Mask")
			(remove_unused_layers no)
			(net "UART_DSR_P1_L_N")
			(clearance 0.1016)
			(thermal_gap 0.1016)
		)
		(pad "B62" thru_hole circle
			(at -4.499864 63.000128 270)
			(size 1.016 1.016)
			(drill 0.7112)
			(layers "*.Cu" "*.Mask")
			(remove_unused_layers no)
			(net "UART_RX_P1_L")
			(clearance 0.1016)
			(thermal_gap 0.1016)
		)
		(pad "B63" thru_hole circle
			(at -2.499868 63.999872 270)
			(size 1.016 1.016)
			(drill 0.7112)
			(layers "*.Cu" "*.Mask")
			(remove_unused_layers no)
			(net "UART_TX_P1_L")
			(clearance 0.1016)
			(thermal_gap 0.1016)
		)
		(pad "B64" thru_hole circle
			(at -4.499864 65.000124 270)
			(size 1.016 1.016)
			(drill 0.7112)
			(layers "*.Cu" "*.Mask")
			(remove_unused_layers no)
			(net "UART_DTR_P1_L_N")
			(clearance 0.1016)
			(thermal_gap 0.1016)
		)
		(pad "B65" thru_hole circle
			(at -2.499868 65.999868 270)
			(size 1.016 1.016)
			(drill 0.7112)
			(layers "*.Cu" "*.Mask")
			(remove_unused_layers no)
			(net "UART_CTS_P1_L_N")
			(clearance 0.1016)
			(thermal_gap 0.1016)
		)
		(pad "B66" thru_hole circle
			(at -4.499864 67.00012 270)
			(size 1.016 1.016)
			(drill 0.7112)
			(layers "*.Cu" "*.Mask")
			(remove_unused_layers no)
			(net "GND")
			(clearance 0.1016)
			(thermal_gap 0.1016)
		)
		(pad "B67" thru_hole circle
			(at -2.499868 67.999864 270)
			(size 1.016 1.016)
			(drill 0.7112)
			(layers "*.Cu" "*.Mask")
			(remove_unused_layers no)
			(net "Net_411")
			(clearance 0.1016)
			(thermal_gap 0.1016)
		)
		(pad "B68" thru_hole circle
			(at -4.499864 69.000116 270)
			(size 1.016 1.016)
			(drill 0.7112)
			(layers "*.Cu" "*.Mask")
			(remove_unused_layers no)
			(net "GND28")
			(clearance 0.1016)
			(thermal_gap 0.1016)
		)
		(pad "B69" thru_hole circle
			(at -2.499868 70.000114 270)
			(size 1.016 1.016)
			(drill 0.7112)
			(layers "*.Cu" "*.Mask")
			(remove_unused_layers no)
			(net "GND29")
			(clearance 0.1016)
			(thermal_gap 0.1016)
		)
		(pad "B70" thru_hole circle
			(at -4.499864 71.000112 270)
			(size 1.016 1.016)
			(drill 0.7112)
			(layers "*.Cu" "*.Mask")
			(remove_unused_layers no)
			(net "Net_410")
			(clearance 0.1016)
			(thermal_gap 0.1016)
		)
		(pad "B71" thru_hole circle
			(at -2.499868 72.00011 270)
			(size 1.016 1.016)
			(drill 0.7112)
			(layers "*.Cu" "*.Mask")
			(remove_unused_layers no)
			(net "GND")
			(clearance 0.1016)
			(thermal_gap 0.1016)
		)
		(pad "B72" thru_hole circle
			(at -4.499864 73.000108 270)
			(size 1.016 1.016)
			(drill 0.7112)
			(layers "*.Cu" "*.Mask")
			(remove_unused_layers no)
			(net "LAN1_P3_P")
			(clearance 0.1016)
			(thermal_gap 0.1016)
		)
		(pad "B73" thru_hole circle
			(at -2.499868 74.000106 270)
			(size 1.016 1.016)
			(drill 0.7112)
			(layers "*.Cu" "*.Mask")
			(remove_unused_layers no)
			(net "LAN1_P3_N")
			(clearance 0.1016)
			(thermal_gap 0.1016)
		)
		(pad "B74" thru_hole circle
			(at -4.499864 75.000104 270)
			(size 1.016 1.016)
			(drill 0.7112)
			(layers "*.Cu" "*.Mask")
			(remove_unused_layers no)
			(net "GND")
			(clearance 0.1016)
			(thermal_gap 0.1016)
		)
		(pad "B75" thru_hole circle
			(at -2.499868 76.000102 270)
			(size 1.016 1.016)
			(drill 0.7112)
			(layers "*.Cu" "*.Mask")
			(remove_unused_layers no)
			(net "LAN1_P4_P")
			(clearance 0.1016)
			(thermal_gap 0.1016)
		)
		(pad "B76" thru_hole circle
			(at -4.499864 77.0001 270)
			(size 1.016 1.016)
			(drill 0.7112)
			(layers "*.Cu" "*.Mask")
			(remove_unused_layers no)
			(net "LAN1_P4_N")
			(clearance 0.1016)
			(thermal_gap 0.1016)
		)
		(pad "B77" thru_hole circle
			(at -2.499868 78.000098 270)
			(size 1.016 1.016)
			(drill 0.7112)
			(layers "*.Cu" "*.Mask")
			(remove_unused_layers no)
			(net "GND")
			(clearance 0.1016)
			(thermal_gap 0.1016)
		)
		(pad "B78" thru_hole circle
			(at -4.499864 79.000096 270)
			(size 1.016 1.016)
			(drill 0.7112)
			(layers "*.Cu" "*.Mask")
			(remove_unused_layers no)
			(net "CM_PWR_CTL_IN")
			(clearance 0.1016)
			(thermal_gap 0.1016)
		)
		(pad "B79" thru_hole circle
			(at -2.499868 80.000094 270)
			(size 1.016 1.016)
			(drill 0.7112)
			(layers "*.Cu" "*.Mask")
			(remove_unused_layers no)
			(net "P12V")
			(clearance 0.1016)
			(thermal_gap 0.1016)
		)
		(pad "B80" thru_hole circle
			(at -4.499864 81.000092 270)
			(size 1.016 1.016)
			(drill 0.7112)
			(layers "*.Cu" "*.Mask")
			(remove_unused_layers no)
			(net "P12V")
			(clearance 0.1016)
			(thermal_gap 0.1016)
		)
		(pad "B81" thru_hole circle
			(at -2.499868 82.00009 270)
			(size 1.016 1.016)
			(drill 0.7112)
			(layers "*.Cu" "*.Mask")
			(remove_unused_layers no)
			(net "MATE_A1")
			(clearance 0.1016)
			(thermal_gap 0.1016)
		)
		(pad "B82" thru_hole circle
			(at -4.499864 83.000088 270)
			(size 1.016 1.016)
			(drill 0.7112)
			(layers "*.Cu" "*.Mask")
			(remove_unused_layers no)
			(net "P12V")
			(clearance 0.1016)
			(thermal_gap 0.1016)
		)
		(zone
			(layers "F.Cu" "B.Cu" "In1.Cu" "In2.Cu" "In3.Cu" "In4.Cu" "In5.Cu" "In6.Cu")
			(hatch none 0.5)
			(connect_pads
				(clearance 0)
			)
			(min_thickness 0.25)
			(keepout
				(tracks allowed)
				(vias not_allowed)
				(pads allowed)
				(copperpour not_allowed)
				(footprints allowed)
			)
			(placement
				(enabled no)
				(sheetname "")
			)
			(fill
				(thermal_gap 0.5)
				(thermal_bridge_width 0.5)
				(island_removal_mode 0)
			)
			(polygon
				(pts
					(xy 1.368806 -178.104546) (xy 3.731006 -178.104546) (xy 3.731006 -175.386746) (xy 6.677406 -175.386746)
					(xy 6.677406 -178.104546) (xy 9.014206 -178.104546) (xy 9.014206 -262.254746) (xy 1.368806 -262.254746)
				)
			)
		)
		(zone
			(layers "F.Cu" "B.Cu" "In1.Cu" "In2.Cu" "In3.Cu" "In4.Cu" "In5.Cu" "In6.Cu")
			(hatch none 0.5)
			(connect_pads
				(clearance 0)
			)
			(min_thickness 0.25)
			(keepout
				(tracks not_allowed)
				(vias allowed)
				(pads allowed)
				(copperpour not_allowed)
				(footprints allowed)
			)
			(placement
				(enabled no)
				(sheetname "")
			)
			(fill
				(thermal_gap 0.5)
				(thermal_bridge_width 0.5)
				(island_removal_mode 0)
			)
			(polygon
				(pts
					(arc
						(start 3.58267 -250.020582)
						(mid 3.674142 -250.556339)
						(end 3.938016 -251.031502)
					)
					(xy 4.566412 -251.031502)
					(arc
						(start 4.566412 -251.507752)
						(mid 5.200269 -251.636551)
						(end 5.833872 -251.506482)
					)
					(xy 5.833872 -251.039376)
					(arc
						(start 6.453124 -251.039376)
						(mid 5.739145 -248.497573)
						(end 3.58267 -250.020582)
					)
				)
			)
		)
	)
	(footprint ""
		(layer "F.Cu")
		(at 27.16911 -373.43207)
		(property "Reference" "R19"
			(at -3.196844 0.148336 0)
			(unlocked yes)
			(layer "F.SilkS")
			(effects
				(font
					(size 0.7874 0.5842)
					(thickness 0.1524)
				)
				(justify left)
			)
		)
		(property "Value" ""
			(at 0 0 0)
			(layer "F.Fab")
			(effects
				(font
					(size 1.27 1.27)
				)
			)
		)
		(duplicate_pad_numbers_are_jumpers no)
		(fp_line
			(start -0.7874 -0.4064)
			(end 0.7874 -0.4064)
			(stroke
				(width 0.1524)
				(type default)
			)
			(layer "F.SilkS")
		)
		(fp_line
			(start -0.7874 0.4064)
			(end -0.7874 -0.4064)
			(stroke
				(width 0.1524)
				(type default)
			)
			(layer "F.SilkS")
		)
		(fp_line
			(start 0.7874 -0.4064)
			(end 0.7874 0.4064)
			(stroke
				(width 0.1524)
				(type default)
			)
			(layer "F.SilkS")
		)
		(fp_line
			(start 0.7874 0.4064)
			(end -0.7874 0.4064)
			(stroke
				(width 0.1524)
				(type default)
			)
			(layer "F.SilkS")
		)
		(fp_poly
			(pts
				(xy -0.508 0.2794) (xy -0.508 0.2286) (xy -0.635 0.2286) (xy -0.635 -0.254) (xy -0.5334 -0.254)
				(xy -0.5334 -0.2794) (xy 0.5334 -0.2794) (xy 0.5334 -0.254) (xy 0.635 -0.254) (xy 0.635 0.254) (xy 0.5334 0.254)
				(xy 0.5334 0.2794)
			)
			(stroke
				(width 0)
				(type default)
			)
			(fill no)
			(layer "F.CrtYd")
		)
		(pad "1" smd rect
			(at 0.40005 0)
			(size 0.4572 0.508)
			(layers "F.Cu" "F.Mask" "F.Paste")
			(net "PSU5_REMOTE_N")
		)
		(pad "2" smd rect
			(at -0.40005 0)
			(size 0.4572 0.508)
			(layers "F.Cu" "F.Mask" "F.Paste")
			(net "GND")
		)
	)
	(footprint ""
		(layer "F.Cu")
		(at 26.102056 -276.12213)
		(property "Reference" "R75"
			(at -4.037838 -0.005334 0)
			(unlocked yes)
			(layer "F.SilkS")
			(effects
				(font
					(size 0.7874 0.5842)
					(thickness 0.1524)
				)
				(justify left)
			)
		)
		(property "Value" ""
			(at 0 0 0)
			(layer "F.Fab")
			(effects
				(font
					(size 1.27 1.27)
				)
			)
		)
		(duplicate_pad_numbers_are_jumpers no)
		(fp_line
			(start -0.7874 -0.4064)
			(end 0.7874 -0.4064)
			(stroke
				(width 0.1524)
				(type default)
			)
			(layer "F.SilkS")
		)
		(fp_line
			(start -0.7874 0.4064)
			(end -0.7874 -0.4064)
			(stroke
				(width 0.1524)
				(type default)
			)
			(layer "F.SilkS")
		)
		(fp_line
			(start 0.7874 -0.4064)
			(end 0.7874 0.4064)
			(stroke
				(width 0.1524)
				(type default)
			)
			(layer "F.SilkS")
		)
		(fp_line
			(start 0.7874 0.4064)
			(end -0.7874 0.4064)
			(stroke
				(width 0.1524)
				(type default)
			)
			(layer "F.SilkS")
		)
		(fp_poly
			(pts
				(xy -0.508 0.2794) (xy -0.508 0.2286) (xy -0.635 0.2286) (xy -0.635 -0.254) (xy -0.5334 -0.254)
				(xy -0.5334 -0.2794) (xy 0.5334 -0.2794) (xy 0.5334 -0.254) (xy 0.635 -0.254) (xy 0.635 0.254) (xy 0.5334 0.254)
				(xy 0.5334 0.2794)
			)
			(stroke
				(width 0)
				(type default)
			)
			(fill no)
			(layer "F.CrtYd")
		)
		(pad "1" smd rect
			(at 0.40005 0)
			(size 0.4572 0.508)
			(layers "F.Cu" "F.Mask" "F.Paste")
			(net "PSU4_PS_KILL")
		)
		(pad "2" smd rect
			(at -0.40005 0)
			(size 0.4572 0.508)
			(layers "F.Cu" "F.Mask" "F.Paste")
			(net "GND")
		)
	)
	(footprint ""
		(layer "F.Cu")
		(at 50.217578 -84.273644 180)
		(property "Reference" "CE4"
			(at 1.809242 -5.224018 0)
			(unlocked yes)
			(layer "F.SilkS")
			(effects
				(font
					(size 0.7874 0.5842)
					(thickness 0.1524)
				)
				(justify left)
			)
		)
		(property "Value" ""
			(at 0 0 180)
			(layer "F.Fab")
			(effects
				(font
					(size 1.27 1.27)
				)
			)
		)
		(duplicate_pad_numbers_are_jumpers no)
		(fp_line
			(start 0 -4.2672)
			(end 0 4.2672)
			(stroke
				(width 0.1524)
				(type default)
			)
			(layer "F.SilkS")
		)
		(fp_circle
			(center 0 0)
			(end -4.2672 0)
			(stroke
				(width 0.1524)
				(type default)
			)
			(fill no)
			(layer "F.SilkS")
		)
		(fp_poly
			(pts
				(arc
					(start 0 -4.2672)
					(mid 4.2672 0)
					(end 0 4.2672)
				)
			)
			(stroke
				(width 0)
				(type default)
			)
			(fill yes)
			(layer "F.SilkS")
		)
		(fp_poly
			(pts
				(xy -2.5146 -0.762) (xy -0.9906 -0.762) (xy -0.9906 0.762) (xy -2.5146 0.762)
			)
			(stroke
				(width 0)
				(type default)
			)
			(fill no)
			(layer "B.CrtYd")
		)
		(fp_poly
			(pts
				(arc
					(start 1.7526 0.762)
					(mid 2.291415 -0.538815)
					(end 0.9906 0)
				)
				(arc
					(start 0.9906 0.0254)
					(mid 1.206345 0.546255)
					(end 1.7272 0.762)
				)
			)
			(stroke
				(width 0)
				(type default)
			)
			(fill no)
			(layer "B.CrtYd")
		)
		(fp_poly
			(pts
				(arc
					(start -4.2672 0)
					(mid 4.2672 0)
					(end -4.2672 0)
				)
			)
			(stroke
				(width 0)
				(type default)
			)
			(fill no)
			(layer "F.CrtYd")
		)
		(fp_circle
			(center 0 0)
			(end -4.2672 0)
			(stroke
				(width 0.1)
				(type default)
			)
			(fill no)
			(layer "F.Fab")
		)
		(fp_text user "+"
			(at -3.604514 -3.626866 180)
			(unlocked yes)
			(layer "F.SilkS")
			(effects
				(font
					(size 0.7874 0.5842)
					(thickness 0.1524)
				)
				(justify left)
			)
		)
		(fp_text user "+"
			(at -5.6642 -0.34925 180)
			(unlocked yes)
			(layer "F.Fab")
			(effects
				(font
					(size 1.905 1.4224)
					(thickness 0.000001)
				)
				(justify left)
			)
		)
		(pad "1" thru_hole rect
			(at -1.75006 0 180)
			(size 1.397 1.397)
			(drill 0.9144)
			(layers "*.Cu" "*.Mask")
			(remove_unused_layers no)
			(net "P12V")
			(clearance 0.0127)
			(thermal_gap 0.0127)
			(padstack
				(mode front_inner_back)
				(layer "Inner"
					(shape circle)
					(size 1.397 1.397)
					(clearance 0.0127)
				)
				(layer "B.Cu"
					(shape rect)
					(size 1.397 1.397)
					(clearance 0.0127)
				)
			)
		)
		(pad "2" thru_hole circle
			(at 1.75006 0 180)
			(size 1.397 1.397)
			(drill 0.9144)
			(layers "*.Cu" "*.Mask")
			(remove_unused_layers no)
			(net "GND")
			(clearance 0.0127)
			(thermal_gap 0.0127)
		)
	)
	(footprint ""
		(layer "F.Cu")
		(at 73.914508 -104.75976 -90)
		(property "Reference" "C17"
			(at -2.68224 -0.080772 90)
			(unlocked yes)
			(layer "F.SilkS")
			(effects
				(font
					(size 0.7874 0.5842)
					(thickness 0.1524)
				)
				(justify left)
			)
		)
		(property "Value" ""
			(at 0 0 270)
			(layer "F.Fab")
			(effects
				(font
					(size 1.27 1.27)
				)
			)
		)
		(duplicate_pad_numbers_are_jumpers no)
		(fp_line
			(start -0.7874 0.4064)
			(end -0.7874 -0.4064)
			(stroke
				(width 0.1524)
				(type default)
			)
			(layer "F.SilkS")
		)
		(fp_line
			(start 0.7874 0.4064)
			(end -0.7874 0.4064)
			(stroke
				(width 0.1524)
				(type default)
			)
			(layer "F.SilkS")
		)
		(fp_line
			(start 0 0.381)
			(end 0 -0.381)
			(stroke
				(width 0.1524)
				(type default)
			)
			(layer "F.SilkS")
		)
		(fp_line
			(start -0.7874 -0.4064)
			(end 0.7874 -0.4064)
			(stroke
				(width 0.1524)
				(type default)
			)
			(layer "F.SilkS")
		)
		(fp_line
			(start 0.7874 -0.4064)
			(end 0.7874 0.4064)
			(stroke
				(width 0.1524)
				(type default)
			)
			(layer "F.SilkS")
		)
		(fp_poly
			(pts
				(xy -0.5334 0.254) (xy -0.635 0.254) (xy -0.635 0.2286) (xy -0.635 -0.254) (xy -0.5334 -0.254) (xy -0.5334 -0.2794)
				(xy 0.5334 -0.2794) (xy 0.5334 -0.254) (xy 0.635 -0.254) (xy 0.635 0.254) (xy 0.5334 0.254) (xy 0.5334 0.2794)
				(xy -0.508 0.2794) (xy -0.5334 0.2794)
			)
			(stroke
				(width 0)
				(type default)
			)
			(fill no)
			(layer "F.CrtYd")
		)
		(pad "1" smd rect
			(at 0.40005 0 270)
			(size 0.4572 0.508)
			(layers "F.Cu" "F.Mask" "F.Paste")
			(net "P12V")
		)
		(pad "2" smd rect
			(at -0.40005 0 270)
			(size 0.4572 0.508)
			(layers "F.Cu" "F.Mask" "F.Paste")
			(net "GND")
		)
	)
	(footprint ""
		(layer "F.Cu")
		(at 70.095364 -238.216694 -90)
		(property "Reference" "C36"
			(at 0.16256 -3.77825 90)
			(unlocked yes)
			(layer "F.SilkS")
			(effects
				(font
					(size 0.7874 0.5842)
					(thickness 0.1524)
				)
			)
		)
		(property "Value" ""
			(at 0 0 270)
			(layer "F.Fab")
			(effects
				(font
					(size 1.27 1.27)
				)
			)
		)
		(duplicate_pad_numbers_are_jumpers no)
		(fp_line
			(start -1.2954 0.5842)
			(end -1.2954 -0.5842)
			(stroke
				(width 0.1524)
				(type default)
			)
			(layer "F.SilkS")
		)
		(fp_line
			(start 1.2954 0.5842)
			(end -1.2954 0.5842)
			(stroke
				(width 0.1524)
				(type default)
			)
			(layer "F.SilkS")
		)
		(fp_line
			(start -1.2954 -0.5842)
			(end 1.2954 -0.5842)
			(stroke
				(width 0.1524)
				(type default)
			)
			(layer "F.SilkS")
		)
		(fp_line
			(start 0 -0.5842)
			(end 0 0.5842)
			(stroke
				(width 0.1524)
				(type default)
			)
			(layer "F.SilkS")
		)
		(fp_line
			(start 1.2954 -0.5842)
			(end 1.2954 0.5842)
			(stroke
				(width 0.1524)
				(type default)
			)
			(layer "F.SilkS")
		)
		(fp_poly
			(pts
				(xy 0.8636 -0.4572) (xy 0.8636 -0.3556) (xy 1.143 -0.3556) (xy 1.143 0.3556) (xy 0.8636 0.3556)
				(xy 0.8636 0.4572) (xy -0.8636 0.4572) (xy -0.8636 0.3556) (xy -1.143 0.3556) (xy -1.143 -0.3556)
				(xy -0.8636 -0.3556) (xy -0.8636 -0.4572)
			)
			(stroke
				(width 0)
				(type default)
			)
			(fill no)
			(layer "F.CrtYd")
		)
		(fp_line
			(start -0.884936 0.504952)
			(end -0.884936 -0.504952)
			(stroke
				(width 0.1)
				(type default)
			)
			(layer "F.Fab")
		)
		(fp_line
			(start 0.884936 0.504952)
			(end -0.884936 0.504952)
			(stroke
				(width 0.1)
				(type default)
			)
			(layer "F.Fab")
		)
		(fp_line
			(start -0.884936 -0.504952)
			(end 0.884936 -0.504952)
			(stroke
				(width 0.1)
				(type default)
			)
			(layer "F.Fab")
		)
		(fp_line
			(start 0.884936 -0.504952)
			(end 0.884936 0.504952)
			(stroke
				(width 0.1)
				(type default)
			)
			(layer "F.Fab")
		)
		(pad "1" smd rect
			(at 0.7366 0)
			(size 0.7112 0.8128)
			(layers "F.Cu" "F.Mask" "F.Paste")
			(net "P12V")
		)
		(pad "2" smd rect
			(at -0.7366 0)
			(size 0.7112 0.8128)
			(layers "F.Cu" "F.Mask" "F.Paste")
			(net "GND")
		)
	)
	(footprint ""
		(layer "F.Cu")
		(at 30.45968 -525.329912)
		(property "Reference" "J6"
			(at 8.641842 9.092438 90)
			(unlocked yes)
			(layer "F.SilkS")
			(effects
				(font
					(size 0.7874 0.5842)
					(thickness 0.1524)
				)
				(justify left)
			)
		)
		(property "Value" ""
			(at 0 0 0)
			(layer "F.Fab")
			(effects
				(font
					(size 1.27 1.27)
				)
			)
		)
		(duplicate_pad_numbers_are_jumpers no)
		(fp_line
			(start -2.135124 -4.560062)
			(end -2.135124 83.300062)
			(stroke
				(width 0.1524)
				(type default)
			)
			(layer "F.SilkS")
		)
		(fp_line
			(start -2.135124 83.300062)
			(end 7.215124 83.300062)
			(stroke
				(width 0.1524)
				(type default)
			)
			(layer "F.SilkS")
		)
		(fp_line
			(start 7.215124 -4.560062)
			(end -2.135124 -4.560062)
			(stroke
				(width 0.1524)
				(type default)
			)
			(layer "F.SilkS")
		)
		(fp_line
			(start 7.215124 83.300062)
			(end 7.215124 -4.560062)
			(stroke
				(width 0.1524)
				(type default)
			)
			(layer "F.SilkS")
		)
		(fp_poly
			(pts
				(xy -2.491486 0.079248) (xy -5.191506 -0.620776) (xy -5.191506 0.779272)
			)
			(stroke
				(width 0)
				(type default)
			)
			(fill yes)
			(layer "F.SilkS")
		)
		(fp_poly
			(pts
				(xy -2.28219 -0.127) (xy -4.98221 -0.827024) (xy -4.98221 0.573024)
			)
			(stroke
				(width 0)
				(type default)
			)
			(fill yes)
			(layer "B.SilkS")
		)
		(fp_poly
			(pts
				(xy -0.8636 -0.8636) (xy -0.8636 79.6036) (xy -0.8636 79.629) (xy 5.9436 79.629) (xy 5.9436 79.6036)
				(xy 5.9436 -0.8636) (xy 5.9436 -0.889) (xy -0.8636 -0.889)
			)
			(stroke
				(width 0)
				(type default)
			)
			(fill no)
			(layer "B.CrtYd")
		)
		(fp_rect
			(start -2.135124 -4.560062)
			(end 7.21487 83.300062)
			(stroke
				(width 0)
				(type default)
			)
			(fill no)
			(layer "F.CrtYd")
		)
		(fp_line
			(start -2.135124 -4.560062)
			(end 7.215124 -4.560062)
			(stroke
				(width 0.1)
				(type default)
			)
			(layer "F.Fab")
		)
		(fp_line
			(start -2.135124 83.300062)
			(end -2.135124 -4.560062)
			(stroke
				(width 0.1)
				(type default)
			)
			(layer "F.Fab")
		)
		(fp_line
			(start 7.215124 -4.560062)
			(end 7.215124 83.300062)
			(stroke
				(width 0.1)
				(type default)
			)
			(layer "F.Fab")
		)
		(fp_line
			(start 7.215124 83.300062)
			(end -2.135124 83.300062)
			(stroke
				(width 0.1)
				(type default)
			)
			(layer "F.Fab")
		)
		(fp_text user "32"
			(at -4.215638 79.904082 0)
			(unlocked yes)
			(layer "F.SilkS")
			(effects
				(font
					(size 0.7874 0.5842)
					(thickness 0.1524)
				)
				(justify left)
			)
		)
		(fp_text user "1"
			(at -3.120644 -1.027176 0)
			(unlocked yes)
			(layer "F.SilkS")
			(effects
				(font
					(size 0.7874 0.5842)
					(thickness 0.1524)
				)
				(justify left)
			)
		)
		(fp_text user "64"
			(at 7.523988 -0.308864 0)
			(unlocked yes)
			(layer "F.SilkS")
			(effects
				(font
					(size 0.7874 0.5842)
					(thickness 0.1524)
				)
				(justify left)
			)
		)
		(fp_text user "33"
			(at 7.80161 81.392268 0)
			(unlocked yes)
			(layer "F.SilkS")
			(effects
				(font
					(size 0.7874 0.5842)
					(thickness 0.1524)
				)
				(justify left)
			)
		)
		(fp_text user "32"
			(at -1.360678 79.256636 0)
			(unlocked yes)
			(layer "B.SilkS")
			(effects
				(font
					(size 0.7874 0.5842)
					(thickness 0.1524)
				)
				(justify left mirror)
			)
		)
		(fp_text user "1"
			(at -1.297686 -1.511046 0)
			(unlocked yes)
			(layer "B.SilkS")
			(effects
				(font
					(size 0.7874 0.5842)
					(thickness 0.1524)
				)
				(justify left mirror)
			)
		)
		(fp_text user "33"
			(at 5.67055 81.353152 0)
			(unlocked yes)
			(layer "B.SilkS")
			(effects
				(font
					(size 0.7874 0.5842)
					(thickness 0.1524)
				)
				(justify left mirror)
			)
		)
		(fp_text user "64"
			(at 5.908802 -1.856994 0)
			(unlocked yes)
			(layer "B.SilkS")
			(effects
				(font
					(size 0.7874 0.5842)
					(thickness 0.1524)
				)
				(justify left mirror)
			)
		)
		(pad "1" thru_hole rect
			(at 0 0 270)
			(size 1.6256 1.6256)
			(drill 1.1176)
			(layers "*.Cu" "*.Mask")
			(remove_unused_layers no)
			(net "P12V")
			(clearance 0)
			(padstack
				(mode front_inner_back)
				(layer "Inner"
					(shape circle)
					(size 1.6256 1.6256)
					(clearance 0)
				)
				(layer "B.Cu"
					(shape rect)
					(size 1.6256 1.6256)
					(clearance 0)
				)
			)
		)
		(pad "2" thru_hole circle
			(at 0 2.54 270)
			(size 1.6256 1.6256)
			(drill 1.1176)
			(layers "*.Cu" "*.Mask")
			(remove_unused_layers no)
			(net "P12V")
			(clearance 0)
		)
		(pad "3" thru_hole circle
			(at 0 5.08 270)
			(size 1.6256 1.6256)
			(drill 1.1176)
			(layers "*.Cu" "*.Mask")
			(remove_unused_layers no)
			(net "P12V")
			(clearance 0)
		)
		(pad "4" thru_hole circle
			(at 0 7.62 270)
			(size 1.6256 1.6256)
			(drill 1.1176)
			(layers "*.Cu" "*.Mask")
			(remove_unused_layers no)
			(net "P12V")
			(clearance 0)
		)
		(pad "5" thru_hole circle
			(at 0 10.16 270)
			(size 1.6256 1.6256)
			(drill 1.1176)
			(layers "*.Cu" "*.Mask")
			(remove_unused_layers no)
			(net "P12V")
			(clearance 0)
		)
		(pad "6" thru_hole circle
			(at 0 12.7 270)
			(size 1.6256 1.6256)
			(drill 1.1176)
			(layers "*.Cu" "*.Mask")
			(remove_unused_layers no)
			(net "P12V")
			(clearance 0)
		)
		(pad "7" thru_hole circle
			(at 0 15.24 270)
			(size 1.6256 1.6256)
			(drill 1.1176)
			(layers "*.Cu" "*.Mask")
			(remove_unused_layers no)
			(net "P12V")
			(clearance 0)
		)
		(pad "8" thru_hole circle
			(at 0 17.78 270)
			(size 1.6256 1.6256)
			(drill 1.1176)
			(layers "*.Cu" "*.Mask")
			(remove_unused_layers no)
			(net "P12V")
			(clearance 0)
		)
		(pad "9" thru_hole circle
			(at 0 20.32 270)
			(size 1.6256 1.6256)
			(drill 1.1176)
			(layers "*.Cu" "*.Mask")
			(remove_unused_layers no)
			(net "P12V")
			(clearance 0)
		)
		(pad "10" thru_hole circle
			(at 0 22.86 270)
			(size 1.6256 1.6256)
			(drill 1.1176)
			(layers "*.Cu" "*.Mask")
			(remove_unused_layers no)
			(net "P12V")
			(clearance 0)
		)
		(pad "11" thru_hole circle
			(at 0 25.4 270)
			(size 1.6256 1.6256)
			(drill 1.1176)
			(layers "*.Cu" "*.Mask")
			(remove_unused_layers no)
			(net "P12V")
			(clearance 0)
		)
		(pad "12" thru_hole circle
			(at 0 27.94 270)
			(size 1.6256 1.6256)
			(drill 1.1176)
			(layers "*.Cu" "*.Mask")
			(remove_unused_layers no)
			(net "P12V")
			(clearance 0)
		)
		(pad "13" thru_hole circle
			(at 0 30.48 270)
			(size 1.6256 1.6256)
			(drill 1.1176)
			(layers "*.Cu" "*.Mask")
			(remove_unused_layers no)
			(net "GND")
			(clearance 0)
		)
		(pad "14" thru_hole circle
			(at 0 33.02 270)
			(size 1.6256 1.6256)
			(drill 1.1176)
			(layers "*.Cu" "*.Mask")
			(remove_unused_layers no)
			(net "GND")
			(clearance 0)
		)
		(pad "15" thru_hole circle
			(at 0 35.56 270)
			(size 1.6256 1.6256)
			(drill 1.1176)
			(layers "*.Cu" "*.Mask")
			(remove_unused_layers no)
			(net "GND")
			(clearance 0)
		)
		(pad "16" thru_hole circle
			(at 0 38.1 270)
			(size 1.6256 1.6256)
			(drill 1.1176)
			(layers "*.Cu" "*.Mask")
			(remove_unused_layers no)
			(net "GND")
			(clearance 0)
		)
		(pad "17" thru_hole circle
			(at 0 40.64 270)
			(size 1.6256 1.6256)
			(drill 1.1176)
			(layers "*.Cu" "*.Mask")
			(remove_unused_layers no)
			(net "GND")
			(clearance 0)
		)
		(pad "18" thru_hole circle
			(at 0 43.18 270)
			(size 1.6256 1.6256)
			(drill 1.1176)
			(layers "*.Cu" "*.Mask")
			(remove_unused_layers no)
			(net "GND")
			(clearance 0)
		)
		(pad "19" thru_hole circle
			(at 0 45.72 270)
			(size 1.6256 1.6256)
			(drill 1.1176)
			(layers "*.Cu" "*.Mask")
			(remove_unused_layers no)
			(net "GND")
			(clearance 0)
		)
		(pad "20" thru_hole circle
			(at 0 48.26 270)
			(size 1.6256 1.6256)
			(drill 1.1176)
			(layers "*.Cu" "*.Mask")
			(remove_unused_layers no)
			(net "GND")
			(clearance 0)
		)
		(pad "21" thru_hole circle
			(at 0 50.8 270)
			(size 1.6256 1.6256)
			(drill 1.1176)
			(layers "*.Cu" "*.Mask")
			(remove_unused_layers no)
			(net "GND")
			(clearance 0)
		)
		(pad "22" thru_hole circle
			(at 0 53.34 270)
			(size 1.6256 1.6256)
			(drill 1.1176)
			(layers "*.Cu" "*.Mask")
			(remove_unused_layers no)
			(net "GND")
			(clearance 0)
		)
		(pad "23" thru_hole circle
			(at 0 55.88 270)
			(size 1.6256 1.6256)
			(drill 1.1176)
			(layers "*.Cu" "*.Mask")
			(remove_unused_layers no)
			(net "GND")
			(clearance 0)
		)
		(pad "24" thru_hole circle
			(at 0 58.42 270)
			(size 1.6256 1.6256)
			(drill 1.1176)
			(layers "*.Cu" "*.Mask")
			(remove_unused_layers no)
			(net "GND")
			(clearance 0)
		)
		(pad "25" thru_hole circle
			(at 0 60.96 270)
			(size 1.6256 1.6256)
			(drill 1.1176)
			(layers "*.Cu" "*.Mask")
			(remove_unused_layers no)
			(net "Net_397")
			(clearance 0)
		)
		(pad "26" thru_hole circle
			(at 0 63.5 270)
			(size 1.6256 1.6256)
			(drill 1.1176)
			(layers "*.Cu" "*.Mask")
			(remove_unused_layers no)
			(net "PSU6_REMOTE_N")
			(clearance 0)
		)
		(pad "27" thru_hole circle
			(at 0 66.04 270)
			(size 1.6256 1.6256)
			(drill 1.1176)
			(layers "*.Cu" "*.Mask")
			(remove_unused_layers no)
			(net "PSU6_AC_OK")
			(clearance 0)
		)
		(pad "28" thru_hole circle
			(at 0 68.58 270)
			(size 1.6256 1.6256)
			(drill 1.1176)
			(layers "*.Cu" "*.Mask")
			(remove_unused_layers no)
			(net "PSU6_CSAHRE")
			(clearance 0)
		)
		(pad "29" thru_hole circle
			(at 0 71.12 270)
			(size 1.6256 1.6256)
			(drill 1.1176)
			(layers "*.Cu" "*.Mask")
			(remove_unused_layers no)
			(net "PSU6_PS_ON_N")
			(clearance 0)
		)
		(pad "30" thru_hole circle
			(at 0 73.66 270)
			(size 1.6256 1.6256)
			(drill 1.1176)
			(layers "*.Cu" "*.Mask")
			(remove_unused_layers no)
			(net "PSU6_PS_KILL")
			(clearance 0)
		)
		(pad "31" thru_hole circle
			(at 0 76.2 270)
			(size 1.6256 1.6256)
			(drill 1.1176)
			(layers "*.Cu" "*.Mask")
			(remove_unused_layers no)
			(net "PSU6_RESET")
			(clearance 0)
		)
		(pad "32" thru_hole circle
			(at 0 78.74 270)
			(size 1.6256 1.6256)
			(drill 1.1176)
			(layers "*.Cu" "*.Mask")
			(remove_unused_layers no)
			(net "PSU_ALERT_N")
			(clearance 0)
		)
		(pad "33" thru_hole circle
			(at 5.08 78.74 270)
			(size 1.6256 1.6256)
			(drill 1.1176)
			(layers "*.Cu" "*.Mask")
			(remove_unused_layers no)
			(net "I2C_PSU3_SDA")
			(clearance 0)
		)
		(pad "34" thru_hole circle
			(at 5.08 76.2 270)
			(size 1.6256 1.6256)
			(drill 1.1176)
			(layers "*.Cu" "*.Mask")
			(remove_unused_layers no)
			(net "Net_398")
			(clearance 0)
		)
		(pad "35" thru_hole circle
			(at 5.08 73.66 270)
			(size 1.6256 1.6256)
			(drill 1.1176)
			(layers "*.Cu" "*.Mask")
			(remove_unused_layers no)
			(net "I2C_PSU3_SCL")
			(clearance 0)
		)
		(pad "36" thru_hole circle
			(at 5.08 71.12 270)
			(size 1.6256 1.6256)
			(drill 1.1176)
			(layers "*.Cu" "*.Mask")
			(remove_unused_layers no)
			(net "PSU6_RETURN")
			(clearance 0)
		)
		(pad "37" thru_hole circle
			(at 5.08 68.58 270)
			(size 1.6256 1.6256)
			(drill 1.1176)
			(layers "*.Cu" "*.Mask")
			(remove_unused_layers no)
			(net "PSU6_DC_OK")
			(clearance 0)
		)
		(pad "38" thru_hole circle
			(at 5.08 66.04 270)
			(size 1.6256 1.6256)
			(drill 1.1176)
			(layers "*.Cu" "*.Mask")
			(remove_unused_layers no)
			(net "PSU6_AD0")
			(clearance 0)
		)
		(pad "39" thru_hole circle
			(at 5.08 63.5 270)
			(size 1.6256 1.6256)
			(drill 1.1176)
			(layers "*.Cu" "*.Mask")
			(remove_unused_layers no)
			(net "P12V_STBY")
			(clearance 0)
		)
		(pad "40" thru_hole circle
			(at 5.08 60.96 270)
			(size 1.6256 1.6256)
			(drill 1.1176)
			(layers "*.Cu" "*.Mask")
			(remove_unused_layers no)
			(net "PSU6_REMOTE_P")
			(clearance 0)
		)
		(pad "41" thru_hole circle
			(at 5.08 58.42 270)
			(size 1.6256 1.6256)
			(drill 1.1176)
			(layers "*.Cu" "*.Mask")
			(remove_unused_layers no)
			(net "GND")
			(clearance 0)
		)
		(pad "42" thru_hole circle
			(at 5.08 55.88 270)
			(size 1.6256 1.6256)
			(drill 1.1176)
			(layers "*.Cu" "*.Mask")
			(remove_unused_layers no)
			(net "GND")
			(clearance 0)
		)
		(pad "43" thru_hole circle
			(at 5.08 53.34 270)
			(size 1.6256 1.6256)
			(drill 1.1176)
			(layers "*.Cu" "*.Mask")
			(remove_unused_layers no)
			(net "GND")
			(clearance 0)
		)
		(pad "44" thru_hole circle
			(at 5.08 50.8 270)
			(size 1.6256 1.6256)
			(drill 1.1176)
			(layers "*.Cu" "*.Mask")
			(remove_unused_layers no)
			(net "GND")
			(clearance 0)
		)
		(pad "45" thru_hole circle
			(at 5.08 48.26 270)
			(size 1.6256 1.6256)
			(drill 1.1176)
			(layers "*.Cu" "*.Mask")
			(remove_unused_layers no)
			(net "GND")
			(clearance 0)
		)
		(pad "46" thru_hole circle
			(at 5.08 45.72 270)
			(size 1.6256 1.6256)
			(drill 1.1176)
			(layers "*.Cu" "*.Mask")
			(remove_unused_layers no)
			(net "GND")
			(clearance 0)
		)
		(pad "47" thru_hole circle
			(at 5.08 43.18 270)
			(size 1.6256 1.6256)
			(drill 1.1176)
			(layers "*.Cu" "*.Mask")
			(remove_unused_layers no)
			(net "GND")
			(clearance 0)
		)
		(pad "48" thru_hole circle
			(at 5.08 40.64 270)
			(size 1.6256 1.6256)
			(drill 1.1176)
			(layers "*.Cu" "*.Mask")
			(remove_unused_layers no)
			(net "GND")
			(clearance 0)
		)
		(pad "49" thru_hole circle
			(at 5.08 38.1 270)
			(size 1.6256 1.6256)
			(drill 1.1176)
			(layers "*.Cu" "*.Mask")
			(remove_unused_layers no)
			(net "GND")
			(clearance 0)
		)
		(pad "50" thru_hole circle
			(at 5.08 35.56 270)
			(size 1.6256 1.6256)
			(drill 1.1176)
			(layers "*.Cu" "*.Mask")
			(remove_unused_layers no)
			(net "GND")
			(clearance 0)
		)
		(pad "51" thru_hole circle
			(at 5.08 33.02 270)
			(size 1.6256 1.6256)
			(drill 1.1176)
			(layers "*.Cu" "*.Mask")
			(remove_unused_layers no)
			(net "GND")
			(clearance 0)
		)
		(pad "52" thru_hole circle
			(at 5.08 30.48 270)
			(size 1.6256 1.6256)
			(drill 1.1176)
			(layers "*.Cu" "*.Mask")
			(remove_unused_layers no)
			(net "GND")
			(clearance 0)
		)
		(pad "53" thru_hole circle
			(at 5.08 27.94 270)
			(size 1.6256 1.6256)
			(drill 1.1176)
			(layers "*.Cu" "*.Mask")
			(remove_unused_layers no)
			(net "P12V")
			(clearance 0)
		)
		(pad "54" thru_hole circle
			(at 5.08 25.4 270)
			(size 1.6256 1.6256)
			(drill 1.1176)
			(layers "*.Cu" "*.Mask")
			(remove_unused_layers no)
			(net "P12V")
			(clearance 0)
		)
		(pad "55" thru_hole circle
			(at 5.08 22.86 270)
			(size 1.6256 1.6256)
			(drill 1.1176)
			(layers "*.Cu" "*.Mask")
			(remove_unused_layers no)
			(net "P12V")
			(clearance 0)
		)
		(pad "56" thru_hole circle
			(at 5.08 20.32 270)
			(size 1.6256 1.6256)
			(drill 1.1176)
			(layers "*.Cu" "*.Mask")
			(remove_unused_layers no)
			(net "P12V")
			(clearance 0)
		)
		(pad "57" thru_hole circle
			(at 5.08 17.78 270)
			(size 1.6256 1.6256)
			(drill 1.1176)
			(layers "*.Cu" "*.Mask")
			(remove_unused_layers no)
			(net "P12V")
			(clearance 0)
		)
		(pad "58" thru_hole circle
			(at 5.08 15.24 270)
			(size 1.6256 1.6256)
			(drill 1.1176)
			(layers "*.Cu" "*.Mask")
			(remove_unused_layers no)
			(net "P12V")
			(clearance 0)
		)
		(pad "59" thru_hole circle
			(at 5.08 12.7 270)
			(size 1.6256 1.6256)
			(drill 1.1176)
			(layers "*.Cu" "*.Mask")
			(remove_unused_layers no)
			(net "P12V")
			(clearance 0)
		)
		(pad "60" thru_hole circle
			(at 5.08 10.16 270)
			(size 1.6256 1.6256)
			(drill 1.1176)
			(layers "*.Cu" "*.Mask")
			(remove_unused_layers no)
			(net "P12V")
			(clearance 0)
		)
		(pad "61" thru_hole circle
			(at 5.08 7.62 270)
			(size 1.6256 1.6256)
			(drill 1.1176)
			(layers "*.Cu" "*.Mask")
			(remove_unused_layers no)
			(net "P12V")
			(clearance 0)
		)
		(pad "62" thru_hole circle
			(at 5.08 5.08 270)
			(size 1.6256 1.6256)
			(drill 1.1176)
			(layers "*.Cu" "*.Mask")
			(remove_unused_layers no)
			(net "P12V")
			(clearance 0)
		)
		(pad "63" thru_hole circle
			(at 5.08 2.54 270)
			(size 1.6256 1.6256)
			(drill 1.1176)
			(layers "*.Cu" "*.Mask")
			(remove_unused_layers no)
			(net "P12V")
			(clearance 0)
		)
		(pad "64" thru_hole circle
			(at 5.08 0 270)
			(size 1.6256 1.6256)
			(drill 1.1176)
			(layers "*.Cu" "*.Mask")
			(remove_unused_layers no)
			(net "P12V")
			(clearance 0)
		)
	)
	(footprint ""
		(layer "F.Cu")
		(at 98.702114 -15.774924)
		(property "Reference" ""
			(at 0 0 0)
			(layer "F.SilkS")
			(hide yes)
			(effects
				(font
					(size 1.27 1.27)
				)
			)
		)
		(property "Value" ""
			(at 0 0 0)
			(layer "F.Fab")
			(effects
				(font
					(size 1.27 1.27)
				)
			)
		)
		(duplicate_pad_numbers_are_jumpers no)
		(fp_poly
			(pts
				(arc
					(start 1.4986 0)
					(mid -1.4986 0)
					(end 1.4986 0)
				)
			)
			(stroke
				(width 0)
				(type default)
			)
			(fill no)
			(layer "F.CrtYd")
		)
		(pad "1" smd circle
			(at 0 0)
			(size 0.9906 0.9906)
			(layers "F.Cu" "F.Mask" "F.Paste")
			(net "Net_172")
		)
		(zone
			(layer "F.Cu")
			(hatch none 0.5)
			(connect_pads
				(clearance 0)
			)
			(min_thickness 0.25)
			(keepout
				(tracks not_allowed)
				(vias allowed)
				(pads allowed)
				(copperpour not_allowed)
				(footprints allowed)
			)
			(placement
				(enabled no)
				(sheetname "")
			)
			(fill
				(thermal_gap 0.5)
				(thermal_bridge_width 0.5)
				(island_removal_mode 0)
			)
			(polygon
				(pts
					(arc
						(start 100.327714 -15.774924)
						(mid 97.076514 -15.774924)
						(end 100.327714 -15.774924)
					)
				)
			)
		)
	)
	(footprint ""
		(layer "F.Cu")
		(at 49.949354 -107.119928 180)
		(property "Reference" "CE5"
			(at -5.215128 0.67437 0)
			(unlocked yes)
			(layer "F.SilkS")
			(effects
				(font
					(size 0.7874 0.5842)
					(thickness 0.1524)
				)
				(justify left)
			)
		)
		(property "Value" ""
			(at 0 0 180)
			(layer "F.Fab")
			(effects
				(font
					(size 1.27 1.27)
				)
			)
		)
		(duplicate_pad_numbers_are_jumpers no)
		(fp_line
			(start 0 -4.2672)
			(end 0 4.2672)
			(stroke
				(width 0.1524)
				(type default)
			)
			(layer "F.SilkS")
		)
		(fp_circle
			(center 0 0)
			(end -4.2672 0)
			(stroke
				(width 0.1524)
				(type default)
			)
			(fill no)
			(layer "F.SilkS")
		)
		(fp_poly
			(pts
				(arc
					(start 0 -4.2672)
					(mid 4.2672 0)
					(end 0 4.2672)
				)
			)
			(stroke
				(width 0)
				(type default)
			)
			(fill yes)
			(layer "F.SilkS")
		)
		(fp_poly
			(pts
				(xy -2.5146 -0.762) (xy -0.9906 -0.762) (xy -0.9906 0.762) (xy -2.5146 0.762)
			)
			(stroke
				(width 0)
				(type default)
			)
			(fill no)
			(layer "B.CrtYd")
		)
		(fp_poly
			(pts
				(arc
					(start 1.7526 0.762)
					(mid 2.291415 -0.538815)
					(end 0.9906 0)
				)
				(arc
					(start 0.9906 0.0254)
					(mid 1.206345 0.546255)
					(end 1.7272 0.762)
				)
			)
			(stroke
				(width 0)
				(type default)
			)
			(fill no)
			(layer "B.CrtYd")
		)
		(fp_poly
			(pts
				(arc
					(start -4.2672 0)
					(mid 4.2672 0)
					(end -4.2672 0)
				)
			)
			(stroke
				(width 0)
				(type default)
			)
			(fill no)
			(layer "F.CrtYd")
		)
		(fp_circle
			(center 0 0)
			(end -4.2672 0)
			(stroke
				(width 0.1)
				(type default)
			)
			(fill no)
			(layer "F.Fab")
		)
		(fp_text user "+"
			(at -5.033772 -1.421384 180)
			(unlocked yes)
			(layer "F.SilkS")
			(effects
				(font
					(size 0.7874 0.5842)
					(thickness 0.1524)
				)
				(justify left)
			)
		)
		(fp_text user "+"
			(at -5.6642 -0.34925 180)
			(unlocked yes)
			(layer "F.Fab")
			(effects
				(font
					(size 1.905 1.4224)
					(thickness 0.000001)
				)
				(justify left)
			)
		)
		(pad "1" thru_hole rect
			(at -1.75006 0 180)
			(size 1.397 1.397)
			(drill 0.9144)
			(layers "*.Cu" "*.Mask")
			(remove_unused_layers no)
			(net "P12V")
			(clearance 0.0127)
			(thermal_gap 0.0127)
			(padstack
				(mode front_inner_back)
				(layer "Inner"
					(shape circle)
					(size 1.397 1.397)
					(clearance 0.0127)
				)
				(layer "B.Cu"
					(shape rect)
					(size 1.397 1.397)
					(clearance 0.0127)
				)
			)
		)
		(pad "2" thru_hole circle
			(at 1.75006 0 180)
			(size 1.397 1.397)
			(drill 0.9144)
			(layers "*.Cu" "*.Mask")
			(remove_unused_layers no)
			(net "GND")
			(clearance 0.0127)
			(thermal_gap 0.0127)
		)
	)
	(footprint ""
		(layer "F.Cu")
		(at 16.017494 -330.497434 -90)
		(property "Reference" "R38"
			(at 3.685032 -0.234188 90)
			(unlocked yes)
			(layer "F.SilkS")
			(effects
				(font
					(size 0.7874 0.5842)
					(thickness 0.1524)
				)
				(justify left)
			)
		)
		(property "Value" ""
			(at 0 0 270)
			(layer "F.Fab")
			(effects
				(font
					(size 1.27 1.27)
				)
			)
		)
		(duplicate_pad_numbers_are_jumpers no)
		(fp_line
			(start -0.7874 0.4064)
			(end -0.7874 -0.4064)
			(stroke
				(width 0.1524)
				(type default)
			)
			(layer "F.SilkS")
		)
		(fp_line
			(start 0.7874 0.4064)
			(end -0.7874 0.4064)
			(stroke
				(width 0.1524)
				(type default)
			)
			(layer "F.SilkS")
		)
		(fp_line
			(start -0.7874 -0.4064)
			(end 0.7874 -0.4064)
			(stroke
				(width 0.1524)
				(type default)
			)
			(layer "F.SilkS")
		)
		(fp_line
			(start 0.7874 -0.4064)
			(end 0.7874 0.4064)
			(stroke
				(width 0.1524)
				(type default)
			)
			(layer "F.SilkS")
		)
		(fp_poly
			(pts
				(xy -0.508 0.2794) (xy -0.508 0.2286) (xy -0.635 0.2286) (xy -0.635 -0.254) (xy -0.5334 -0.254)
				(xy -0.5334 -0.2794) (xy 0.5334 -0.2794) (xy 0.5334 -0.254) (xy 0.635 -0.254) (xy 0.635 0.254) (xy 0.5334 0.254)
				(xy 0.5334 0.2794)
			)
			(stroke
				(width 0)
				(type default)
			)
			(fill no)
			(layer "F.CrtYd")
		)
		(pad "1" smd rect
			(at 0.40005 0 270)
			(size 0.4572 0.508)
			(layers "F.Cu" "F.Mask" "F.Paste")
			(net "GND")
		)
		(pad "2" smd rect
			(at -0.40005 0 270)
			(size 0.4572 0.508)
			(layers "F.Cu" "F.Mask" "F.Paste")
			(net "FRU_A1")
		)
	)
	(footprint ""
		(layer "F.Cu")
		(at 50.417984 -217.485976 180)
		(property "Reference" "CE11"
			(at -4.932426 0.531114 0)
			(unlocked yes)
			(layer "F.SilkS")
			(effects
				(font
					(size 0.7874 0.5842)
					(thickness 0.1524)
				)
				(justify left)
			)
		)
		(property "Value" ""
			(at 0 0 180)
			(layer "F.Fab")
			(effects
				(font
					(size 1.27 1.27)
				)
			)
		)
		(duplicate_pad_numbers_are_jumpers no)
		(fp_line
			(start 0 -4.2672)
			(end 0 4.2672)
			(stroke
				(width 0.1524)
				(type default)
			)
			(layer "F.SilkS")
		)
		(fp_circle
			(center 0 0)
			(end -4.2672 0)
			(stroke
				(width 0.1524)
				(type default)
			)
			(fill no)
			(layer "F.SilkS")
		)
		(fp_poly
			(pts
				(arc
					(start 0 -4.2672)
					(mid 4.2672 0)
					(end 0 4.2672)
				)
			)
			(stroke
				(width 0)
				(type default)
			)
			(fill yes)
			(layer "F.SilkS")
		)
		(fp_poly
			(pts
				(xy -2.5146 -0.762) (xy -0.9906 -0.762) (xy -0.9906 0.762) (xy -2.5146 0.762)
			)
			(stroke
				(width 0)
				(type default)
			)
			(fill no)
			(layer "B.CrtYd")
		)
		(fp_poly
			(pts
				(arc
					(start 1.7526 0.762)
					(mid 2.291415 -0.538815)
					(end 0.9906 0)
				)
				(arc
					(start 0.9906 0.0254)
					(mid 1.206345 0.546255)
					(end 1.7272 0.762)
				)
			)
			(stroke
				(width 0)
				(type default)
			)
			(fill no)
			(layer "B.CrtYd")
		)
		(fp_poly
			(pts
				(arc
					(start -4.2672 0)
					(mid 4.2672 0)
					(end -4.2672 0)
				)
			)
			(stroke
				(width 0)
				(type default)
			)
			(fill no)
			(layer "F.CrtYd")
		)
		(fp_circle
			(center 0 0)
			(end -4.2672 0)
			(stroke
				(width 0.1)
				(type default)
			)
			(fill no)
			(layer "F.Fab")
		)
		(fp_text user "+"
			(at -6.029198 -0.758698 180)
			(unlocked yes)
			(layer "F.SilkS")
			(effects
				(font
					(size 0.7874 0.5842)
					(thickness 0.1524)
				)
				(justify left)
			)
		)
		(fp_text user "+"
			(at -5.6642 -0.34925 180)
			(unlocked yes)
			(layer "F.Fab")
			(effects
				(font
					(size 1.905 1.4224)
					(thickness 0.000001)
				)
				(justify left)
			)
		)
		(pad "1" thru_hole rect
			(at -1.75006 0 180)
			(size 1.397 1.397)
			(drill 0.9144)
			(layers "*.Cu" "*.Mask")
			(remove_unused_layers no)
			(net "P12V")
			(clearance 0.0127)
			(thermal_gap 0.0127)
			(padstack
				(mode front_inner_back)
				(layer "Inner"
					(shape circle)
					(size 1.397 1.397)
					(clearance 0.0127)
				)
				(layer "B.Cu"
					(shape rect)
					(size 1.397 1.397)
					(clearance 0.0127)
				)
			)
		)
		(pad "2" thru_hole circle
			(at 1.75006 0 180)
			(size 1.397 1.397)
			(drill 0.9144)
			(layers "*.Cu" "*.Mask")
			(remove_unused_layers no)
			(net "GND")
			(clearance 0.0127)
			(thermal_gap 0.0127)
		)
	)
	(footprint ""
		(layer "F.Cu")
		(at 50.083466 -38.6207 180)
		(property "Reference" "CE2"
			(at 1.317244 -5.56133 0)
			(unlocked yes)
			(layer "F.SilkS")
			(effects
				(font
					(size 0.7874 0.5842)
					(thickness 0.1524)
				)
				(justify left)
			)
		)
		(property "Value" ""
			(at 0 0 180)
			(layer "F.Fab")
			(effects
				(font
					(size 1.27 1.27)
				)
			)
		)
		(duplicate_pad_numbers_are_jumpers no)
		(fp_line
			(start 0 -4.2672)
			(end 0 4.2672)
			(stroke
				(width 0.1524)
				(type default)
			)
			(layer "F.SilkS")
		)
		(fp_circle
			(center 0 0)
			(end -4.2672 0)
			(stroke
				(width 0.1524)
				(type default)
			)
			(fill no)
			(layer "F.SilkS")
		)
		(fp_poly
			(pts
				(arc
					(start 0 -4.2672)
					(mid 4.2672 0)
					(end 0 4.2672)
				)
			)
			(stroke
				(width 0)
				(type default)
			)
			(fill yes)
			(layer "F.SilkS")
		)
		(fp_poly
			(pts
				(xy -2.5146 -0.762) (xy -0.9906 -0.762) (xy -0.9906 0.762) (xy -2.5146 0.762)
			)
			(stroke
				(width 0)
				(type default)
			)
			(fill no)
			(layer "B.CrtYd")
		)
		(fp_poly
			(pts
				(arc
					(start 1.7526 0.762)
					(mid 2.291415 -0.538815)
					(end 0.9906 0)
				)
				(arc
					(start 0.9906 0.0254)
					(mid 1.206345 0.546255)
					(end 1.7272 0.762)
				)
			)
			(stroke
				(width 0)
				(type default)
			)
			(fill no)
			(layer "B.CrtYd")
		)
		(fp_poly
			(pts
				(arc
					(start -4.2672 0)
					(mid 4.2672 0)
					(end -4.2672 0)
				)
			)
			(stroke
				(width 0)
				(type default)
			)
			(fill no)
			(layer "F.CrtYd")
		)
		(fp_circle
			(center 0 0)
			(end -4.2672 0)
			(stroke
				(width 0.1)
				(type default)
			)
			(fill no)
			(layer "F.Fab")
		)
		(fp_text user "+"
			(at -3.633216 3.210814 180)
			(unlocked yes)
			(layer "F.SilkS")
			(effects
				(font
					(size 0.7874 0.5842)
					(thickness 0.1524)
				)
				(justify left)
			)
		)
		(fp_text user "+"
			(at -5.6642 -0.34925 180)
			(unlocked yes)
			(layer "F.Fab")
			(effects
				(font
					(size 1.905 1.4224)
					(thickness 0.000001)
				)
				(justify left)
			)
		)
		(pad "1" thru_hole rect
			(at -1.75006 0 180)
			(size 1.397 1.397)
			(drill 0.9144)
			(layers "*.Cu" "*.Mask")
			(remove_unused_layers no)
			(net "P12V")
			(clearance 0.0127)
			(thermal_gap 0.0127)
			(padstack
				(mode front_inner_back)
				(layer "Inner"
					(shape circle)
					(size 1.397 1.397)
					(clearance 0.0127)
				)
				(layer "B.Cu"
					(shape rect)
					(size 1.397 1.397)
					(clearance 0.0127)
				)
			)
		)
		(pad "2" thru_hole circle
			(at 1.75006 0 180)
			(size 1.397 1.397)
			(drill 0.9144)
			(layers "*.Cu" "*.Mask")
			(remove_unused_layers no)
			(net "GND")
			(clearance 0.0127)
			(thermal_gap 0.0127)
		)
	)
	(footprint ""
		(layer "F.Cu")
		(at 26.850848 -19.859244)
		(property "Reference" "R5"
			(at -2.617978 0.04699 0)
			(unlocked yes)
			(layer "F.SilkS")
			(effects
				(font
					(size 0.7874 0.5842)
					(thickness 0.1524)
				)
				(justify left)
			)
		)
		(property "Value" ""
			(at 0 0 0)
			(layer "F.Fab")
			(effects
				(font
					(size 1.27 1.27)
				)
			)
		)
		(duplicate_pad_numbers_are_jumpers no)
		(fp_line
			(start -0.7874 -0.4064)
			(end 0.7874 -0.4064)
			(stroke
				(width 0.1524)
				(type default)
			)
			(layer "F.SilkS")
		)
		(fp_line
			(start -0.7874 0.4064)
			(end -0.7874 -0.4064)
			(stroke
				(width 0.1524)
				(type default)
			)
			(layer "F.SilkS")
		)
		(fp_line
			(start 0.7874 -0.4064)
			(end 0.7874 0.4064)
			(stroke
				(width 0.1524)
				(type default)
			)
			(layer "F.SilkS")
		)
		(fp_line
			(start 0.7874 0.4064)
			(end -0.7874 0.4064)
			(stroke
				(width 0.1524)
				(type default)
			)
			(layer "F.SilkS")
		)
		(fp_poly
			(pts
				(xy -0.508 0.2794) (xy -0.508 0.2286) (xy -0.635 0.2286) (xy -0.635 -0.254) (xy -0.5334 -0.254)
				(xy -0.5334 -0.2794) (xy 0.5334 -0.2794) (xy 0.5334 -0.254) (xy 0.635 -0.254) (xy 0.635 0.254) (xy 0.5334 0.254)
				(xy 0.5334 0.2794)
			)
			(stroke
				(width 0)
				(type default)
			)
			(fill no)
			(layer "F.CrtYd")
		)
		(pad "1" smd rect
			(at 0.40005 0)
			(size 0.4572 0.508)
			(layers "F.Cu" "F.Mask" "F.Paste")
			(net "PSU1_REMOTE_N")
		)
		(pad "2" smd rect
			(at -0.40005 0)
			(size 0.4572 0.508)
			(layers "F.Cu" "F.Mask" "F.Paste")
			(net "GND")
		)
	)
	(footprint ""
		(layer "F.Cu")
		(at 4.50469 -521.121894)
		(property "Reference" "J24"
			(at 4.5085 14.04239 0)
			(unlocked yes)
			(layer "F.SilkS")
			(effects
				(font
					(size 0.7874 0.5842)
					(thickness 0.1524)
				)
				(justify left)
			)
		)
		(property "Value" ""
			(at 0 0 0)
			(layer "F.Fab")
			(effects
				(font
					(size 1.27 1.27)
				)
			)
		)
		(duplicate_pad_numbers_are_jumpers no)
		(fp_line
			(start -3.370072 -3.81)
			(end 12.260072 -3.81)
			(stroke
				(width 0.1524)
				(type default)
			)
			(layer "F.SilkS")
		)
		(fp_line
			(start -3.370072 12.830048)
			(end -3.370072 -3.81)
			(stroke
				(width 0.1524)
				(type default)
			)
			(layer "F.SilkS")
		)
		(fp_line
			(start 12.260072 -3.81)
			(end 12.260072 12.830048)
			(stroke
				(width 0.1524)
				(type default)
			)
			(layer "F.SilkS")
		)
		(fp_line
			(start 12.260072 12.830048)
			(end -3.370072 12.830048)
			(stroke
				(width 0.1524)
				(type default)
			)
			(layer "F.SilkS")
		)
		(fp_poly
			(pts
				(xy -3.48234 1.034034) (xy -3.700018 1.828038) (xy -4.24815 1.336294)
			)
			(stroke
				(width 0)
				(type default)
			)
			(fill yes)
			(layer "F.SilkS")
		)
		(fp_poly
			(pts
				(xy -0.762 0.762) (xy 8.382 0.762) (xy 8.382 -1.8034) (xy 9.652 -1.8034) (xy 9.652 -3.302) (xy 0.508 -3.302)
				(xy 0.508 -0.762) (xy -0.762 -0.762)
			)
			(stroke
				(width 0)
				(type default)
			)
			(fill no)
			(layer "B.CrtYd")
		)
		(fp_poly
			(pts
				(arc
					(start 0.6604 6.35)
					(mid -3.2004 6.35)
					(end 0.6604 6.35)
				)
			)
			(stroke
				(width 0)
				(type default)
			)
			(fill no)
			(layer "B.CrtYd")
		)
		(fp_poly
			(pts
				(arc
					(start 12.0904 6.35)
					(mid 8.2296 6.35)
					(end 12.0904 6.35)
				)
			)
			(stroke
				(width 0)
				(type default)
			)
			(fill no)
			(layer "B.CrtYd")
		)
		(fp_poly
			(pts
				(xy -3.370072 12.830048) (xy 12.260072 12.830048) (xy 12.260072 -3.81) (xy -3.370072 -3.81)
			)
			(stroke
				(width 0)
				(type default)
			)
			(fill no)
			(layer "F.CrtYd")
		)
		(fp_line
			(start -3.370072 -3.81)
			(end 12.260072 -3.81)
			(stroke
				(width 0.1)
				(type default)
			)
			(layer "F.Fab")
		)
		(fp_line
			(start -3.370072 12.830048)
			(end -3.370072 -3.81)
			(stroke
				(width 0.1)
				(type default)
			)
			(layer "F.Fab")
		)
		(fp_line
			(start 12.260072 -3.81)
			(end 12.260072 12.830048)
			(stroke
				(width 0.1)
				(type default)
			)
			(layer "F.Fab")
		)
		(fp_line
			(start 12.260072 12.830048)
			(end -3.370072 12.830048)
			(stroke
				(width 0.1)
				(type default)
			)
			(layer "F.Fab")
		)
		(fp_poly
			(pts
				(xy -3.576828 0) (xy -5.0038 0.713486) (xy -5.0038 -0.713486)
			)
			(stroke
				(width 0)
				(type default)
			)
			(fill yes)
			(layer "F.Fab")
		)
		(fp_text user "2"
			(at -3.9624 -2.428748 0)
			(unlocked yes)
			(layer "F.SilkS")
			(effects
				(font
					(size 0.7874 0.5842)
					(thickness 0.1524)
				)
			)
		)
		(fp_text user "1"
			(at -3.77952 -0.862584 0)
			(unlocked yes)
			(layer "F.SilkS")
			(effects
				(font
					(size 0.7874 0.5842)
					(thickness 0.1524)
				)
			)
		)
		(fp_text user "8"
			(at 12.7762 -2.555748 0)
			(unlocked yes)
			(layer "F.SilkS")
			(effects
				(font
					(size 0.7874 0.5842)
					(thickness 0.1524)
				)
			)
		)
		(fp_text user "7"
			(at 12.7762 -0.091948 0)
			(unlocked yes)
			(layer "F.SilkS")
			(effects
				(font
					(size 0.7874 0.5842)
					(thickness 0.1524)
				)
			)
		)
		(fp_text user "1"
			(at -1.2954 0.085852 0)
			(unlocked yes)
			(layer "B.SilkS")
			(effects
				(font
					(size 0.7874 0.5842)
					(thickness 0.1524)
				)
				(justify mirror)
			)
		)
		(fp_text user "2"
			(at 0 -2.581148 0)
			(unlocked yes)
			(layer "B.SilkS")
			(effects
				(font
					(size 0.7874 0.5842)
					(thickness 0.1524)
				)
				(justify mirror)
			)
		)
		(fp_text user "7"
			(at 8.8138 0.238252 0)
			(unlocked yes)
			(layer "B.SilkS")
			(effects
				(font
					(size 0.7874 0.5842)
					(thickness 0.1524)
				)
				(justify mirror)
			)
		)
		(fp_text user "8"
			(at 10.0838 -2.403348 0)
			(unlocked yes)
			(layer "B.SilkS")
			(effects
				(font
					(size 0.7874 0.5842)
					(thickness 0.1524)
				)
				(justify mirror)
			)
		)
		(fp_text user "1"
			(at -1.2954 0.085852 0)
			(unlocked yes)
			(layer "B.Fab")
			(effects
				(font
					(size 0.7874 0.5842)
					(thickness 0.000001)
				)
				(justify mirror)
			)
		)
		(fp_text user "2"
			(at 0 -2.581148 0)
			(unlocked yes)
			(layer "B.Fab")
			(effects
				(font
					(size 0.7874 0.5842)
					(thickness 0.000001)
				)
				(justify mirror)
			)
		)
		(fp_text user "7"
			(at 8.8138 0.238252 0)
			(unlocked yes)
			(layer "B.Fab")
			(effects
				(font
					(size 0.7874 0.5842)
					(thickness 0.000001)
				)
				(justify mirror)
			)
		)
		(fp_text user "8"
			(at 10.0838 -2.403348 0)
			(unlocked yes)
			(layer "B.Fab")
			(effects
				(font
					(size 0.7874 0.5842)
					(thickness 0.000001)
				)
				(justify mirror)
			)
		)
		(fp_text user "2"
			(at -3.9624 -2.428748 0)
			(unlocked yes)
			(layer "F.Fab")
			(effects
				(font
					(size 0.7874 0.5842)
					(thickness 0.000001)
				)
			)
		)
		(fp_text user "1"
			(at -3.9116 -0.930148 0)
			(unlocked yes)
			(layer "F.Fab")
			(effects
				(font
					(size 0.7874 0.5842)
					(thickness 0.000001)
				)
			)
		)
		(fp_text user "8"
			(at 12.7762 -2.555748 0)
			(unlocked yes)
			(layer "F.Fab")
			(effects
				(font
					(size 0.7874 0.5842)
					(thickness 0.000001)
				)
			)
		)
		(fp_text user "7"
			(at 12.7762 -0.091948 0)
			(unlocked yes)
			(layer "F.Fab")
			(effects
				(font
					(size 0.7874 0.5842)
					(thickness 0.000001)
				)
			)
		)
		(pad "" np_thru_hole circle
			(at -1.27 6.35)
			(size 3.3528 3.3528)
			(drill 3.3528)
			(layers "*.Cu" "*.Mask")
			(clearance 0.381)
			(thermal_gap 0.381)
		)
		(pad "" np_thru_hole circle
			(at 10.16 6.35)
			(size 3.3528 3.3528)
			(drill 3.3528)
			(layers "*.Cu" "*.Mask")
			(clearance 0.381)
			(thermal_gap 0.381)
		)
		(pad "1" thru_hole rect
			(at 0 0)
			(size 1.397 1.397)
			(drill 0.9906)
			(layers "*.Cu" "*.Mask")
			(remove_unused_layers no)
			(net "UART_RTS_RP6_L_N")
			(clearance 0.0508)
			(thermal_gap 0.0508)
			(padstack
				(mode front_inner_back)
				(layer "Inner"
					(shape circle)
					(size 1.397 1.397)
					(clearance 0.0508)
				)
				(layer "B.Cu"
					(shape rect)
					(size 1.397 1.397)
					(clearance 0.0508)
				)
			)
		)
		(pad "2" thru_hole circle
			(at 1.27 -2.54)
			(size 1.397 1.397)
			(drill 0.9906)
			(layers "*.Cu" "*.Mask")
			(remove_unused_layers no)
			(net "UART_DSR_RP6_L")
			(clearance 0.0508)
			(thermal_gap 0.0508)
		)
		(pad "3" thru_hole circle
			(at 2.54 0)
			(size 1.397 1.397)
			(drill 0.9906)
			(layers "*.Cu" "*.Mask")
			(remove_unused_layers no)
			(net "UART_RX_RP6_L")
			(clearance 0.0508)
			(thermal_gap 0.0508)
		)
		(pad "4" thru_hole circle
			(at 3.81 -2.54)
			(size 1.397 1.397)
			(drill 0.9906)
			(layers "*.Cu" "*.Mask")
			(remove_unused_layers no)
			(net "UART_RI_RP6_L_N")
			(clearance 0.0508)
			(thermal_gap 0.0508)
		)
		(pad "5" thru_hole circle
			(at 5.08 0)
			(size 1.397 1.397)
			(drill 0.9906)
			(layers "*.Cu" "*.Mask")
			(remove_unused_layers no)
			(net "GND")
			(clearance 0.0508)
			(thermal_gap 0.0508)
		)
		(pad "6" thru_hole circle
			(at 6.35 -2.54)
			(size 1.397 1.397)
			(drill 0.9906)
			(layers "*.Cu" "*.Mask")
			(remove_unused_layers no)
			(net "UART_TX_RP6_L")
			(clearance 0.0508)
			(thermal_gap 0.0508)
		)
		(pad "7" thru_hole circle
			(at 7.62 0)
			(size 1.397 1.397)
			(drill 0.9906)
			(layers "*.Cu" "*.Mask")
			(remove_unused_layers no)
			(net "UART_DTR_RP6_L_N")
			(clearance 0.0508)
			(thermal_gap 0.0508)
		)
		(pad "8" thru_hole circle
			(at 8.89 -2.54)
			(size 1.397 1.397)
			(drill 0.9906)
			(layers "*.Cu" "*.Mask")
			(remove_unused_layers no)
			(net "UART_CTS_RP6_L_N")
			(clearance 0.0508)
			(thermal_gap 0.0508)
		)
		(zone
			(layers "F.Cu" "B.Cu" "In1.Cu" "In2.Cu" "In3.Cu" "In4.Cu" "In5.Cu" "In6.Cu")
			(hatch none 0.5)
			(connect_pads
				(clearance 0)
			)
			(min_thickness 0.25)
			(keepout
				(tracks not_allowed)
				(vias allowed)
				(pads allowed)
				(copperpour not_allowed)
				(footprints allowed)
			)
			(placement
				(enabled no)
				(sheetname "")
			)
			(fill
				(thermal_gap 0.5)
				(thermal_bridge_width 0.5)
				(island_removal_mode 0)
			)
			(polygon
				(pts
					(arc
						(start 5.31749 -514.771894)
						(mid 1.15189 -514.771894)
						(end 5.31749 -514.771894)
					)
				)
			)
		)
		(zone
			(layers "F.Cu" "B.Cu" "In1.Cu" "In2.Cu" "In3.Cu" "In4.Cu" "In5.Cu" "In6.Cu")
			(hatch none 0.5)
			(connect_pads
				(clearance 0)
			)
			(min_thickness 0.25)
			(keepout
				(tracks not_allowed)
				(vias allowed)
				(pads allowed)
				(copperpour not_allowed)
				(footprints allowed)
			)
			(placement
				(enabled no)
				(sheetname "")
			)
			(fill
				(thermal_gap 0.5)
				(thermal_bridge_width 0.5)
				(island_removal_mode 0)
			)
			(polygon
				(pts
					(arc
						(start 16.74749 -514.771894)
						(mid 12.58189 -514.771894)
						(end 16.74749 -514.771894)
					)
				)
			)
		)
	)
	(footprint ""
		(layer "F.Cu")
		(at 46.36516 -256.467102 180)
		(property "Reference" "R108"
			(at -1.033272 -0.247396 0)
			(unlocked yes)
			(layer "F.SilkS")
			(effects
				(font
					(size 0.7874 0.5842)
					(thickness 0.1524)
				)
				(justify left)
			)
		)
		(property "Value" ""
			(at 0 0 180)
			(layer "F.Fab")
			(effects
				(font
					(size 1.27 1.27)
				)
			)
		)
		(duplicate_pad_numbers_are_jumpers no)
		(fp_line
			(start 0.7874 0.4064)
			(end -0.7874 0.4064)
			(stroke
				(width 0.1524)
				(type default)
			)
			(layer "F.SilkS")
		)
		(fp_line
			(start 0.7874 -0.4064)
			(end 0.7874 0.4064)
			(stroke
				(width 0.1524)
				(type default)
			)
			(layer "F.SilkS")
		)
		(fp_line
			(start -0.7874 0.4064)
			(end -0.7874 -0.4064)
			(stroke
				(width 0.1524)
				(type default)
			)
			(layer "F.SilkS")
		)
		(fp_line
			(start -0.7874 -0.4064)
			(end 0.7874 -0.4064)
			(stroke
				(width 0.1524)
				(type default)
			)
			(layer "F.SilkS")
		)
		(fp_poly
			(pts
				(xy -0.508 0.2794) (xy -0.508 0.2286) (xy -0.635 0.2286) (xy -0.635 -0.254) (xy -0.5334 -0.254)
				(xy -0.5334 -0.2794) (xy 0.5334 -0.2794) (xy 0.5334 -0.254) (xy 0.635 -0.254) (xy 0.635 0.254) (xy 0.5334 0.254)
				(xy 0.5334 0.2794)
			)
			(stroke
				(width 0)
				(type default)
			)
			(fill no)
			(layer "F.CrtYd")
		)
		(pad "1" smd rect
			(at 0.40005 0 180)
			(size 0.4572 0.508)
			(layers "F.Cu" "F.Mask" "F.Paste")
			(net "PSU4_REMOTE_R_P")
		)
		(pad "2" smd rect
			(at -0.40005 0 180)
			(size 0.4572 0.508)
			(layers "F.Cu" "F.Mask" "F.Paste")
			(net "P12V")
		)
	)
	(footprint ""
		(layer "F.Cu")
		(at 72.559164 -263.260078 90)
		(property "Reference" "C48"
			(at -4.374134 -0.046482 90)
			(unlocked yes)
			(layer "F.SilkS")
			(effects
				(font
					(size 0.7874 0.5842)
					(thickness 0.1524)
				)
				(justify left)
			)
		)
		(property "Value" ""
			(at 0 0 90)
			(layer "F.Fab")
			(effects
				(font
					(size 1.27 1.27)
				)
			)
		)
		(duplicate_pad_numbers_are_jumpers no)
		(fp_line
			(start 0.7874 -0.4064)
			(end 0.7874 0.4064)
			(stroke
				(width 0.1524)
				(type default)
			)
			(layer "F.SilkS")
		)
		(fp_line
			(start -0.7874 -0.4064)
			(end 0.7874 -0.4064)
			(stroke
				(width 0.1524)
				(type default)
			)
			(layer "F.SilkS")
		)
		(fp_line
			(start 0 0.381)
			(end 0 -0.381)
			(stroke
				(width 0.1524)
				(type default)
			)
			(layer "F.SilkS")
		)
		(fp_line
			(start 0.7874 0.4064)
			(end -0.7874 0.4064)
			(stroke
				(width 0.1524)
				(type default)
			)
			(layer "F.SilkS")
		)
		(fp_line
			(start -0.7874 0.4064)
			(end -0.7874 -0.4064)
			(stroke
				(width 0.1524)
				(type default)
			)
			(layer "F.SilkS")
		)
		(fp_poly
			(pts
				(xy -0.5334 0.254) (xy -0.635 0.254) (xy -0.635 0.2286) (xy -0.635 -0.254) (xy -0.5334 -0.254) (xy -0.5334 -0.2794)
				(xy 0.5334 -0.2794) (xy 0.5334 -0.254) (xy 0.635 -0.254) (xy 0.635 0.254) (xy 0.5334 0.254) (xy 0.5334 0.2794)
				(xy -0.508 0.2794) (xy -0.5334 0.2794)
			)
			(stroke
				(width 0)
				(type default)
			)
			(fill no)
			(layer "F.CrtYd")
		)
		(pad "1" smd rect
			(at 0.40005 0 90)
			(size 0.4572 0.508)
			(layers "F.Cu" "F.Mask" "F.Paste")
			(net "P12V")
		)
		(pad "2" smd rect
			(at -0.40005 0 90)
			(size 0.4572 0.508)
			(layers "F.Cu" "F.Mask" "F.Paste")
			(net "GND")
		)
	)
	(footprint ""
		(layer "F.Cu")
		(at 27.577796 -373.032528 90)
		(property "Reference" "R129"
			(at -3.094482 -0.932942 90)
			(unlocked yes)
			(layer "F.SilkS")
			(effects
				(font
					(size 0.7874 0.5842)
					(thickness 0.1524)
				)
				(justify left)
			)
		)
		(property "Value" ""
			(at 0 0 90)
			(layer "F.Fab")
			(effects
				(font
					(size 1.27 1.27)
				)
			)
		)
		(duplicate_pad_numbers_are_jumpers no)
		(fp_line
			(start 0.7874 -0.4064)
			(end 0.7874 0.4064)
			(stroke
				(width 0.1524)
				(type default)
			)
			(layer "F.SilkS")
		)
		(fp_line
			(start -0.7874 -0.4064)
			(end 0.7874 -0.4064)
			(stroke
				(width 0.1524)
				(type default)
			)
			(layer "F.SilkS")
		)
		(fp_line
			(start 0.7874 0.4064)
			(end -0.7874 0.4064)
			(stroke
				(width 0.1524)
				(type default)
			)
			(layer "F.SilkS")
		)
		(fp_line
			(start -0.7874 0.4064)
			(end -0.7874 -0.4064)
			(stroke
				(width 0.1524)
				(type default)
			)
			(layer "F.SilkS")
		)
		(fp_poly
			(pts
				(xy -0.508 0.2794) (xy -0.508 0.2286) (xy -0.635 0.2286) (xy -0.635 -0.254) (xy -0.5334 -0.254)
				(xy -0.5334 -0.2794) (xy 0.5334 -0.2794) (xy 0.5334 -0.254) (xy 0.635 -0.254) (xy 0.635 0.254) (xy 0.5334 0.254)
				(xy 0.5334 0.2794)
			)
			(stroke
				(width 0)
				(type default)
			)
			(fill no)
			(layer "F.CrtYd")
		)
		(pad "1" smd rect
			(at 0.40005 0 90)
			(size 0.4572 0.508)
			(layers "F.Cu" "F.Mask" "F.Paste")
			(net "PSU5_REMOTE_N")
		)
		(pad "2" smd rect
			(at -0.40005 0 90)
			(size 0.4572 0.508)
			(layers "F.Cu" "F.Mask" "F.Paste")
			(net "PSU5_REMOTE_R2_N")
		)
	)
	(footprint ""
		(layer "F.Cu")
		(at 78.397354 -14.939772 -90)
		(property "Reference" "C4"
			(at -1.75133 0.035052 90)
			(unlocked yes)
			(layer "F.SilkS")
			(effects
				(font
					(size 0.7874 0.5842)
					(thickness 0.1524)
				)
				(justify left)
			)
		)
		(property "Value" ""
			(at 0 0 270)
			(layer "F.Fab")
			(effects
				(font
					(size 1.27 1.27)
				)
			)
		)
		(duplicate_pad_numbers_are_jumpers no)
		(fp_line
			(start -0.7874 0.4064)
			(end -0.7874 -0.4064)
			(stroke
				(width 0.1524)
				(type default)
			)
			(layer "F.SilkS")
		)
		(fp_line
			(start 0.7874 0.4064)
			(end -0.7874 0.4064)
			(stroke
				(width 0.1524)
				(type default)
			)
			(layer "F.SilkS")
		)
		(fp_line
			(start 0 0.381)
			(end 0 -0.381)
			(stroke
				(width 0.1524)
				(type default)
			)
			(layer "F.SilkS")
		)
		(fp_line
			(start -0.7874 -0.4064)
			(end 0.7874 -0.4064)
			(stroke
				(width 0.1524)
				(type default)
			)
			(layer "F.SilkS")
		)
		(fp_line
			(start 0.7874 -0.4064)
			(end 0.7874 0.4064)
			(stroke
				(width 0.1524)
				(type default)
			)
			(layer "F.SilkS")
		)
		(fp_poly
			(pts
				(xy -0.5334 0.254) (xy -0.635 0.254) (xy -0.635 0.2286) (xy -0.635 -0.254) (xy -0.5334 -0.254) (xy -0.5334 -0.2794)
				(xy 0.5334 -0.2794) (xy 0.5334 -0.254) (xy 0.635 -0.254) (xy 0.635 0.254) (xy 0.5334 0.254) (xy 0.5334 0.2794)
				(xy -0.508 0.2794) (xy -0.5334 0.2794)
			)
			(stroke
				(width 0)
				(type default)
			)
			(fill no)
			(layer "F.CrtYd")
		)
		(pad "1" smd rect
			(at 0.40005 0 270)
			(size 0.4572 0.508)
			(layers "F.Cu" "F.Mask" "F.Paste")
			(net "P12V")
		)
		(pad "2" smd rect
			(at -0.40005 0 270)
			(size 0.4572 0.508)
			(layers "F.Cu" "F.Mask" "F.Paste")
			(net "GND")
		)
	)
	(footprint ""
		(layer "F.Cu")
		(at 39.873936 -462.37144)
		(property "Reference" "R18"
			(at 1.141984 0.133096 0)
			(unlocked yes)
			(layer "F.SilkS")
			(effects
				(font
					(size 0.7874 0.5842)
					(thickness 0.1524)
				)
				(justify left)
			)
		)
		(property "Value" ""
			(at 0 0 0)
			(layer "F.Fab")
			(effects
				(font
					(size 1.27 1.27)
				)
			)
		)
		(duplicate_pad_numbers_are_jumpers no)
		(fp_line
			(start -0.7874 -0.4064)
			(end 0.7874 -0.4064)
			(stroke
				(width 0.1524)
				(type default)
			)
			(layer "F.SilkS")
		)
		(fp_line
			(start -0.7874 0.4064)
			(end -0.7874 -0.4064)
			(stroke
				(width 0.1524)
				(type default)
			)
			(layer "F.SilkS")
		)
		(fp_line
			(start 0.7874 -0.4064)
			(end 0.7874 0.4064)
			(stroke
				(width 0.1524)
				(type default)
			)
			(layer "F.SilkS")
		)
		(fp_line
			(start 0.7874 0.4064)
			(end -0.7874 0.4064)
			(stroke
				(width 0.1524)
				(type default)
			)
			(layer "F.SilkS")
		)
		(fp_poly
			(pts
				(xy -0.508 0.2794) (xy -0.508 0.2286) (xy -0.635 0.2286) (xy -0.635 -0.254) (xy -0.5334 -0.254)
				(xy -0.5334 -0.2794) (xy 0.5334 -0.2794) (xy 0.5334 -0.254) (xy 0.635 -0.254) (xy 0.635 0.254) (xy 0.5334 0.254)
				(xy 0.5334 0.2794)
			)
			(stroke
				(width 0)
				(type default)
			)
			(fill no)
			(layer "F.CrtYd")
		)
		(pad "1" smd rect
			(at 0.40005 0)
			(size 0.4572 0.508)
			(layers "F.Cu" "F.Mask" "F.Paste")
			(net "PSU6_AD0")
		)
		(pad "2" smd rect
			(at -0.40005 0)
			(size 0.4572 0.508)
			(layers "F.Cu" "F.Mask" "F.Paste")
			(net "P12V_STBY")
		)
	)
	(footprint ""
		(layer "F.Cu")
		(at 80.932782 -295.215564 180)
		(property "Reference" "R124"
			(at 1.303528 -1.245108 0)
			(unlocked yes)
			(layer "F.SilkS")
			(effects
				(font
					(size 0.7874 0.5842)
					(thickness 0.1524)
				)
				(justify left)
			)
		)
		(property "Value" ""
			(at 0 0 180)
			(layer "F.Fab")
			(effects
				(font
					(size 1.27 1.27)
				)
			)
		)
		(duplicate_pad_numbers_are_jumpers no)
		(fp_line
			(start 0.7874 0.4064)
			(end -0.7874 0.4064)
			(stroke
				(width 0.1524)
				(type default)
			)
			(layer "F.SilkS")
		)
		(fp_line
			(start 0.7874 -0.4064)
			(end 0.7874 0.4064)
			(stroke
				(width 0.1524)
				(type default)
			)
			(layer "F.SilkS")
		)
		(fp_line
			(start -0.7874 0.4064)
			(end -0.7874 -0.4064)
			(stroke
				(width 0.1524)
				(type default)
			)
			(layer "F.SilkS")
		)
		(fp_line
			(start -0.7874 -0.4064)
			(end 0.7874 -0.4064)
			(stroke
				(width 0.1524)
				(type default)
			)
			(layer "F.SilkS")
		)
		(fp_poly
			(pts
				(xy -0.508 0.2794) (xy -0.508 0.2286) (xy -0.635 0.2286) (xy -0.635 -0.254) (xy -0.5334 -0.254)
				(xy -0.5334 -0.2794) (xy 0.5334 -0.2794) (xy 0.5334 -0.254) (xy 0.635 -0.254) (xy 0.635 0.254) (xy 0.5334 0.254)
				(xy 0.5334 0.2794)
			)
			(stroke
				(width 0)
				(type default)
			)
			(fill no)
			(layer "F.CrtYd")
		)
		(pad "1" smd rect
			(at 0.40005 0 180)
			(size 0.4572 0.508)
			(layers "F.Cu" "F.Mask" "F.Paste")
			(net "PSU4_REMOTE_R2_N")
		)
		(pad "2" smd rect
			(at -0.40005 0 180)
			(size 0.4572 0.508)
			(layers "F.Cu" "F.Mask" "F.Paste")
			(net "GND")
		)
	)
	(footprint ""
		(layer "F.Cu")
		(at 25.931622 -95.65132)
		(property "Reference" "R47"
			(at -4.080256 -0.075692 0)
			(unlocked yes)
			(layer "F.SilkS")
			(effects
				(font
					(size 0.7874 0.5842)
					(thickness 0.1524)
				)
				(justify left)
			)
		)
		(property "Value" ""
			(at 0 0 0)
			(layer "F.Fab")
			(effects
				(font
					(size 1.27 1.27)
				)
			)
		)
		(duplicate_pad_numbers_are_jumpers no)
		(fp_line
			(start -0.7874 -0.4064)
			(end 0.7874 -0.4064)
			(stroke
				(width 0.1524)
				(type default)
			)
			(layer "F.SilkS")
		)
		(fp_line
			(start -0.7874 0.4064)
			(end -0.7874 -0.4064)
			(stroke
				(width 0.1524)
				(type default)
			)
			(layer "F.SilkS")
		)
		(fp_line
			(start 0.7874 -0.4064)
			(end 0.7874 0.4064)
			(stroke
				(width 0.1524)
				(type default)
			)
			(layer "F.SilkS")
		)
		(fp_line
			(start 0.7874 0.4064)
			(end -0.7874 0.4064)
			(stroke
				(width 0.1524)
				(type default)
			)
			(layer "F.SilkS")
		)
		(fp_poly
			(pts
				(xy -0.508 0.2794) (xy -0.508 0.2286) (xy -0.635 0.2286) (xy -0.635 -0.254) (xy -0.5334 -0.254)
				(xy -0.5334 -0.2794) (xy 0.5334 -0.2794) (xy 0.5334 -0.254) (xy 0.635 -0.254) (xy 0.635 0.254) (xy 0.5334 0.254)
				(xy 0.5334 0.2794)
			)
			(stroke
				(width 0)
				(type default)
			)
			(fill no)
			(layer "F.CrtYd")
		)
		(pad "1" smd rect
			(at 0.40005 0)
			(size 0.4572 0.508)
			(layers "F.Cu" "F.Mask" "F.Paste")
			(net "PSU2_RESET")
		)
		(pad "2" smd rect
			(at -0.40005 0)
			(size 0.4572 0.508)
			(layers "F.Cu" "F.Mask" "F.Paste")
			(net "GND")
		)
	)
	(footprint ""
		(layer "F.Cu")
		(at 71.815198 -193.582544 -90)
		(property "Reference" "C31"
			(at 0.978662 -4.304284 90)
			(unlocked yes)
			(layer "F.SilkS")
			(effects
				(font
					(size 0.7874 0.5842)
					(thickness 0.1524)
				)
				(justify left)
			)
		)
		(property "Value" ""
			(at 0 0 270)
			(layer "F.Fab")
			(effects
				(font
					(size 1.27 1.27)
				)
			)
		)
		(duplicate_pad_numbers_are_jumpers no)
		(fp_line
			(start -0.7874 0.4064)
			(end -0.7874 -0.4064)
			(stroke
				(width 0.1524)
				(type default)
			)
			(layer "F.SilkS")
		)
		(fp_line
			(start 0.7874 0.4064)
			(end -0.7874 0.4064)
			(stroke
				(width 0.1524)
				(type default)
			)
			(layer "F.SilkS")
		)
		(fp_line
			(start 0 0.381)
			(end 0 -0.381)
			(stroke
				(width 0.1524)
				(type default)
			)
			(layer "F.SilkS")
		)
		(fp_line
			(start -0.7874 -0.4064)
			(end 0.7874 -0.4064)
			(stroke
				(width 0.1524)
				(type default)
			)
			(layer "F.SilkS")
		)
		(fp_line
			(start 0.7874 -0.4064)
			(end 0.7874 0.4064)
			(stroke
				(width 0.1524)
				(type default)
			)
			(layer "F.SilkS")
		)
		(fp_poly
			(pts
				(xy -0.5334 0.254) (xy -0.635 0.254) (xy -0.635 0.2286) (xy -0.635 -0.254) (xy -0.5334 -0.254) (xy -0.5334 -0.2794)
				(xy 0.5334 -0.2794) (xy 0.5334 -0.254) (xy 0.635 -0.254) (xy 0.635 0.254) (xy 0.5334 0.254) (xy 0.5334 0.2794)
				(xy -0.508 0.2794) (xy -0.5334 0.2794)
			)
			(stroke
				(width 0)
				(type default)
			)
			(fill no)
			(layer "F.CrtYd")
		)
		(pad "1" smd rect
			(at 0.40005 0 270)
			(size 0.4572 0.508)
			(layers "F.Cu" "F.Mask" "F.Paste")
			(net "P12V")
		)
		(pad "2" smd rect
			(at -0.40005 0 270)
			(size 0.4572 0.508)
			(layers "F.Cu" "F.Mask" "F.Paste")
			(net "GND")
		)
	)
	(footprint ""
		(layer "F.Cu")
		(at 91.399868 -153.359866)
		(property "Reference" "H22"
			(at -5.1308 -5.23113 0)
			(unlocked yes)
			(layer "F.SilkS")
			(effects
				(font
					(size 0.7874 0.5842)
					(thickness 0.1524)
				)
				(justify left)
			)
		)
		(property "Value" ""
			(at 0 0 0)
			(layer "F.Fab")
			(effects
				(font
					(size 1.27 1.27)
				)
			)
		)
		(duplicate_pad_numbers_are_jumpers no)
		(fp_circle
			(center 0 0)
			(end 4.826 0)
			(stroke
				(width 0.1524)
				(type default)
			)
			(fill no)
			(layer "F.SilkS")
		)
		(fp_circle
			(center 0 0)
			(end 4.826 0)
			(stroke
				(width 0.1524)
				(type default)
			)
			(fill no)
			(layer "B.SilkS")
		)
		(fp_poly
			(pts
				(arc
					(start 0 4.0132)
					(mid 0 -4.0132)
					(end 0 4.0132)
				)
			)
			(stroke
				(width 0)
				(type default)
			)
			(fill no)
			(layer "F.CrtYd")
		)
		(pad "" np_thru_hole circle
			(at 0 0)
			(size 8.001 8.001)
			(drill 8.001)
			(layers "*.Cu" "*.Mask")
			(clearance 0.381)
			(thermal_gap 0.381)
		)
		(zone
			(layers "F.Cu" "B.Cu" "In1.Cu" "In2.Cu" "In3.Cu" "In4.Cu" "In5.Cu" "In6.Cu")
			(hatch none 0.5)
			(connect_pads
				(clearance 0)
			)
			(min_thickness 0.25)
			(keepout
				(tracks not_allowed)
				(vias allowed)
				(pads allowed)
				(copperpour not_allowed)
				(footprints allowed)
			)
			(placement
				(enabled no)
				(sheetname "")
			)
			(fill
				(thermal_gap 0.5)
				(thermal_bridge_width 0.5)
				(island_removal_mode 0)
			)
			(polygon
				(pts
					(arc
						(start 91.399868 -148.838666)
						(mid 91.399868 -157.881066)
						(end 91.399868 -148.838666)
					)
				)
			)
		)
	)
	(footprint ""
		(layer "F.Cu")
		(at 72.520302 -87.145368 90)
		(property "Reference" "C20"
			(at -4.402836 -0.015748 90)
			(unlocked yes)
			(layer "F.SilkS")
			(effects
				(font
					(size 0.7874 0.5842)
					(thickness 0.1524)
				)
				(justify left)
			)
		)
		(property "Value" ""
			(at 0 0 90)
			(layer "F.Fab")
			(effects
				(font
					(size 1.27 1.27)
				)
			)
		)
		(duplicate_pad_numbers_are_jumpers no)
		(fp_line
			(start 0.7874 -0.4064)
			(end 0.7874 0.4064)
			(stroke
				(width 0.1524)
				(type default)
			)
			(layer "F.SilkS")
		)
		(fp_line
			(start -0.7874 -0.4064)
			(end 0.7874 -0.4064)
			(stroke
				(width 0.1524)
				(type default)
			)
			(layer "F.SilkS")
		)
		(fp_line
			(start 0 0.381)
			(end 0 -0.381)
			(stroke
				(width 0.1524)
				(type default)
			)
			(layer "F.SilkS")
		)
		(fp_line
			(start 0.7874 0.4064)
			(end -0.7874 0.4064)
			(stroke
				(width 0.1524)
				(type default)
			)
			(layer "F.SilkS")
		)
		(fp_line
			(start -0.7874 0.4064)
			(end -0.7874 -0.4064)
			(stroke
				(width 0.1524)
				(type default)
			)
			(layer "F.SilkS")
		)
		(fp_poly
			(pts
				(xy -0.5334 0.254) (xy -0.635 0.254) (xy -0.635 0.2286) (xy -0.635 -0.254) (xy -0.5334 -0.254) (xy -0.5334 -0.2794)
				(xy 0.5334 -0.2794) (xy 0.5334 -0.254) (xy 0.635 -0.254) (xy 0.635 0.254) (xy 0.5334 0.254) (xy 0.5334 0.2794)
				(xy -0.508 0.2794) (xy -0.5334 0.2794)
			)
			(stroke
				(width 0)
				(type default)
			)
			(fill no)
			(layer "F.CrtYd")
		)
		(pad "1" smd rect
			(at 0.40005 0 90)
			(size 0.4572 0.508)
			(layers "F.Cu" "F.Mask" "F.Paste")
			(net "P12V")
		)
		(pad "2" smd rect
			(at -0.40005 0 90)
			(size 0.4572 0.508)
			(layers "F.Cu" "F.Mask" "F.Paste")
			(net "GND")
		)
	)
	(footprint ""
		(layer "F.Cu")
		(at 50.54981 -507.67742 180)
		(property "Reference" "CE23"
			(at 2.73939 5.49021 0)
			(unlocked yes)
			(layer "F.SilkS")
			(effects
				(font
					(size 0.7874 0.5842)
					(thickness 0.1524)
				)
				(justify left)
			)
		)
		(property "Value" ""
			(at 0 0 180)
			(layer "F.Fab")
			(effects
				(font
					(size 1.27 1.27)
				)
			)
		)
		(duplicate_pad_numbers_are_jumpers no)
		(fp_line
			(start 0 -4.2672)
			(end 0 4.2672)
			(stroke
				(width 0.1524)
				(type default)
			)
			(layer "F.SilkS")
		)
		(fp_circle
			(center 0 0)
			(end -4.2672 0)
			(stroke
				(width 0.1524)
				(type default)
			)
			(fill no)
			(layer "F.SilkS")
		)
		(fp_poly
			(pts
				(arc
					(start 0 -4.2672)
					(mid 4.2672 0)
					(end 0 4.2672)
				)
			)
			(stroke
				(width 0)
				(type default)
			)
			(fill yes)
			(layer "F.SilkS")
		)
		(fp_poly
			(pts
				(xy -2.5146 -0.762) (xy -0.9906 -0.762) (xy -0.9906 0.762) (xy -2.5146 0.762)
			)
			(stroke
				(width 0)
				(type default)
			)
			(fill no)
			(layer "B.CrtYd")
		)
		(fp_poly
			(pts
				(arc
					(start 1.7526 0.762)
					(mid 2.291415 -0.538815)
					(end 0.9906 0)
				)
				(arc
					(start 0.9906 0.0254)
					(mid 1.206345 0.546255)
					(end 1.7272 0.762)
				)
			)
			(stroke
				(width 0)
				(type default)
			)
			(fill no)
			(layer "B.CrtYd")
		)
		(fp_poly
			(pts
				(arc
					(start -4.2672 0)
					(mid 4.2672 0)
					(end -4.2672 0)
				)
			)
			(stroke
				(width 0)
				(type default)
			)
			(fill no)
			(layer "F.CrtYd")
		)
		(fp_circle
			(center 0 0)
			(end -4.2672 0)
			(stroke
				(width 0.1)
				(type default)
			)
			(fill no)
			(layer "F.Fab")
		)
		(fp_text user "+"
			(at -5.619496 0.15367 180)
			(unlocked yes)
			(layer "F.SilkS")
			(effects
				(font
					(size 0.7874 0.5842)
					(thickness 0.1524)
				)
				(justify left)
			)
		)
		(fp_text user "+"
			(at -5.6642 -0.34925 180)
			(unlocked yes)
			(layer "F.Fab")
			(effects
				(font
					(size 1.905 1.4224)
					(thickness 0.000001)
				)
				(justify left)
			)
		)
		(pad "1" thru_hole rect
			(at -1.75006 0 180)
			(size 1.397 1.397)
			(drill 0.9144)
			(layers "*.Cu" "*.Mask")
			(remove_unused_layers no)
			(net "P12V")
			(clearance 0.0127)
			(thermal_gap 0.0127)
			(padstack
				(mode front_inner_back)
				(layer "Inner"
					(shape circle)
					(size 1.397 1.397)
					(clearance 0.0127)
				)
				(layer "B.Cu"
					(shape rect)
					(size 1.397 1.397)
					(clearance 0.0127)
				)
			)
		)
		(pad "2" thru_hole circle
			(at 1.75006 0 180)
			(size 1.397 1.397)
			(drill 0.9144)
			(layers "*.Cu" "*.Mask")
			(remove_unused_layers no)
			(net "GND")
			(clearance 0.0127)
			(thermal_gap 0.0127)
		)
	)
	(footprint ""
		(layer "F.Cu")
		(at 50.39868 -463.099658 180)
		(property "Reference" "CE22"
			(at -4.925568 2.154174 0)
			(unlocked yes)
			(layer "F.SilkS")
			(effects
				(font
					(size 0.7874 0.5842)
					(thickness 0.1524)
				)
				(justify left)
			)
		)
		(property "Value" ""
			(at 0 0 180)
			(layer "F.Fab")
			(effects
				(font
					(size 1.27 1.27)
				)
			)
		)
		(duplicate_pad_numbers_are_jumpers no)
		(fp_line
			(start 0 -4.2672)
			(end 0 4.2672)
			(stroke
				(width 0.1524)
				(type default)
			)
			(layer "F.SilkS")
		)
		(fp_circle
			(center 0 0)
			(end -4.2672 0)
			(stroke
				(width 0.1524)
				(type default)
			)
			(fill no)
			(layer "F.SilkS")
		)
		(fp_poly
			(pts
				(arc
					(start 0 -4.2672)
					(mid 4.2672 0)
					(end 0 4.2672)
				)
			)
			(stroke
				(width 0)
				(type default)
			)
			(fill yes)
			(layer "F.SilkS")
		)
		(fp_poly
			(pts
				(xy -2.5146 -0.762) (xy -0.9906 -0.762) (xy -0.9906 0.762) (xy -2.5146 0.762)
			)
			(stroke
				(width 0)
				(type default)
			)
			(fill no)
			(layer "B.CrtYd")
		)
		(fp_poly
			(pts
				(arc
					(start 1.7526 0.762)
					(mid 2.291415 -0.538815)
					(end 0.9906 0)
				)
				(arc
					(start 0.9906 0.0254)
					(mid 1.206345 0.546255)
					(end 1.7272 0.762)
				)
			)
			(stroke
				(width 0)
				(type default)
			)
			(fill no)
			(layer "B.CrtYd")
		)
		(fp_poly
			(pts
				(arc
					(start -4.2672 0)
					(mid 4.2672 0)
					(end -4.2672 0)
				)
			)
			(stroke
				(width 0)
				(type default)
			)
			(fill no)
			(layer "F.CrtYd")
		)
		(fp_circle
			(center 0 0)
			(end -4.2672 0)
			(stroke
				(width 0.1)
				(type default)
			)
			(fill no)
			(layer "F.Fab")
		)
		(fp_text user "+"
			(at -5.6642 0.15367 180)
			(unlocked yes)
			(layer "F.SilkS")
			(effects
				(font
					(size 0.7874 0.5842)
					(thickness 0.1524)
				)
				(justify left)
			)
		)
		(fp_text user "+"
			(at -5.6642 -0.34925 180)
			(unlocked yes)
			(layer "F.Fab")
			(effects
				(font
					(size 1.905 1.4224)
					(thickness 0.000001)
				)
				(justify left)
			)
		)
		(pad "1" thru_hole rect
			(at -1.75006 0 180)
			(size 1.397 1.397)
			(drill 0.9144)
			(layers "*.Cu" "*.Mask")
			(remove_unused_layers no)
			(net "P12V")
			(clearance 0.0127)
			(thermal_gap 0.0127)
			(padstack
				(mode front_inner_back)
				(layer "Inner"
					(shape circle)
					(size 1.397 1.397)
					(clearance 0.0127)
				)
				(layer "B.Cu"
					(shape rect)
					(size 1.397 1.397)
					(clearance 0.0127)
				)
			)
		)
		(pad "2" thru_hole circle
			(at 1.75006 0 180)
			(size 1.397 1.397)
			(drill 0.9144)
			(layers "*.Cu" "*.Mask")
			(remove_unused_layers no)
			(net "GND")
			(clearance 0.0127)
			(thermal_gap 0.0127)
		)
	)
	(footprint ""
		(layer "F.Cu")
		(at 13.463778 -325.064882 180)
		(property "Reference" "R142"
			(at -1.084834 -0.000254 0)
			(unlocked yes)
			(layer "F.SilkS")
			(effects
				(font
					(size 0.7874 0.5842)
					(thickness 0.1524)
				)
				(justify left)
			)
		)
		(property "Value" ""
			(at 0 0 180)
			(layer "F.Fab")
			(effects
				(font
					(size 1.27 1.27)
				)
			)
		)
		(duplicate_pad_numbers_are_jumpers no)
		(fp_line
			(start 0.7874 0.4064)
			(end -0.7874 0.4064)
			(stroke
				(width 0.1524)
				(type default)
			)
			(layer "F.SilkS")
		)
		(fp_line
			(start 0.7874 -0.4064)
			(end 0.7874 0.4064)
			(stroke
				(width 0.1524)
				(type default)
			)
			(layer "F.SilkS")
		)
		(fp_line
			(start -0.7874 0.4064)
			(end -0.7874 -0.4064)
			(stroke
				(width 0.1524)
				(type default)
			)
			(layer "F.SilkS")
		)
		(fp_line
			(start -0.7874 -0.4064)
			(end 0.7874 -0.4064)
			(stroke
				(width 0.1524)
				(type default)
			)
			(layer "F.SilkS")
		)
		(fp_poly
			(pts
				(xy -0.508 0.2794) (xy -0.508 0.2286) (xy -0.635 0.2286) (xy -0.635 -0.254) (xy -0.5334 -0.254)
				(xy -0.5334 -0.2794) (xy 0.5334 -0.2794) (xy 0.5334 -0.254) (xy 0.635 -0.254) (xy 0.635 0.254) (xy 0.5334 0.254)
				(xy 0.5334 0.2794)
			)
			(stroke
				(width 0)
				(type default)
			)
			(fill no)
			(layer "F.CrtYd")
		)
		(pad "1" smd rect
			(at 0.40005 0 180)
			(size 0.4572 0.508)
			(layers "F.Cu" "F.Mask" "F.Paste")
			(net "FAN1_TACH")
		)
		(pad "2" smd rect
			(at -0.40005 0 180)
			(size 0.4572 0.508)
			(layers "F.Cu" "F.Mask" "F.Paste")
			(net "P12V")
		)
	)
	(footprint ""
		(layer "F.Cu")
		(at 71.871332 -282.664154 -90)
		(property "Reference" "C43"
			(at 0.298704 -4.020312 90)
			(unlocked yes)
			(layer "F.SilkS")
			(effects
				(font
					(size 0.7874 0.5842)
					(thickness 0.1524)
				)
			)
		)
		(property "Value" ""
			(at 0 0 270)
			(layer "F.Fab")
			(effects
				(font
					(size 1.27 1.27)
				)
			)
		)
		(duplicate_pad_numbers_are_jumpers no)
		(fp_line
			(start -1.2954 0.5842)
			(end -1.2954 -0.5842)
			(stroke
				(width 0.1524)
				(type default)
			)
			(layer "F.SilkS")
		)
		(fp_line
			(start 1.2954 0.5842)
			(end -1.2954 0.5842)
			(stroke
				(width 0.1524)
				(type default)
			)
			(layer "F.SilkS")
		)
		(fp_line
			(start -1.2954 -0.5842)
			(end 1.2954 -0.5842)
			(stroke
				(width 0.1524)
				(type default)
			)
			(layer "F.SilkS")
		)
		(fp_line
			(start 0 -0.5842)
			(end 0 0.5842)
			(stroke
				(width 0.1524)
				(type default)
			)
			(layer "F.SilkS")
		)
		(fp_line
			(start 1.2954 -0.5842)
			(end 1.2954 0.5842)
			(stroke
				(width 0.1524)
				(type default)
			)
			(layer "F.SilkS")
		)
		(fp_poly
			(pts
				(xy 0.8636 -0.4572) (xy 0.8636 -0.3556) (xy 1.143 -0.3556) (xy 1.143 0.3556) (xy 0.8636 0.3556)
				(xy 0.8636 0.4572) (xy -0.8636 0.4572) (xy -0.8636 0.3556) (xy -1.143 0.3556) (xy -1.143 -0.3556)
				(xy -0.8636 -0.3556) (xy -0.8636 -0.4572)
			)
			(stroke
				(width 0)
				(type default)
			)
			(fill no)
			(layer "F.CrtYd")
		)
		(fp_line
			(start -0.884936 0.504952)
			(end -0.884936 -0.504952)
			(stroke
				(width 0.1)
				(type default)
			)
			(layer "F.Fab")
		)
		(fp_line
			(start 0.884936 0.504952)
			(end -0.884936 0.504952)
			(stroke
				(width 0.1)
				(type default)
			)
			(layer "F.Fab")
		)
		(fp_line
			(start -0.884936 -0.504952)
			(end 0.884936 -0.504952)
			(stroke
				(width 0.1)
				(type default)
			)
			(layer "F.Fab")
		)
		(fp_line
			(start 0.884936 -0.504952)
			(end 0.884936 0.504952)
			(stroke
				(width 0.1)
				(type default)
			)
			(layer "F.Fab")
		)
		(pad "1" smd rect
			(at 0.7366 0)
			(size 0.7112 0.8128)
			(layers "F.Cu" "F.Mask" "F.Paste")
			(net "P12V")
		)
		(pad "2" smd rect
			(at -0.7366 0)
			(size 0.7112 0.8128)
			(layers "F.Cu" "F.Mask" "F.Paste")
			(net "GND")
		)
	)
	(footprint ""
		(layer "F.Cu")
		(at 69.370956 -194.090544 -90)
		(property "Reference" "C29"
			(at 0.407162 -4.16433 90)
			(unlocked yes)
			(layer "F.SilkS")
			(effects
				(font
					(size 0.7874 0.5842)
					(thickness 0.1524)
				)
			)
		)
		(property "Value" ""
			(at 0 0 270)
			(layer "F.Fab")
			(effects
				(font
					(size 1.27 1.27)
				)
			)
		)
		(duplicate_pad_numbers_are_jumpers no)
		(fp_line
			(start -1.2954 0.5842)
			(end -1.2954 -0.5842)
			(stroke
				(width 0.1524)
				(type default)
			)
			(layer "F.SilkS")
		)
		(fp_line
			(start 1.2954 0.5842)
			(end -1.2954 0.5842)
			(stroke
				(width 0.1524)
				(type default)
			)
			(layer "F.SilkS")
		)
		(fp_line
			(start -1.2954 -0.5842)
			(end 1.2954 -0.5842)
			(stroke
				(width 0.1524)
				(type default)
			)
			(layer "F.SilkS")
		)
		(fp_line
			(start 0 -0.5842)
			(end 0 0.5842)
			(stroke
				(width 0.1524)
				(type default)
			)
			(layer "F.SilkS")
		)
		(fp_line
			(start 1.2954 -0.5842)
			(end 1.2954 0.5842)
			(stroke
				(width 0.1524)
				(type default)
			)
			(layer "F.SilkS")
		)
		(fp_poly
			(pts
				(xy 0.8636 -0.4572) (xy 0.8636 -0.3556) (xy 1.143 -0.3556) (xy 1.143 0.3556) (xy 0.8636 0.3556)
				(xy 0.8636 0.4572) (xy -0.8636 0.4572) (xy -0.8636 0.3556) (xy -1.143 0.3556) (xy -1.143 -0.3556)
				(xy -0.8636 -0.3556) (xy -0.8636 -0.4572)
			)
			(stroke
				(width 0)
				(type default)
			)
			(fill no)
			(layer "F.CrtYd")
		)
		(fp_line
			(start -0.884936 0.504952)
			(end -0.884936 -0.504952)
			(stroke
				(width 0.1)
				(type default)
			)
			(layer "F.Fab")
		)
		(fp_line
			(start 0.884936 0.504952)
			(end -0.884936 0.504952)
			(stroke
				(width 0.1)
				(type default)
			)
			(layer "F.Fab")
		)
		(fp_line
			(start -0.884936 -0.504952)
			(end 0.884936 -0.504952)
			(stroke
				(width 0.1)
				(type default)
			)
			(layer "F.Fab")
		)
		(fp_line
			(start 0.884936 -0.504952)
			(end 0.884936 0.504952)
			(stroke
				(width 0.1)
				(type default)
			)
			(layer "F.Fab")
		)
		(pad "1" smd rect
			(at 0.7366 0)
			(size 0.7112 0.8128)
			(layers "F.Cu" "F.Mask" "F.Paste")
			(net "P12V")
		)
		(pad "2" smd rect
			(at -0.7366 0)
			(size 0.7112 0.8128)
			(layers "F.Cu" "F.Mask" "F.Paste")
			(net "GND")
		)
	)
	(footprint ""
		(layer "F.Cu")
		(at 74.153522 -42.631106 90)
		(property "Reference" "C12"
			(at -1.11506 4.720336 90)
			(unlocked yes)
			(layer "F.SilkS")
			(effects
				(font
					(size 0.7874 0.5842)
					(thickness 0.1524)
				)
				(justify left)
			)
		)
		(property "Value" ""
			(at 0 0 90)
			(layer "F.Fab")
			(effects
				(font
					(size 1.27 1.27)
				)
			)
		)
		(duplicate_pad_numbers_are_jumpers no)
		(fp_line
			(start 0.7874 -0.4064)
			(end 0.7874 0.4064)
			(stroke
				(width 0.1524)
				(type default)
			)
			(layer "F.SilkS")
		)
		(fp_line
			(start -0.7874 -0.4064)
			(end 0.7874 -0.4064)
			(stroke
				(width 0.1524)
				(type default)
			)
			(layer "F.SilkS")
		)
		(fp_line
			(start 0 0.381)
			(end 0 -0.381)
			(stroke
				(width 0.1524)
				(type default)
			)
			(layer "F.SilkS")
		)
		(fp_line
			(start 0.7874 0.4064)
			(end -0.7874 0.4064)
			(stroke
				(width 0.1524)
				(type default)
			)
			(layer "F.SilkS")
		)
		(fp_line
			(start -0.7874 0.4064)
			(end -0.7874 -0.4064)
			(stroke
				(width 0.1524)
				(type default)
			)
			(layer "F.SilkS")
		)
		(fp_poly
			(pts
				(xy -0.5334 0.254) (xy -0.635 0.254) (xy -0.635 0.2286) (xy -0.635 -0.254) (xy -0.5334 -0.254) (xy -0.5334 -0.2794)
				(xy 0.5334 -0.2794) (xy 0.5334 -0.254) (xy 0.635 -0.254) (xy 0.635 0.254) (xy 0.5334 0.254) (xy 0.5334 0.2794)
				(xy -0.508 0.2794) (xy -0.5334 0.2794)
			)
			(stroke
				(width 0)
				(type default)
			)
			(fill no)
			(layer "F.CrtYd")
		)
		(pad "1" smd rect
			(at 0.40005 0 90)
			(size 0.4572 0.508)
			(layers "F.Cu" "F.Mask" "F.Paste")
			(net "P12V")
		)
		(pad "2" smd rect
			(at -0.40005 0 90)
			(size 0.4572 0.508)
			(layers "F.Cu" "F.Mask" "F.Paste")
			(net "GND")
		)
	)
	(footprint ""
		(layer "F.Cu")
		(at 69.774816 -442.84646 90)
		(property "Reference" "C77"
			(at -3.83667 0.064516 90)
			(unlocked yes)
			(layer "F.SilkS")
			(effects
				(font
					(size 0.7874 0.5842)
					(thickness 0.1524)
				)
				(justify left)
			)
		)
		(property "Value" ""
			(at 0 0 90)
			(layer "F.Fab")
			(effects
				(font
					(size 1.27 1.27)
				)
			)
		)
		(duplicate_pad_numbers_are_jumpers no)
		(fp_line
			(start 0.7874 -0.4064)
			(end 0.7874 0.4064)
			(stroke
				(width 0.1524)
				(type default)
			)
			(layer "F.SilkS")
		)
		(fp_line
			(start -0.7874 -0.4064)
			(end 0.7874 -0.4064)
			(stroke
				(width 0.1524)
				(type default)
			)
			(layer "F.SilkS")
		)
		(fp_line
			(start 0 0.381)
			(end 0 -0.381)
			(stroke
				(width 0.1524)
				(type default)
			)
			(layer "F.SilkS")
		)
		(fp_line
			(start 0.7874 0.4064)
			(end -0.7874 0.4064)
			(stroke
				(width 0.1524)
				(type default)
			)
			(layer "F.SilkS")
		)
		(fp_line
			(start -0.7874 0.4064)
			(end -0.7874 -0.4064)
			(stroke
				(width 0.1524)
				(type default)
			)
			(layer "F.SilkS")
		)
		(fp_poly
			(pts
				(xy -0.5334 0.254) (xy -0.635 0.254) (xy -0.635 0.2286) (xy -0.635 -0.254) (xy -0.5334 -0.254) (xy -0.5334 -0.2794)
				(xy 0.5334 -0.2794) (xy 0.5334 -0.254) (xy 0.635 -0.254) (xy 0.635 0.254) (xy 0.5334 0.254) (xy 0.5334 0.2794)
				(xy -0.508 0.2794) (xy -0.5334 0.2794)
			)
			(stroke
				(width 0)
				(type default)
			)
			(fill no)
			(layer "F.CrtYd")
		)
		(pad "1" smd rect
			(at 0.40005 0 90)
			(size 0.4572 0.508)
			(layers "F.Cu" "F.Mask" "F.Paste")
			(net "P12V")
		)
		(pad "2" smd rect
			(at -0.40005 0 90)
			(size 0.4572 0.508)
			(layers "F.Cu" "F.Mask" "F.Paste")
			(net "GND")
		)
	)
	(footprint ""
		(layer "F.Cu")
		(at 40.303958 -370.099336 180)
		(property "Reference" "R24"
			(at -1.863598 -0.010922 0)
			(unlocked yes)
			(layer "F.SilkS")
			(effects
				(font
					(size 0.7874 0.5842)
					(thickness 0.1524)
				)
				(justify left)
			)
		)
		(property "Value" ""
			(at 0 0 180)
			(layer "F.Fab")
			(effects
				(font
					(size 1.27 1.27)
				)
			)
		)
		(duplicate_pad_numbers_are_jumpers no)
		(fp_line
			(start 0.7874 0.4064)
			(end -0.7874 0.4064)
			(stroke
				(width 0.1524)
				(type default)
			)
			(layer "F.SilkS")
		)
		(fp_line
			(start 0.7874 -0.4064)
			(end 0.7874 0.4064)
			(stroke
				(width 0.1524)
				(type default)
			)
			(layer "F.SilkS")
		)
		(fp_line
			(start -0.7874 0.4064)
			(end -0.7874 -0.4064)
			(stroke
				(width 0.1524)
				(type default)
			)
			(layer "F.SilkS")
		)
		(fp_line
			(start -0.7874 -0.4064)
			(end 0.7874 -0.4064)
			(stroke
				(width 0.1524)
				(type default)
			)
			(layer "F.SilkS")
		)
		(fp_poly
			(pts
				(xy -0.508 0.2794) (xy -0.508 0.2286) (xy -0.635 0.2286) (xy -0.635 -0.254) (xy -0.5334 -0.254)
				(xy -0.5334 -0.2794) (xy 0.5334 -0.2794) (xy 0.5334 -0.254) (xy 0.635 -0.254) (xy 0.635 0.254) (xy 0.5334 0.254)
				(xy 0.5334 0.2794)
			)
			(stroke
				(width 0)
				(type default)
			)
			(fill no)
			(layer "F.CrtYd")
		)
		(pad "1" smd rect
			(at 0.40005 0 180)
			(size 0.4572 0.508)
			(layers "F.Cu" "F.Mask" "F.Paste")
			(net "PSU5_RETURN")
		)
		(pad "2" smd rect
			(at -0.40005 0 180)
			(size 0.4572 0.508)
			(layers "F.Cu" "F.Mask" "F.Paste")
			(net "GND")
		)
	)
	(footprint ""
		(layer "F.Cu")
		(at 6.449822 -352.669856)
		(property "Reference" "J25"
			(at 6.653784 1.81356 90)
			(unlocked yes)
			(layer "F.SilkS")
			(effects
				(font
					(size 0.7874 0.5842)
					(thickness 0.1524)
				)
				(justify left)
			)
		)
		(property "Value" ""
			(at 0 0 0)
			(layer "F.Fab")
			(effects
				(font
					(size 1.27 1.27)
				)
			)
		)
		(duplicate_pad_numbers_are_jumpers no)
		(fp_line
			(start -9.400032 -5.999988)
			(end -9.400032 89.229946)
			(stroke
				(width 0.1524)
				(type default)
			)
			(layer "F.SilkS")
		)
		(fp_line
			(start -9.400032 89.229946)
			(end 5.649976 89.229946)
			(stroke
				(width 0.1524)
				(type default)
			)
			(layer "F.SilkS")
		)
		(fp_line
			(start -6.400038 -2.999994)
			(end 2.649982 -2.999994)
			(stroke
				(width 0.1524)
				(type default)
			)
			(layer "F.SilkS")
		)
		(fp_line
			(start -6.400038 86.229952)
			(end -6.400038 -2.999994)
			(stroke
				(width 0.1524)
				(type default)
			)
			(layer "F.SilkS")
		)
		(fp_line
			(start -2.265172 86.229952)
			(end -6.400038 86.229952)
			(stroke
				(width 0.1524)
				(type default)
			)
			(layer "F.SilkS")
		)
		(fp_line
			(start 2.649982 -2.999994)
			(end 2.649982 86.229952)
			(stroke
				(width 0.1524)
				(type default)
			)
			(layer "F.SilkS")
		)
		(fp_line
			(start 2.649982 86.229952)
			(end -0.334772 86.229952)
			(stroke
				(width 0.1524)
				(type default)
			)
			(layer "F.SilkS")
		)
		(fp_line
			(start 5.649976 -5.999988)
			(end -9.400032 -5.999988)
			(stroke
				(width 0.1524)
				(type default)
			)
			(layer "F.SilkS")
		)
		(fp_line
			(start 5.649976 89.229946)
			(end 5.649976 -5.999988)
			(stroke
				(width 0.1524)
				(type default)
			)
			(layer "F.SilkS")
		)
		(fp_poly
			(pts
				(xy 0.127 -6.569456) (xy 0.889 -8.474456) (xy -0.635 -8.474456)
			)
			(stroke
				(width 0)
				(type default)
			)
			(fill yes)
			(layer "F.SilkS")
		)
		(fp_line
			(start -9.400032 -5.999988)
			(end -9.400032 89.229946)
			(stroke
				(width 0.1524)
				(type default)
			)
			(layer "B.SilkS")
		)
		(fp_line
			(start -9.400032 89.229946)
			(end 5.649976 89.229946)
			(stroke
				(width 0.1524)
				(type default)
			)
			(layer "B.SilkS")
		)
		(fp_line
			(start -6.400038 -2.999994)
			(end 2.649982 -2.999994)
			(stroke
				(width 0.1524)
				(type default)
			)
			(layer "B.SilkS")
		)
		(fp_line
			(start -6.400038 86.229952)
			(end -6.400038 -2.999994)
			(stroke
				(width 0.1524)
				(type default)
			)
			(layer "B.SilkS")
		)
		(fp_line
			(start -2.265172 86.229952)
			(end -6.400038 86.229952)
			(stroke
				(width 0.1524)
				(type default)
			)
			(layer "B.SilkS")
		)
		(fp_line
			(start 2.649982 -2.999994)
			(end 2.649982 86.229952)
			(stroke
				(width 0.1524)
				(type default)
			)
			(layer "B.SilkS")
		)
		(fp_line
			(start 2.649982 86.229952)
			(end -0.334772 86.229952)
			(stroke
				(width 0.1524)
				(type default)
			)
			(layer "B.SilkS")
		)
		(fp_line
			(start 5.649976 -5.999988)
			(end -9.400032 -5.999988)
			(stroke
				(width 0.1524)
				(type default)
			)
			(layer "B.SilkS")
		)
		(fp_line
			(start 5.649976 89.229946)
			(end 5.649976 -5.999988)
			(stroke
				(width 0.1524)
				(type default)
			)
			(layer "B.SilkS")
		)
		(fp_poly
			(pts
				(xy 0.127 -6.569456) (xy 0.889 -8.474456) (xy -0.635 -8.474456)
			)
			(stroke
				(width 0)
				(type default)
			)
			(fill yes)
			(layer "B.SilkS")
		)
		(fp_poly
			(pts
				(xy 2.5654 -0.5842) (xy -5.08 -0.5842) (xy -5.08 86.2838) (xy 2.5654 86.2838)
			)
			(stroke
				(width 0)
				(type default)
			)
			(fill no)
			(layer "B.CrtYd")
		)
		(fp_poly
			(pts
				(xy -6.400038 -2.999994) (xy -6.400038 86.229952) (xy -1.624838 86.229952) (xy -1.624838 86.2838)
				(xy -0.964438 86.2838) (xy -0.964438 86.229952) (xy 2.649982 86.229952) (xy 2.649982 -2.999994)
			)
			(stroke
				(width 0)
				(type default)
			)
			(fill no)
			(layer "F.CrtYd")
		)
		(fp_line
			(start -6.400038 -2.999994)
			(end -6.400038 86.229952)
			(stroke
				(width 0.1)
				(type default)
			)
			(layer "F.Fab")
		)
		(fp_line
			(start -6.400038 86.229952)
			(end 2.649982 86.229952)
			(stroke
				(width 0.1)
				(type default)
			)
			(layer "F.Fab")
		)
		(fp_line
			(start 2.649982 -2.999994)
			(end -6.400038 -2.999994)
			(stroke
				(width 0.1)
				(type default)
			)
			(layer "F.Fab")
		)
		(fp_line
			(start 2.649982 86.229952)
			(end 2.649982 -2.999994)
			(stroke
				(width 0.1)
				(type default)
			)
			(layer "F.Fab")
		)
		(fp_text user "B82"
			(at -4.692142 85.662262 90)
			(unlocked yes)
			(layer "F.SilkS")
			(effects
				(font
					(size 0.7874 0.5842)
					(thickness 0.1524)
				)
				(justify left)
			)
		)
		(fp_text user "B2"
			(at -4.289298 -3.45821 90)
			(unlocked yes)
			(layer "F.SilkS")
			(effects
				(font
					(size 0.7874 0.5842)
					(thickness 0.1524)
				)
				(justify left)
			)
		)
		(fp_text user "B81"
			(at -3.288538 85.729064 90)
			(unlocked yes)
			(layer "F.SilkS")
			(effects
				(font
					(size 0.7874 0.5842)
					(thickness 0.1524)
				)
				(justify left)
			)
		)
		(fp_text user "B1"
			(at -2.289302 -3.45821 90)
			(unlocked yes)
			(layer "F.SilkS")
			(effects
				(font
					(size 0.7874 0.5842)
					(thickness 0.1524)
				)
				(justify left)
			)
		)
		(fp_text user "A1"
			(at -0.09017 -3.658616 90)
			(unlocked yes)
			(layer "F.SilkS")
			(effects
				(font
					(size 0.7874 0.5842)
					(thickness 0.1524)
				)
				(justify left)
			)
		)
		(fp_text user "A2"
			(at 1.91008 -3.658616 90)
			(unlocked yes)
			(layer "F.SilkS")
			(effects
				(font
					(size 0.7874 0.5842)
					(thickness 0.1524)
				)
				(justify left)
			)
		)
		(fp_text user "A81"
			(at 1.930908 85.713824 90)
			(unlocked yes)
			(layer "F.SilkS")
			(effects
				(font
					(size 0.7874 0.5842)
					(thickness 0.1524)
				)
				(justify left)
			)
		)
		(fp_text user "PRESS  FIT"
			(at 9.95299 5.769864 90)
			(unlocked yes)
			(layer "F.SilkS")
			(effects
				(font
					(size 1.27 0.9652)
					(thickness 0.1524)
				)
				(justify left)
			)
		)
		(fp_text user "A82"
			(at 11.784584 85.145626 90)
			(unlocked yes)
			(layer "F.SilkS")
			(effects
				(font
					(size 0.7874 0.5842)
					(thickness 0.1524)
				)
				(justify left)
			)
		)
		(fp_text user "B2"
			(at -4.40817 0.275844 270)
			(unlocked yes)
			(layer "B.SilkS")
			(effects
				(font
					(size 0.7874 0.5842)
					(thickness 0.1524)
				)
				(justify left mirror)
			)
		)
		(fp_text user "B82"
			(at -4.40817 86.013544 270)
			(unlocked yes)
			(layer "B.SilkS")
			(effects
				(font
					(size 0.7874 0.5842)
					(thickness 0.1524)
				)
				(justify left mirror)
			)
		)
		(fp_text user "B81"
			(at -3.170174 84.489544 270)
			(unlocked yes)
			(layer "B.SilkS")
			(effects
				(font
					(size 0.7874 0.5842)
					(thickness 0.1524)
				)
				(justify left mirror)
			)
		)
		(fp_text user "B1"
			(at -2.408174 -0.867156 270)
			(unlocked yes)
			(layer "B.SilkS")
			(effects
				(font
					(size 0.7874 0.5842)
					(thickness 0.1524)
				)
				(justify left mirror)
			)
		)
		(fp_text user "A1"
			(at 0.091694 -0.867156 270)
			(unlocked yes)
			(layer "B.SilkS")
			(effects
				(font
					(size 0.7874 0.5842)
					(thickness 0.1524)
				)
				(justify left mirror)
			)
		)
		(fp_text user "A81"
			(at 0.663194 84.489544 270)
			(unlocked yes)
			(layer "B.SilkS")
			(effects
				(font
					(size 0.7874 0.5842)
					(thickness 0.1524)
				)
				(justify left mirror)
			)
		)
		(fp_text user "A2"
			(at 2.091944 0.275844 270)
			(unlocked yes)
			(layer "B.SilkS")
			(effects
				(font
					(size 0.7874 0.5842)
					(thickness 0.1524)
				)
				(justify left mirror)
			)
		)
		(fp_text user "A82"
			(at 2.091944 86.013544 270)
			(unlocked yes)
			(layer "B.SilkS")
			(effects
				(font
					(size 0.7874 0.5842)
					(thickness 0.1524)
				)
				(justify left mirror)
			)
		)
		(fp_text user "PRESS  FIT"
			(at 11.557254 39.706804 270)
			(unlocked yes)
			(layer "B.SilkS")
			(effects
				(font
					(size 1.6002 1.1938)
					(thickness 0.000001)
				)
				(justify left mirror)
			)
		)
		(pad "" np_thru_hole circle
			(at -1.249934 11.649964 270)
			(size 2.413 2.413)
			(drill 2.413)
			(layers "*.Cu" "*.Mask")
			(clearance 0.381)
			(thermal_gap 0.381)
		)
		(pad "" np_thru_hole circle
			(at -1.249934 84.799932 270)
			(size 2.413 2.413)
			(drill 2.413)
			(layers "*.Cu" "*.Mask")
			(clearance 0.381)
			(thermal_gap 0.381)
		)
		(pad "A1" thru_hole rect
			(at 0 0 270)
			(size 1.016 1.016)
			(drill 0.7112)
			(layers "*.Cu" "*.Mask")
			(remove_unused_layers no)
			(net "MATE_A1")
			(clearance 0.1016)
			(thermal_gap 0.1016)
			(padstack
				(mode front_inner_back)
				(layer "Inner"
					(shape circle)
					(size 1.016 1.016)
					(clearance 0.1016)
				)
				(layer "B.Cu"
					(shape rect)
					(size 1.016 1.016)
					(clearance 0.1016)
				)
			)
		)
		(pad "A2" thru_hole circle
			(at 1.999996 0.999998 270)
			(size 1.016 1.016)
			(drill 0.7112)
			(layers "*.Cu" "*.Mask")
			(remove_unused_layers no)
			(net "GND")
			(clearance 0.1016)
			(thermal_gap 0.1016)
		)
		(pad "A3" thru_hole circle
			(at 0 1.999996 270)
			(size 1.016 1.016)
			(drill 0.7112)
			(layers "*.Cu" "*.Mask")
			(remove_unused_layers no)
			(net "LAN2_P3_P")
			(clearance 0.1016)
			(thermal_gap 0.1016)
		)
		(pad "A4" thru_hole circle
			(at 1.999996 2.999994 270)
			(size 1.016 1.016)
			(drill 0.7112)
			(layers "*.Cu" "*.Mask")
			(remove_unused_layers no)
			(net "LAN2_P3_N")
			(clearance 0.1016)
			(thermal_gap 0.1016)
		)
		(pad "A5" thru_hole circle
			(at 0 3.999992 270)
			(size 1.016 1.016)
			(drill 0.7112)
			(layers "*.Cu" "*.Mask")
			(remove_unused_layers no)
			(net "GND")
			(clearance 0.1016)
			(thermal_gap 0.1016)
		)
		(pad "A6" thru_hole circle
			(at 1.999996 4.99999 270)
			(size 1.016 1.016)
			(drill 0.7112)
			(layers "*.Cu" "*.Mask")
			(remove_unused_layers no)
			(net "LAN2_P4_P")
			(clearance 0.1016)
			(thermal_gap 0.1016)
		)
		(pad "A7" thru_hole circle
			(at 0 5.999988 270)
			(size 1.016 1.016)
			(drill 0.7112)
			(layers "*.Cu" "*.Mask")
			(remove_unused_layers no)
			(net "LAN2_P4_N")
			(clearance 0.1016)
			(thermal_gap 0.1016)
		)
		(pad "A8" thru_hole circle
			(at 1.999996 6.999986 270)
			(size 1.016 1.016)
			(drill 0.7112)
			(layers "*.Cu" "*.Mask")
			(remove_unused_layers no)
			(net "GND")
			(clearance 0.1016)
			(thermal_gap 0.1016)
		)
		(pad "A9" thru_hole circle
			(at 0 7.999984 270)
			(size 1.016 1.016)
			(drill 0.7112)
			(layers "*.Cu" "*.Mask")
			(remove_unused_layers no)
			(net "POWER_SW3_PWR_CTR_12V")
			(clearance 0.1016)
			(thermal_gap 0.1016)
		)
		(pad "A10" thru_hole circle
			(at 1.999996 8.999982 270)
			(size 1.016 1.016)
			(drill 0.7112)
			(layers "*.Cu" "*.Mask")
			(remove_unused_layers no)
			(net "POWER_SW2_PWR_CTR_12V")
			(clearance 0.1016)
			(thermal_gap 0.1016)
		)
		(pad "A11" thru_hole circle
			(at 0 9.99998 270)
			(size 1.016 1.016)
			(drill 0.7112)
			(layers "*.Cu" "*.Mask")
			(remove_unused_layers no)
			(net "POWER_SW1_PWR_CTR_12V")
			(clearance 0.1016)
			(thermal_gap 0.1016)
		)
		(pad "A12" thru_hole circle
			(at 1.999996 12.999974 270)
			(size 1.016 1.016)
			(drill 0.7112)
			(layers "*.Cu" "*.Mask")
			(remove_unused_layers no)
			(net "GND36")
			(clearance 0.1016)
			(thermal_gap 0.1016)
		)
		(pad "A13" thru_hole circle
			(at 0 13.999972 270)
			(size 1.016 1.016)
			(drill 0.7112)
			(layers "*.Cu" "*.Mask")
			(remove_unused_layers no)
			(net "Net_417")
			(clearance 0.1016)
			(thermal_gap 0.1016)
		)
		(pad "A14" thru_hole circle
			(at 1.999996 14.99997 270)
			(size 1.016 1.016)
			(drill 0.7112)
			(layers "*.Cu" "*.Mask")
			(remove_unused_layers no)
			(net "Net_416")
			(clearance 0.1016)
			(thermal_gap 0.1016)
		)
		(pad "A15" thru_hole circle
			(at 0 15.999968 270)
			(size 1.016 1.016)
			(drill 0.7112)
			(layers "*.Cu" "*.Mask")
			(remove_unused_layers no)
			(net "GND37")
			(clearance 0.1016)
			(thermal_gap 0.1016)
		)
		(pad "A16" thru_hole circle
			(at 1.999996 16.999966 270)
			(size 1.016 1.016)
			(drill 0.7112)
			(layers "*.Cu" "*.Mask")
			(remove_unused_layers no)
			(net "Net_421")
			(clearance 0.1016)
			(thermal_gap 0.1016)
		)
		(pad "A17" thru_hole circle
			(at 0 17.999964 270)
			(size 1.016 1.016)
			(drill 0.7112)
			(layers "*.Cu" "*.Mask")
			(remove_unused_layers no)
			(net "GND")
			(clearance 0.1016)
			(thermal_gap 0.1016)
		)
		(pad "A18" thru_hole circle
			(at 1.999996 18.999962 270)
			(size 1.016 1.016)
			(drill 0.7112)
			(layers "*.Cu" "*.Mask")
			(remove_unused_layers no)
			(net "UART_RTS_RP6_L_N")
			(clearance 0.1016)
			(thermal_gap 0.1016)
		)
		(pad "A19" thru_hole circle
			(at 0 19.99996 270)
			(size 1.016 1.016)
			(drill 0.7112)
			(layers "*.Cu" "*.Mask")
			(remove_unused_layers no)
			(net "UART_DSR_RP6_L")
			(clearance 0.1016)
			(thermal_gap 0.1016)
		)
		(pad "A20" thru_hole circle
			(at 1.999996 20.999958 270)
			(size 1.016 1.016)
			(drill 0.7112)
			(layers "*.Cu" "*.Mask")
			(remove_unused_layers no)
			(net "UART_RX_RP6_L")
			(clearance 0.1016)
			(thermal_gap 0.1016)
		)
		(pad "A21" thru_hole circle
			(at 0 21.999956 270)
			(size 1.016 1.016)
			(drill 0.7112)
			(layers "*.Cu" "*.Mask")
			(remove_unused_layers no)
			(net "UART_TX_RP6_L")
			(clearance 0.1016)
			(thermal_gap 0.1016)
		)
		(pad "A22" thru_hole circle
			(at 1.999996 22.999954 270)
			(size 1.016 1.016)
			(drill 0.7112)
			(layers "*.Cu" "*.Mask")
			(remove_unused_layers no)
			(net "UART_DTR_RP6_L_N")
			(clearance 0.1016)
			(thermal_gap 0.1016)
		)
		(pad "A23" thru_hole circle
			(at 0 23.999952 270)
			(size 1.016 1.016)
			(drill 0.7112)
			(layers "*.Cu" "*.Mask")
			(remove_unused_layers no)
			(net "UART_CTS_RP6_L_N")
			(clearance 0.1016)
			(thermal_gap 0.1016)
		)
		(pad "A24" thru_hole circle
			(at 1.999996 24.99995 270)
			(size 1.016 1.016)
			(drill 0.7112)
			(layers "*.Cu" "*.Mask")
			(remove_unused_layers no)
			(net "UART_RI_RP6_L_N")
			(clearance 0.1016)
			(thermal_gap 0.1016)
		)
		(pad "A25" thru_hole circle
			(at 0 25.999948 270)
			(size 1.016 1.016)
			(drill 0.7112)
			(layers "*.Cu" "*.Mask")
			(remove_unused_layers no)
			(net "GND")
			(clearance 0.1016)
			(thermal_gap 0.1016)
		)
		(pad "A26" thru_hole circle
			(at 1.999996 26.999946 270)
			(size 1.016 1.016)
			(drill 0.7112)
			(layers "*.Cu" "*.Mask")
			(remove_unused_layers no)
			(net "FAN4_TACH")
			(clearance 0.1016)
			(thermal_gap 0.1016)
		)
		(pad "A27" thru_hole circle
			(at 0 27.999944 270)
			(size 1.016 1.016)
			(drill 0.7112)
			(layers "*.Cu" "*.Mask")
			(remove_unused_layers no)
			(net "FAN5_TACH")
			(clearance 0.1016)
			(thermal_gap 0.1016)
		)
		(pad "A28" thru_hole circle
			(at 1.999996 28.999942 270)
			(size 1.016 1.016)
			(drill 0.7112)
			(layers "*.Cu" "*.Mask")
			(remove_unused_layers no)
			(net "FAN6_TACH")
			(clearance 0.1016)
			(thermal_gap 0.1016)
		)
		(pad "A29" thru_hole circle
			(at 0 29.99994 270)
			(size 1.016 1.016)
			(drill 0.7112)
			(layers "*.Cu" "*.Mask")
			(remove_unused_layers no)
			(net "GND")
			(clearance 0.1016)
			(thermal_gap 0.1016)
		)
		(pad "A30" thru_hole circle
			(at 1.999996 30.999938 270)
			(size 1.016 1.016)
			(drill 0.7112)
			(layers "*.Cu" "*.Mask")
			(remove_unused_layers no)
			(net "FAN_PWM")
			(clearance 0.1016)
			(thermal_gap 0.1016)
		)
		(pad "A31" thru_hole circle
			(at 0 31.999936 270)
			(size 1.016 1.016)
			(drill 0.7112)
			(layers "*.Cu" "*.Mask")
			(remove_unused_layers no)
			(net "GND")
			(clearance 0.1016)
			(thermal_gap 0.1016)
		)
		(pad "A32" thru_hole circle
			(at 1.999996 32.999934 270)
			(size 1.016 1.016)
			(drill 0.7112)
			(layers "*.Cu" "*.Mask")
			(remove_unused_layers no)
			(net "I2C_PSU3_SCL")
			(clearance 0.1016)
			(thermal_gap 0.1016)
		)
		(pad "A33" thru_hole circle
			(at 0 33.999932 270)
			(size 1.016 1.016)
			(drill 0.7112)
			(layers "*.Cu" "*.Mask")
			(remove_unused_layers no)
			(net "I2C_PSU3_SDA")
			(clearance 0.1016)
			(thermal_gap 0.1016)
		)
		(pad "A34" thru_hole circle
			(at 1.999996 34.99993 270)
			(size 1.016 1.016)
			(drill 0.7112)
			(layers "*.Cu" "*.Mask")
			(remove_unused_layers no)
			(net "GND")
			(clearance 0.1016)
			(thermal_gap 0.1016)
		)
		(pad "A35" thru_hole circle
			(at 0 35.999928 270)
			(size 1.016 1.016)
			(drill 0.7112)
			(layers "*.Cu" "*.Mask")
			(remove_unused_layers no)
			(net "T11_BLAD1_EN")
			(clearance 0.1016)
			(thermal_gap 0.1016)
		)
		(pad "A36" thru_hole circle
			(at 1.999996 36.999926 270)
			(size 1.016 1.016)
			(drill 0.7112)
			(layers "*.Cu" "*.Mask")
			(remove_unused_layers no)
			(net "T11_BLAD2_EN")
			(clearance 0.1016)
			(thermal_gap 0.1016)
		)
		(pad "A37" thru_hole circle
			(at 0 37.999924 270)
			(size 1.016 1.016)
			(drill 0.7112)
			(layers "*.Cu" "*.Mask")
			(remove_unused_layers no)
			(net "T11_BLAD3_EN")
			(clearance 0.1016)
			(thermal_gap 0.1016)
		)
		(pad "A38" thru_hole circle
			(at 1.999996 38.999922 270)
			(size 1.016 1.016)
			(drill 0.7112)
			(layers "*.Cu" "*.Mask")
			(remove_unused_layers no)
			(net "T11_BLAD4_EN")
			(clearance 0.1016)
			(thermal_gap 0.1016)
		)
		(pad "A39" thru_hole circle
			(at 0 39.99992 270)
			(size 1.016 1.016)
			(drill 0.7112)
			(layers "*.Cu" "*.Mask")
			(remove_unused_layers no)
			(net "GND")
			(clearance 0.1016)
			(thermal_gap 0.1016)
		)
		(pad "A40" thru_hole circle
			(at 1.999996 40.999918 270)
			(size 1.016 1.016)
			(drill 0.7112)
			(layers "*.Cu" "*.Mask")
			(remove_unused_layers no)
			(net "T11_BLAD1_RXD")
			(clearance 0.1016)
			(thermal_gap 0.1016)
		)
		(pad "A41" thru_hole circle
			(at 0 41.999916 270)
			(size 1.016 1.016)
			(drill 0.7112)
			(layers "*.Cu" "*.Mask")
			(remove_unused_layers no)
			(net "T11_BLAD1_TXD")
			(clearance 0.1016)
			(thermal_gap 0.1016)
		)
		(pad "A42" thru_hole circle
			(at 1.999996 42.999914 270)
			(size 1.016 1.016)
			(drill 0.7112)
			(layers "*.Cu" "*.Mask")
			(remove_unused_layers no)
			(net "T11_BLAD2_RXD")
			(clearance 0.1016)
			(thermal_gap 0.1016)
		)
		(pad "A43" thru_hole circle
			(at 0 43.999912 270)
			(size 1.016 1.016)
			(drill 0.7112)
			(layers "*.Cu" "*.Mask")
			(remove_unused_layers no)
			(net "T11_BLAD2_TXD")
			(clearance 0.1016)
			(thermal_gap 0.1016)
		)
		(pad "A44" thru_hole circle
			(at 1.999996 44.99991 270)
			(size 1.016 1.016)
			(drill 0.7112)
			(layers "*.Cu" "*.Mask")
			(remove_unused_layers no)
			(net "GND")
			(clearance 0.1016)
			(thermal_gap 0.1016)
		)
		(pad "A45" thru_hole circle
			(at 0 45.999908 270)
			(size 1.016 1.016)
			(drill 0.7112)
			(layers "*.Cu" "*.Mask")
			(remove_unused_layers no)
			(net "T11_BLAD3_RXD")
			(clearance 0.1016)
			(thermal_gap 0.1016)
		)
		(pad "A46" thru_hole circle
			(at 1.999996 46.999906 270)
			(size 1.016 1.016)
			(drill 0.7112)
			(layers "*.Cu" "*.Mask")
			(remove_unused_layers no)
			(net "T11_BLAD3_TXD")
			(clearance 0.1016)
			(thermal_gap 0.1016)
		)
		(pad "A47" thru_hole circle
			(at 0 47.999904 270)
			(size 1.016 1.016)
			(drill 0.7112)
			(layers "*.Cu" "*.Mask")
			(remove_unused_layers no)
			(net "T11_BLAD4_RXD")
			(clearance 0.1016)
			(thermal_gap 0.1016)
		)
		(pad "A48" thru_hole circle
			(at 1.999996 48.999902 270)
			(size 1.016 1.016)
			(drill 0.7112)
			(layers "*.Cu" "*.Mask")
			(remove_unused_layers no)
			(net "T11_BLAD4_TXD")
			(clearance 0.1016)
			(thermal_gap 0.1016)
		)
		(pad "A49" thru_hole circle
			(at 0 49.9999 270)
			(size 1.016 1.016)
			(drill 0.7112)
			(layers "*.Cu" "*.Mask")
			(remove_unused_layers no)
			(net "GND")
			(clearance 0.1016)
			(thermal_gap 0.1016)
		)
		(pad "A50" thru_hole circle
			(at 1.999996 50.999898 270)
			(size 1.016 1.016)
			(drill 0.7112)
			(layers "*.Cu" "*.Mask")
			(remove_unused_layers no)
			(net "T9_BLAD1_EN")
			(clearance 0.1016)
			(thermal_gap 0.1016)
		)
		(pad "A51" thru_hole circle
			(at 0 51.999896 270)
			(size 1.016 1.016)
			(drill 0.7112)
			(layers "*.Cu" "*.Mask")
			(remove_unused_layers no)
			(net "T9_BLAD2_EN")
			(clearance 0.1016)
			(thermal_gap 0.1016)
		)
		(pad "A52" thru_hole circle
			(at 1.999996 52.999894 270)
			(size 1.016 1.016)
			(drill 0.7112)
			(layers "*.Cu" "*.Mask")
			(remove_unused_layers no)
			(net "T9_BLAD3_EN")
			(clearance 0.1016)
			(thermal_gap 0.1016)
		)
		(pad "A53" thru_hole circle
			(at 0 53.999892 270)
			(size 1.016 1.016)
			(drill 0.7112)
			(layers "*.Cu" "*.Mask")
			(remove_unused_layers no)
			(net "T9_BLAD4_EN")
			(clearance 0.1016)
			(thermal_gap 0.1016)
		)
		(pad "A54" thru_hole circle
			(at 1.999996 54.99989 270)
			(size 1.016 1.016)
			(drill 0.7112)
			(layers "*.Cu" "*.Mask")
			(remove_unused_layers no)
			(net "GND")
			(clearance 0.1016)
			(thermal_gap 0.1016)
		)
		(pad "A55" thru_hole circle
			(at 0 55.999888 270)
			(size 1.016 1.016)
			(drill 0.7112)
			(layers "*.Cu" "*.Mask")
			(remove_unused_layers no)
			(net "T9_BLAD1_RXD")
			(clearance 0.1016)
			(thermal_gap 0.1016)
		)
		(pad "A56" thru_hole circle
			(at 1.999996 56.999886 270)
			(size 1.016 1.016)
			(drill 0.7112)
			(layers "*.Cu" "*.Mask")
			(remove_unused_layers no)
			(net "T9_BLAD1_TXD")
			(clearance 0.1016)
			(thermal_gap 0.1016)
		)
		(pad "A57" thru_hole circle
			(at 0 57.999884 270)
			(size 1.016 1.016)
			(drill 0.7112)
			(layers "*.Cu" "*.Mask")
			(remove_unused_layers no)
			(net "T9_BLAD2_RXD")
			(clearance 0.1016)
			(thermal_gap 0.1016)
		)
		(pad "A58" thru_hole circle
			(at 1.999996 59.000136 270)
			(size 1.016 1.016)
			(drill 0.7112)
			(layers "*.Cu" "*.Mask")
			(remove_unused_layers no)
			(net "T9_BLAD2_TXD")
			(clearance 0.1016)
			(thermal_gap 0.1016)
		)
		(pad "A59" thru_hole circle
			(at 0 59.99988 270)
			(size 1.016 1.016)
			(drill 0.7112)
			(layers "*.Cu" "*.Mask")
			(remove_unused_layers no)
			(net "GND")
			(clearance 0.1016)
			(thermal_gap 0.1016)
		)
		(pad "A60" thru_hole circle
			(at 1.999996 61.000132 270)
			(size 1.016 1.016)
			(drill 0.7112)
			(layers "*.Cu" "*.Mask")
			(remove_unused_layers no)
			(net "T9_BLAD3_RXD")
			(clearance 0.1016)
			(thermal_gap 0.1016)
		)
		(pad "A61" thru_hole circle
			(at 0 61.999876 270)
			(size 1.016 1.016)
			(drill 0.7112)
			(layers "*.Cu" "*.Mask")
			(remove_unused_layers no)
			(net "T9_BLAD3_TXD")
			(clearance 0.1016)
			(thermal_gap 0.1016)
		)
		(pad "A62" thru_hole circle
			(at 1.999996 63.000128 270)
			(size 1.016 1.016)
			(drill 0.7112)
			(layers "*.Cu" "*.Mask")
			(remove_unused_layers no)
			(net "T9_BLAD4_RXD")
			(clearance 0.1016)
			(thermal_gap 0.1016)
		)
		(pad "A63" thru_hole circle
			(at 0 63.999872 270)
			(size 1.016 1.016)
			(drill 0.7112)
			(layers "*.Cu" "*.Mask")
			(remove_unused_layers no)
			(net "T9_BLAD4_TXD")
			(clearance 0.1016)
			(thermal_gap 0.1016)
		)
		(pad "A64" thru_hole circle
			(at 1.999996 65.000124 270)
			(size 1.016 1.016)
			(drill 0.7112)
			(layers "*.Cu" "*.Mask")
			(remove_unused_layers no)
			(net "GND")
			(clearance 0.1016)
			(thermal_gap 0.1016)
		)
		(pad "A65" thru_hole circle
			(at 0 65.999868 270)
			(size 1.016 1.016)
			(drill 0.7112)
			(layers "*.Cu" "*.Mask")
			(remove_unused_layers no)
			(net "T7_BLAD1_EN")
			(clearance 0.1016)
			(thermal_gap 0.1016)
		)
		(pad "A66" thru_hole circle
			(at 1.999996 67.00012 270)
			(size 1.016 1.016)
			(drill 0.7112)
			(layers "*.Cu" "*.Mask")
			(remove_unused_layers no)
			(net "T7_BLAD2_EN")
			(clearance 0.1016)
			(thermal_gap 0.1016)
		)
		(pad "A67" thru_hole circle
			(at 0 67.999864 270)
			(size 1.016 1.016)
			(drill 0.7112)
			(layers "*.Cu" "*.Mask")
			(remove_unused_layers no)
			(net "T7_BLAD3_EN")
			(clearance 0.1016)
			(thermal_gap 0.1016)
		)
		(pad "A68" thru_hole circle
			(at 1.999996 69.000116 270)
			(size 1.016 1.016)
			(drill 0.7112)
			(layers "*.Cu" "*.Mask")
			(remove_unused_layers no)
			(net "T7_BLAD4_EN")
			(clearance 0.1016)
			(thermal_gap 0.1016)
		)
		(pad "A69" thru_hole circle
			(at 0 70.000114 270)
			(size 1.016 1.016)
			(drill 0.7112)
			(layers "*.Cu" "*.Mask")
			(remove_unused_layers no)
			(net "GND")
			(clearance 0.1016)
			(thermal_gap 0.1016)
		)
		(pad "A70" thru_hole circle
			(at 1.999996 71.000112 270)
			(size 1.016 1.016)
			(drill 0.7112)
			(layers "*.Cu" "*.Mask")
			(remove_unused_layers no)
			(net "T7_BLAD1_RXD")
			(clearance 0.1016)
			(thermal_gap 0.1016)
		)
		(pad "A71" thru_hole circle
			(at 0 72.00011 270)
			(size 1.016 1.016)
			(drill 0.7112)
			(layers "*.Cu" "*.Mask")
			(remove_unused_layers no)
			(net "T7_BLAD1_TXD")
			(clearance 0.1016)
			(thermal_gap 0.1016)
		)
		(pad "A72" thru_hole circle
			(at 1.999996 73.000108 270)
			(size 1.016 1.016)
			(drill 0.7112)
			(layers "*.Cu" "*.Mask")
			(remove_unused_layers no)
			(net "T7_BLAD2_RXD")
			(clearance 0.1016)
			(thermal_gap 0.1016)
		)
		(pad "A73" thru_hole circle
			(at 0 74.000106 270)
			(size 1.016 1.016)
			(drill 0.7112)
			(layers "*.Cu" "*.Mask")
			(remove_unused_layers no)
			(net "T7_BLAD2_TXD")
			(clearance 0.1016)
			(thermal_gap 0.1016)
		)
		(pad "A74" thru_hole circle
			(at 1.999996 75.000104 270)
			(size 1.016 1.016)
			(drill 0.7112)
			(layers "*.Cu" "*.Mask")
			(remove_unused_layers no)
			(net "GND")
			(clearance 0.1016)
			(thermal_gap 0.1016)
		)
		(pad "A75" thru_hole circle
			(at 0 76.000102 270)
			(size 1.016 1.016)
			(drill 0.7112)
			(layers "*.Cu" "*.Mask")
			(remove_unused_layers no)
			(net "T7_BLAD3_RXD")
			(clearance 0.1016)
			(thermal_gap 0.1016)
		)
		(pad "A76" thru_hole circle
			(at 1.999996 77.0001 270)
			(size 1.016 1.016)
			(drill 0.7112)
			(layers "*.Cu" "*.Mask")
			(remove_unused_layers no)
			(net "T7_BLAD3_TXD")
			(clearance 0.1016)
			(thermal_gap 0.1016)
		)
		(pad "A77" thru_hole circle
			(at 0 78.000098 270)
			(size 1.016 1.016)
			(drill 0.7112)
			(layers "*.Cu" "*.Mask")
			(remove_unused_layers no)
			(net "T7_BLAD4_RXD")
			(clearance 0.1016)
			(thermal_gap 0.1016)
		)
		(pad "A78" thru_hole circle
			(at 1.999996 79.000096 270)
			(size 1.016 1.016)
			(drill 0.7112)
			(layers "*.Cu" "*.Mask")
			(remove_unused_layers no)
			(net "T7_BLAD4_TXD")
			(clearance 0.1016)
			(thermal_gap 0.1016)
		)
		(pad "A79" thru_hole circle
			(at 0 80.000094 270)
			(size 1.016 1.016)
			(drill 0.7112)
			(layers "*.Cu" "*.Mask")
			(remove_unused_layers no)
			(net "GND")
			(clearance 0.1016)
			(thermal_gap 0.1016)
		)
		(pad "A80" thru_hole circle
			(at 1.999996 81.000092 270)
			(size 1.016 1.016)
			(drill 0.7112)
			(layers "*.Cu" "*.Mask")
			(remove_unused_layers no)
			(net "PSU_ALERT_N")
			(clearance 0.1016)
			(thermal_gap 0.1016)
		)
		(pad "A81" thru_hole circle
			(at 0 82.00009 270)
			(size 1.016 1.016)
			(drill 0.7112)
			(layers "*.Cu" "*.Mask")
			(remove_unused_layers no)
			(net "T5_BLAD1_EN")
			(clearance 0.1016)
			(thermal_gap 0.1016)
		)
		(pad "A82" thru_hole circle
			(at 1.999996 83.000088 270)
			(size 1.016 1.016)
			(drill 0.7112)
			(layers "*.Cu" "*.Mask")
			(remove_unused_layers no)
			(net "T5_BLAD2_EN")
			(clearance 0.1016)
			(thermal_gap 0.1016)
		)
		(pad "B1" thru_hole circle
			(at -2.499868 0 270)
			(size 1.016 1.016)
			(drill 0.7112)
			(layers "*.Cu" "*.Mask")
			(remove_unused_layers no)
			(net "GND")
			(clearance 0.1016)
			(thermal_gap 0.1016)
		)
		(pad "B2" thru_hole circle
			(at -4.499864 0.999998 270)
			(size 1.016 1.016)
			(drill 0.7112)
			(layers "*.Cu" "*.Mask")
			(remove_unused_layers no)
			(net "LAN2_P1_P")
			(clearance 0.1016)
			(thermal_gap 0.1016)
		)
		(pad "B3" thru_hole circle
			(at -2.499868 1.999996 270)
			(size 1.016 1.016)
			(drill 0.7112)
			(layers "*.Cu" "*.Mask")
			(remove_unused_layers no)
			(net "LAN2_P1_N")
			(clearance 0.1016)
			(thermal_gap 0.1016)
		)
		(pad "B4" thru_hole circle
			(at -4.499864 2.999994 270)
			(size 1.016 1.016)
			(drill 0.7112)
			(layers "*.Cu" "*.Mask")
			(remove_unused_layers no)
			(net "GND")
			(clearance 0.1016)
			(thermal_gap 0.1016)
		)
		(pad "B5" thru_hole circle
			(at -2.499868 3.999992 270)
			(size 1.016 1.016)
			(drill 0.7112)
			(layers "*.Cu" "*.Mask")
			(remove_unused_layers no)
			(net "LAN2_P2_P")
			(clearance 0.1016)
			(thermal_gap 0.1016)
		)
		(pad "B6" thru_hole circle
			(at -4.499864 4.99999 270)
			(size 1.016 1.016)
			(drill 0.7112)
			(layers "*.Cu" "*.Mask")
			(remove_unused_layers no)
			(net "LAN2_P2_N")
			(clearance 0.1016)
			(thermal_gap 0.1016)
		)
		(pad "B7" thru_hole circle
			(at -2.499868 5.999988 270)
			(size 1.016 1.016)
			(drill 0.7112)
			(layers "*.Cu" "*.Mask")
			(remove_unused_layers no)
			(net "GND")
			(clearance 0.1016)
			(thermal_gap 0.1016)
		)
		(pad "B8" thru_hole circle
			(at -4.499864 6.999986 270)
			(size 1.016 1.016)
			(drill 0.7112)
			(layers "*.Cu" "*.Mask")
			(remove_unused_layers no)
			(net "GND")
			(clearance 0.1016)
			(thermal_gap 0.1016)
		)
		(pad "B9" thru_hole circle
			(at -2.499868 7.999984 270)
			(size 1.016 1.016)
			(drill 0.7112)
			(layers "*.Cu" "*.Mask")
			(remove_unused_layers no)
			(net "GND")
			(clearance 0.1016)
			(thermal_gap 0.1016)
		)
		(pad "B10" thru_hole circle
			(at -4.499864 8.999982 270)
			(size 1.016 1.016)
			(drill 0.7112)
			(layers "*.Cu" "*.Mask")
			(remove_unused_layers no)
			(net "I2C_PDB_SCL")
			(clearance 0.1016)
			(thermal_gap 0.1016)
		)
		(pad "B11" thru_hole circle
			(at -2.499868 9.99998 270)
			(size 1.016 1.016)
			(drill 0.7112)
			(layers "*.Cu" "*.Mask")
			(remove_unused_layers no)
			(net "I2C_PDB_SDA")
			(clearance 0.1016)
			(thermal_gap 0.1016)
		)
		(pad "B12" thru_hole circle
			(at -4.499864 12.999974 270)
			(size 1.016 1.016)
			(drill 0.7112)
			(layers "*.Cu" "*.Mask")
			(remove_unused_layers no)
			(net "P3V3")
			(clearance 0.1016)
			(thermal_gap 0.1016)
		)
		(pad "B13" thru_hole circle
			(at -2.499868 13.999972 270)
			(size 1.016 1.016)
			(drill 0.7112)
			(layers "*.Cu" "*.Mask")
			(remove_unused_layers no)
			(net "GND3")
			(clearance 0.1016)
			(thermal_gap 0.1016)
		)
		(pad "B14" thru_hole circle
			(at -4.499864 14.99997 270)
			(size 1.016 1.016)
			(drill 0.7112)
			(layers "*.Cu" "*.Mask")
			(remove_unused_layers no)
			(net "Net_420")
			(clearance 0.1016)
			(thermal_gap 0.1016)
		)
		(pad "B15" thru_hole circle
			(at -2.499868 15.999968 270)
			(size 1.016 1.016)
			(drill 0.7112)
			(layers "*.Cu" "*.Mask")
			(remove_unused_layers no)
			(net "Net_419")
			(clearance 0.1016)
			(thermal_gap 0.1016)
		)
		(pad "B16" thru_hole circle
			(at -4.499864 16.999966 270)
			(size 1.016 1.016)
			(drill 0.7112)
			(layers "*.Cu" "*.Mask")
			(remove_unused_layers no)
			(net "GND4")
			(clearance 0.1016)
			(thermal_gap 0.1016)
		)
		(pad "B17" thru_hole circle
			(at -2.499868 17.999964 270)
			(size 1.016 1.016)
			(drill 0.7112)
			(layers "*.Cu" "*.Mask")
			(remove_unused_layers no)
			(net "Net_418")
			(clearance 0.1016)
			(thermal_gap 0.1016)
		)
		(pad "B18" thru_hole circle
			(at -4.499864 18.999962 270)
			(size 1.016 1.016)
			(drill 0.7112)
			(layers "*.Cu" "*.Mask")
			(remove_unused_layers no)
			(net "GND")
			(clearance 0.1016)
			(thermal_gap 0.1016)
		)
		(pad "B19" thru_hole circle
			(at -2.499868 19.99996 270)
			(size 1.016 1.016)
			(drill 0.7112)
			(layers "*.Cu" "*.Mask")
			(remove_unused_layers no)
			(net "UART_RTS_RP5_L_N")
			(clearance 0.1016)
			(thermal_gap 0.1016)
		)
		(pad "B20" thru_hole circle
			(at -4.499864 20.999958 270)
			(size 1.016 1.016)
			(drill 0.7112)
			(layers "*.Cu" "*.Mask")
			(remove_unused_layers no)
			(net "UART_DSR_RP5_L")
			(clearance 0.1016)
			(thermal_gap 0.1016)
		)
		(pad "B21" thru_hole circle
			(at -2.499868 21.999956 270)
			(size 1.016 1.016)
			(drill 0.7112)
			(layers "*.Cu" "*.Mask")
			(remove_unused_layers no)
			(net "UART_RX_RP5_L")
			(clearance 0.1016)
			(thermal_gap 0.1016)
		)
		(pad "B22" thru_hole circle
			(at -4.499864 22.999954 270)
			(size 1.016 1.016)
			(drill 0.7112)
			(layers "*.Cu" "*.Mask")
			(remove_unused_layers no)
			(net "UART_TX_RP5_L")
			(clearance 0.1016)
			(thermal_gap 0.1016)
		)
		(pad "B23" thru_hole circle
			(at -2.499868 23.999952 270)
			(size 1.016 1.016)
			(drill 0.7112)
			(layers "*.Cu" "*.Mask")
			(remove_unused_layers no)
			(net "UART_DTR_RP5_L_N")
			(clearance 0.1016)
			(thermal_gap 0.1016)
		)
		(pad "B24" thru_hole circle
			(at -4.499864 24.99995 270)
			(size 1.016 1.016)
			(drill 0.7112)
			(layers "*.Cu" "*.Mask")
			(remove_unused_layers no)
			(net "UART_CTS_RP5_L_N")
			(clearance 0.1016)
			(thermal_gap 0.1016)
		)
		(pad "B25" thru_hole circle
			(at -2.499868 25.999948 270)
			(size 1.016 1.016)
			(drill 0.7112)
			(layers "*.Cu" "*.Mask")
			(remove_unused_layers no)
			(net "UART_RI_RP5_L_N")
			(clearance 0.1016)
			(thermal_gap 0.1016)
		)
		(pad "B26" thru_hole circle
			(at -4.499864 26.999946 270)
			(size 1.016 1.016)
			(drill 0.7112)
			(layers "*.Cu" "*.Mask")
			(remove_unused_layers no)
			(net "GND")
			(clearance 0.1016)
			(thermal_gap 0.1016)
		)
		(pad "B27" thru_hole circle
			(at -2.499868 27.999944 270)
			(size 1.016 1.016)
			(drill 0.7112)
			(layers "*.Cu" "*.Mask")
			(remove_unused_layers no)
			(net "FAN1_TACH")
			(clearance 0.1016)
			(thermal_gap 0.1016)
		)
		(pad "B28" thru_hole circle
			(at -4.499864 28.999942 270)
			(size 1.016 1.016)
			(drill 0.7112)
			(layers "*.Cu" "*.Mask")
			(remove_unused_layers no)
			(net "FAN2_TACH")
			(clearance 0.1016)
			(thermal_gap 0.1016)
		)
		(pad "B29" thru_hole circle
			(at -2.499868 29.99994 270)
			(size 1.016 1.016)
			(drill 0.7112)
			(layers "*.Cu" "*.Mask")
			(remove_unused_layers no)
			(net "FAN3_TACH")
			(clearance 0.1016)
			(thermal_gap 0.1016)
		)
		(pad "B30" thru_hole circle
			(at -4.499864 30.999938 270)
			(size 1.016 1.016)
			(drill 0.7112)
			(layers "*.Cu" "*.Mask")
			(remove_unused_layers no)
			(net "GND")
			(clearance 0.1016)
			(thermal_gap 0.1016)
		)
		(pad "B31" thru_hole circle
			(at -2.499868 31.999936 270)
			(size 1.016 1.016)
			(drill 0.7112)
			(layers "*.Cu" "*.Mask")
			(remove_unused_layers no)
			(net "T12_BLAD1_EN")
			(clearance 0.1016)
			(thermal_gap 0.1016)
		)
		(pad "B32" thru_hole circle
			(at -4.499864 32.999934 270)
			(size 1.016 1.016)
			(drill 0.7112)
			(layers "*.Cu" "*.Mask")
			(remove_unused_layers no)
			(net "T12_BLAD2_EN")
			(clearance 0.1016)
			(thermal_gap 0.1016)
		)
		(pad "B33" thru_hole circle
			(at -2.499868 33.999932 270)
			(size 1.016 1.016)
			(drill 0.7112)
			(layers "*.Cu" "*.Mask")
			(remove_unused_layers no)
			(net "T12_BLAD3_EN")
			(clearance 0.1016)
			(thermal_gap 0.1016)
		)
		(pad "B34" thru_hole circle
			(at -4.499864 34.99993 270)
			(size 1.016 1.016)
			(drill 0.7112)
			(layers "*.Cu" "*.Mask")
			(remove_unused_layers no)
			(net "T12_BLAD4_EN")
			(clearance 0.1016)
			(thermal_gap 0.1016)
		)
		(pad "B35" thru_hole circle
			(at -2.499868 35.999928 270)
			(size 1.016 1.016)
			(drill 0.7112)
			(layers "*.Cu" "*.Mask")
			(remove_unused_layers no)
			(net "GND")
			(clearance 0.1016)
			(thermal_gap 0.1016)
		)
		(pad "B36" thru_hole circle
			(at -4.499864 36.999926 270)
			(size 1.016 1.016)
			(drill 0.7112)
			(layers "*.Cu" "*.Mask")
			(remove_unused_layers no)
			(net "T12_BLAD1_RXD")
			(clearance 0.1016)
			(thermal_gap 0.1016)
		)
		(pad "B37" thru_hole circle
			(at -2.499868 37.999924 270)
			(size 1.016 1.016)
			(drill 0.7112)
			(layers "*.Cu" "*.Mask")
			(remove_unused_layers no)
			(net "T12_BLAD1_TXD")
			(clearance 0.1016)
			(thermal_gap 0.1016)
		)
		(pad "B38" thru_hole circle
			(at -4.499864 38.999922 270)
			(size 1.016 1.016)
			(drill 0.7112)
			(layers "*.Cu" "*.Mask")
			(remove_unused_layers no)
			(net "T12_BLAD2_RXD")
			(clearance 0.1016)
			(thermal_gap 0.1016)
		)
		(pad "B39" thru_hole circle
			(at -2.499868 39.99992 270)
			(size 1.016 1.016)
			(drill 0.7112)
			(layers "*.Cu" "*.Mask")
			(remove_unused_layers no)
			(net "T12_BLAD2_TXD")
			(clearance 0.1016)
			(thermal_gap 0.1016)
		)
		(pad "B40" thru_hole circle
			(at -4.499864 40.999918 270)
			(size 1.016 1.016)
			(drill 0.7112)
			(layers "*.Cu" "*.Mask")
			(remove_unused_layers no)
			(net "GND")
			(clearance 0.1016)
			(thermal_gap 0.1016)
		)
		(pad "B41" thru_hole circle
			(at -2.499868 41.999916 270)
			(size 1.016 1.016)
			(drill 0.7112)
			(layers "*.Cu" "*.Mask")
			(remove_unused_layers no)
			(net "T12_BLAD3_RXD")
			(clearance 0.1016)
			(thermal_gap 0.1016)
		)
		(pad "B42" thru_hole circle
			(at -4.499864 42.999914 270)
			(size 1.016 1.016)
			(drill 0.7112)
			(layers "*.Cu" "*.Mask")
			(remove_unused_layers no)
			(net "T12_BLAD3_TXD")
			(clearance 0.1016)
			(thermal_gap 0.1016)
		)
		(pad "B43" thru_hole circle
			(at -2.499868 43.999912 270)
			(size 1.016 1.016)
			(drill 0.7112)
			(layers "*.Cu" "*.Mask")
			(remove_unused_layers no)
			(net "T12_BLAD4_RXD")
			(clearance 0.1016)
			(thermal_gap 0.1016)
		)
		(pad "B44" thru_hole circle
			(at -4.499864 44.99991 270)
			(size 1.016 1.016)
			(drill 0.7112)
			(layers "*.Cu" "*.Mask")
			(remove_unused_layers no)
			(net "T12_BLAD4_TXD")
			(clearance 0.1016)
			(thermal_gap 0.1016)
		)
		(pad "B45" thru_hole circle
			(at -2.499868 45.999908 270)
			(size 1.016 1.016)
			(drill 0.7112)
			(layers "*.Cu" "*.Mask")
			(remove_unused_layers no)
			(net "GND")
			(clearance 0.1016)
			(thermal_gap 0.1016)
		)
		(pad "B46" thru_hole circle
			(at -4.499864 46.999906 270)
			(size 1.016 1.016)
			(drill 0.7112)
			(layers "*.Cu" "*.Mask")
			(remove_unused_layers no)
			(net "T10_BLAD1_EN")
			(clearance 0.1016)
			(thermal_gap 0.1016)
		)
		(pad "B47" thru_hole circle
			(at -2.499868 47.999904 270)
			(size 1.016 1.016)
			(drill 0.7112)
			(layers "*.Cu" "*.Mask")
			(remove_unused_layers no)
			(net "T10_BLAD2_EN")
			(clearance 0.1016)
			(thermal_gap 0.1016)
		)
		(pad "B48" thru_hole circle
			(at -4.499864 48.999902 270)
			(size 1.016 1.016)
			(drill 0.7112)
			(layers "*.Cu" "*.Mask")
			(remove_unused_layers no)
			(net "T10_BLAD3_EN")
			(clearance 0.1016)
			(thermal_gap 0.1016)
		)
		(pad "B49" thru_hole circle
			(at -2.499868 49.9999 270)
			(size 1.016 1.016)
			(drill 0.7112)
			(layers "*.Cu" "*.Mask")
			(remove_unused_layers no)
			(net "T10_BLAD4_EN")
			(clearance 0.1016)
			(thermal_gap 0.1016)
		)
		(pad "B50" thru_hole circle
			(at -4.499864 50.999898 270)
			(size 1.016 1.016)
			(drill 0.7112)
			(layers "*.Cu" "*.Mask")
			(remove_unused_layers no)
			(net "GND")
			(clearance 0.1016)
			(thermal_gap 0.1016)
		)
		(pad "B51" thru_hole circle
			(at -2.499868 51.999896 270)
			(size 1.016 1.016)
			(drill 0.7112)
			(layers "*.Cu" "*.Mask")
			(remove_unused_layers no)
			(net "T10_BLAD1_RXD")
			(clearance 0.1016)
			(thermal_gap 0.1016)
		)
		(pad "B52" thru_hole circle
			(at -4.499864 52.999894 270)
			(size 1.016 1.016)
			(drill 0.7112)
			(layers "*.Cu" "*.Mask")
			(remove_unused_layers no)
			(net "T10_BLAD1_TXD")
			(clearance 0.1016)
			(thermal_gap 0.1016)
		)
		(pad "B53" thru_hole circle
			(at -2.499868 53.999892 270)
			(size 1.016 1.016)
			(drill 0.7112)
			(layers "*.Cu" "*.Mask")
			(remove_unused_layers no)
			(net "T10_BLAD2_RXD")
			(clearance 0.1016)
			(thermal_gap 0.1016)
		)
		(pad "B54" thru_hole circle
			(at -4.499864 54.99989 270)
			(size 1.016 1.016)
			(drill 0.7112)
			(layers "*.Cu" "*.Mask")
			(remove_unused_layers no)
			(net "T10_BLAD2_TXD")
			(clearance 0.1016)
			(thermal_gap 0.1016)
		)
		(pad "B55" thru_hole circle
			(at -2.499868 55.999888 270)
			(size 1.016 1.016)
			(drill 0.7112)
			(layers "*.Cu" "*.Mask")
			(remove_unused_layers no)
			(net "GND")
			(clearance 0.1016)
			(thermal_gap 0.1016)
		)
		(pad "B56" thru_hole circle
			(at -4.499864 56.999886 270)
			(size 1.016 1.016)
			(drill 0.7112)
			(layers "*.Cu" "*.Mask")
			(remove_unused_layers no)
			(net "T10_BLAD3_RXD")
			(clearance 0.1016)
			(thermal_gap 0.1016)
		)
		(pad "B57" thru_hole circle
			(at -2.499868 57.999884 270)
			(size 1.016 1.016)
			(drill 0.7112)
			(layers "*.Cu" "*.Mask")
			(remove_unused_layers no)
			(net "T10_BLAD3_TXD")
			(clearance 0.1016)
			(thermal_gap 0.1016)
		)
		(pad "B58" thru_hole circle
			(at -4.499864 59.000136 270)
			(size 1.016 1.016)
			(drill 0.7112)
			(layers "*.Cu" "*.Mask")
			(remove_unused_layers no)
			(net "T10_BLAD4_RXD")
			(clearance 0.1016)
			(thermal_gap 0.1016)
		)
		(pad "B59" thru_hole circle
			(at -2.499868 59.99988 270)
			(size 1.016 1.016)
			(drill 0.7112)
			(layers "*.Cu" "*.Mask")
			(remove_unused_layers no)
			(net "T10_BLAD4_TXD")
			(clearance 0.1016)
			(thermal_gap 0.1016)
		)
		(pad "B60" thru_hole circle
			(at -4.499864 61.000132 270)
			(size 1.016 1.016)
			(drill 0.7112)
			(layers "*.Cu" "*.Mask")
			(remove_unused_layers no)
			(net "GND")
			(clearance 0.1016)
			(thermal_gap 0.1016)
		)
		(pad "B61" thru_hole circle
			(at -2.499868 61.999876 270)
			(size 1.016 1.016)
			(drill 0.7112)
			(layers "*.Cu" "*.Mask")
			(remove_unused_layers no)
			(net "T8_BLAD1_EN")
			(clearance 0.1016)
			(thermal_gap 0.1016)
		)
		(pad "B62" thru_hole circle
			(at -4.499864 63.000128 270)
			(size 1.016 1.016)
			(drill 0.7112)
			(layers "*.Cu" "*.Mask")
			(remove_unused_layers no)
			(net "T8_BLAD2_EN")
			(clearance 0.1016)
			(thermal_gap 0.1016)
		)
		(pad "B63" thru_hole circle
			(at -2.499868 63.999872 270)
			(size 1.016 1.016)
			(drill 0.7112)
			(layers "*.Cu" "*.Mask")
			(remove_unused_layers no)
			(net "T8_BLAD3_EN")
			(clearance 0.1016)
			(thermal_gap 0.1016)
		)
		(pad "B64" thru_hole circle
			(at -4.499864 65.000124 270)
			(size 1.016 1.016)
			(drill 0.7112)
			(layers "*.Cu" "*.Mask")
			(remove_unused_layers no)
			(net "T8_BLAD4_EN")
			(clearance 0.1016)
			(thermal_gap 0.1016)
		)
		(pad "B65" thru_hole circle
			(at -2.499868 65.999868 270)
			(size 1.016 1.016)
			(drill 0.7112)
			(layers "*.Cu" "*.Mask")
			(remove_unused_layers no)
			(net "GND")
			(clearance 0.1016)
			(thermal_gap 0.1016)
		)
		(pad "B66" thru_hole circle
			(at -4.499864 67.00012 270)
			(size 1.016 1.016)
			(drill 0.7112)
			(layers "*.Cu" "*.Mask")
			(remove_unused_layers no)
			(net "T8_BLAD1_RXD")
			(clearance 0.1016)
			(thermal_gap 0.1016)
		)
		(pad "B67" thru_hole circle
			(at -2.499868 67.999864 270)
			(size 1.016 1.016)
			(drill 0.7112)
			(layers "*.Cu" "*.Mask")
			(remove_unused_layers no)
			(net "T8_BLAD1_TXD")
			(clearance 0.1016)
			(thermal_gap 0.1016)
		)
		(pad "B68" thru_hole circle
			(at -4.499864 69.000116 270)
			(size 1.016 1.016)
			(drill 0.7112)
			(layers "*.Cu" "*.Mask")
			(remove_unused_layers no)
			(net "T8_BLAD2_RXD")
			(clearance 0.1016)
			(thermal_gap 0.1016)
		)
		(pad "B69" thru_hole circle
			(at -2.499868 70.000114 270)
			(size 1.016 1.016)
			(drill 0.7112)
			(layers "*.Cu" "*.Mask")
			(remove_unused_layers no)
			(net "T8_BLAD2_TXD")
			(clearance 0.1016)
			(thermal_gap 0.1016)
		)
		(pad "B70" thru_hole circle
			(at -4.499864 71.000112 270)
			(size 1.016 1.016)
			(drill 0.7112)
			(layers "*.Cu" "*.Mask")
			(remove_unused_layers no)
			(net "GND")
			(clearance 0.1016)
			(thermal_gap 0.1016)
		)
		(pad "B71" thru_hole circle
			(at -2.499868 72.00011 270)
			(size 1.016 1.016)
			(drill 0.7112)
			(layers "*.Cu" "*.Mask")
			(remove_unused_layers no)
			(net "T8_BLAD3_RXD")
			(clearance 0.1016)
			(thermal_gap 0.1016)
		)
		(pad "B72" thru_hole circle
			(at -4.499864 73.000108 270)
			(size 1.016 1.016)
			(drill 0.7112)
			(layers "*.Cu" "*.Mask")
			(remove_unused_layers no)
			(net "T8_BLAD3_TXD")
			(clearance 0.1016)
			(thermal_gap 0.1016)
		)
		(pad "B73" thru_hole circle
			(at -2.499868 74.000106 270)
			(size 1.016 1.016)
			(drill 0.7112)
			(layers "*.Cu" "*.Mask")
			(remove_unused_layers no)
			(net "T8_BLAD4_RXD")
			(clearance 0.1016)
			(thermal_gap 0.1016)
		)
		(pad "B74" thru_hole circle
			(at -4.499864 75.000104 270)
			(size 1.016 1.016)
			(drill 0.7112)
			(layers "*.Cu" "*.Mask")
			(remove_unused_layers no)
			(net "T8_BLAD4_TXD")
			(clearance 0.1016)
			(thermal_gap 0.1016)
		)
		(pad "B75" thru_hole circle
			(at -2.499868 76.000102 270)
			(size 1.016 1.016)
			(drill 0.7112)
			(layers "*.Cu" "*.Mask")
			(remove_unused_layers no)
			(net "GND")
			(clearance 0.1016)
			(thermal_gap 0.1016)
		)
		(pad "B76" thru_hole circle
			(at -4.499864 77.0001 270)
			(size 1.016 1.016)
			(drill 0.7112)
			(layers "*.Cu" "*.Mask")
			(remove_unused_layers no)
			(net "T6_BLAD1_EN")
			(clearance 0.1016)
			(thermal_gap 0.1016)
		)
		(pad "B77" thru_hole circle
			(at -2.499868 78.000098 270)
			(size 1.016 1.016)
			(drill 0.7112)
			(layers "*.Cu" "*.Mask")
			(remove_unused_layers no)
			(net "T6_BLAD2_EN")
			(clearance 0.1016)
			(thermal_gap 0.1016)
		)
		(pad "B78" thru_hole circle
			(at -4.499864 79.000096 270)
			(size 1.016 1.016)
			(drill 0.7112)
			(layers "*.Cu" "*.Mask")
			(remove_unused_layers no)
			(net "T6_BLAD3_EN")
			(clearance 0.1016)
			(thermal_gap 0.1016)
		)
		(pad "B79" thru_hole circle
			(at -2.499868 80.000094 270)
			(size 1.016 1.016)
			(drill 0.7112)
			(layers "*.Cu" "*.Mask")
			(remove_unused_layers no)
			(net "T6_BLAD4_EN")
			(clearance 0.1016)
			(thermal_gap 0.1016)
		)
		(pad "B80" thru_hole circle
			(at -4.499864 81.000092 270)
			(size 1.016 1.016)
			(drill 0.7112)
			(layers "*.Cu" "*.Mask")
			(remove_unused_layers no)
			(net "GND")
			(clearance 0.1016)
			(thermal_gap 0.1016)
		)
		(pad "B81" thru_hole circle
			(at -2.499868 82.00009 270)
			(size 1.016 1.016)
			(drill 0.7112)
			(layers "*.Cu" "*.Mask")
			(remove_unused_layers no)
			(net "T6_BLAD1_RXD")
			(clearance 0.1016)
			(thermal_gap 0.1016)
		)
		(pad "B82" thru_hole circle
			(at -4.499864 83.000088 270)
			(size 1.016 1.016)
			(drill 0.7112)
			(layers "*.Cu" "*.Mask")
			(remove_unused_layers no)
			(net "T6_BLAD1_TXD")
			(clearance 0.1016)
			(thermal_gap 0.1016)
		)
		(zone
			(layers "F.Cu" "B.Cu" "In1.Cu" "In2.Cu" "In3.Cu" "In4.Cu" "In5.Cu" "In6.Cu")
			(hatch none 0.5)
			(connect_pads
				(clearance 0)
			)
			(min_thickness 0.25)
			(keepout
				(tracks allowed)
				(vias not_allowed)
				(pads allowed)
				(copperpour not_allowed)
				(footprints allowed)
			)
			(placement
				(enabled no)
				(sheetname "")
			)
			(fill
				(thermal_gap 0.5)
				(thermal_bridge_width 0.5)
				(island_removal_mode 0)
			)
			(polygon
				(pts
					(xy 1.369822 -269.103856) (xy 3.732022 -269.103856) (xy 3.732022 -266.386056) (xy 6.678422 -266.386056)
					(xy 6.678422 -269.103856) (xy 9.015222 -269.103856) (xy 9.015222 -353.254056) (xy 1.369822 -353.254056)
				)
			)
		)
		(zone
			(layers "F.Cu" "B.Cu" "In1.Cu" "In2.Cu" "In3.Cu" "In4.Cu" "In5.Cu" "In6.Cu")
			(hatch none 0.5)
			(connect_pads
				(clearance 0)
			)
			(min_thickness 0.25)
			(keepout
				(tracks not_allowed)
				(vias allowed)
				(pads allowed)
				(copperpour not_allowed)
				(footprints allowed)
			)
			(placement
				(enabled no)
				(sheetname "")
			)
			(fill
				(thermal_gap 0.5)
				(thermal_bridge_width 0.5)
				(island_removal_mode 0)
			)
			(polygon
				(pts
					(arc
						(start 3.583686 -341.019892)
						(mid 3.675158 -341.555649)
						(end 3.939032 -342.030812)
					)
					(xy 4.567428 -342.030812)
					(arc
						(start 4.567428 -342.507062)
						(mid 5.201285 -342.635861)
						(end 5.834888 -342.505792)
					)
					(xy 5.834888 -342.038686)
					(arc
						(start 6.45414 -342.038686)
						(mid 5.740161 -339.496883)
						(end 3.583686 -341.019892)
					)
				)
			)
		)
		(zone
			(layers "F.Cu" "B.Cu" "In1.Cu" "In2.Cu" "In3.Cu" "In4.Cu" "In5.Cu" "In6.Cu")
			(hatch none 0.5)
			(connect_pads
				(clearance 0)
			)
			(min_thickness 0.25)
			(keepout
				(tracks not_allowed)
				(vias allowed)
				(pads allowed)
				(copperpour not_allowed)
				(footprints allowed)
			)
			(placement
				(enabled no)
				(sheetname "")
			)
			(fill
				(thermal_gap 0.5)
				(thermal_bridge_width 0.5)
				(island_removal_mode 0)
			)
			(polygon
				(pts
					(arc
						(start 6.813804 -267.869924)
						(mid 3.585972 -267.869924)
						(end 6.813804 -267.869924)
					)
				)
			)
		)
	)
	(footprint ""
		(layer "F.Cu")
		(at 39.874952 -461.170274 180)
		(property "Reference" "R23"
			(at -1.982978 -0.229108 0)
			(unlocked yes)
			(layer "F.SilkS")
			(effects
				(font
					(size 0.7874 0.5842)
					(thickness 0.1524)
				)
				(justify left)
			)
		)
		(property "Value" ""
			(at 0 0 180)
			(layer "F.Fab")
			(effects
				(font
					(size 1.27 1.27)
				)
			)
		)
		(duplicate_pad_numbers_are_jumpers no)
		(fp_line
			(start 0.7874 0.4064)
			(end -0.7874 0.4064)
			(stroke
				(width 0.1524)
				(type default)
			)
			(layer "F.SilkS")
		)
		(fp_line
			(start 0.7874 -0.4064)
			(end 0.7874 0.4064)
			(stroke
				(width 0.1524)
				(type default)
			)
			(layer "F.SilkS")
		)
		(fp_line
			(start -0.7874 0.4064)
			(end -0.7874 -0.4064)
			(stroke
				(width 0.1524)
				(type default)
			)
			(layer "F.SilkS")
		)
		(fp_line
			(start -0.7874 -0.4064)
			(end 0.7874 -0.4064)
			(stroke
				(width 0.1524)
				(type default)
			)
			(layer "F.SilkS")
		)
		(fp_poly
			(pts
				(xy -0.508 0.2794) (xy -0.508 0.2286) (xy -0.635 0.2286) (xy -0.635 -0.254) (xy -0.5334 -0.254)
				(xy -0.5334 -0.2794) (xy 0.5334 -0.2794) (xy 0.5334 -0.254) (xy 0.635 -0.254) (xy 0.635 0.254) (xy 0.5334 0.254)
				(xy 0.5334 0.2794)
			)
			(stroke
				(width 0)
				(type default)
			)
			(fill no)
			(layer "F.CrtYd")
		)
		(pad "1" smd rect
			(at 0.40005 0 180)
			(size 0.4572 0.508)
			(layers "F.Cu" "F.Mask" "F.Paste")
			(net "PSU6_AD0")
		)
		(pad "2" smd rect
			(at -0.40005 0 180)
			(size 0.4572 0.508)
			(layers "F.Cu" "F.Mask" "F.Paste")
			(net "GND")
		)
	)
	(footprint ""
		(layer "F.Cu")
		(at 25.804876 -369.095274)
		(property "Reference" "R138"
			(at -3.886962 -0.631952 0)
			(unlocked yes)
			(layer "F.SilkS")
			(effects
				(font
					(size 0.7874 0.5842)
					(thickness 0.1524)
				)
				(justify left)
			)
		)
		(property "Value" ""
			(at 0 0 0)
			(layer "F.Fab")
			(effects
				(font
					(size 1.27 1.27)
				)
			)
		)
		(duplicate_pad_numbers_are_jumpers no)
		(fp_line
			(start -0.7874 -0.4064)
			(end 0.7874 -0.4064)
			(stroke
				(width 0.1524)
				(type default)
			)
			(layer "F.SilkS")
		)
		(fp_line
			(start -0.7874 0.4064)
			(end -0.7874 -0.4064)
			(stroke
				(width 0.1524)
				(type default)
			)
			(layer "F.SilkS")
		)
		(fp_line
			(start 0.7874 -0.4064)
			(end 0.7874 0.4064)
			(stroke
				(width 0.1524)
				(type default)
			)
			(layer "F.SilkS")
		)
		(fp_line
			(start 0.7874 0.4064)
			(end -0.7874 0.4064)
			(stroke
				(width 0.1524)
				(type default)
			)
			(layer "F.SilkS")
		)
		(fp_poly
			(pts
				(xy -0.508 0.2794) (xy -0.508 0.2286) (xy -0.635 0.2286) (xy -0.635 -0.254) (xy -0.5334 -0.254)
				(xy -0.5334 -0.2794) (xy 0.5334 -0.2794) (xy 0.5334 -0.254) (xy 0.635 -0.254) (xy 0.635 0.254) (xy 0.5334 0.254)
				(xy 0.5334 0.2794)
			)
			(stroke
				(width 0)
				(type default)
			)
			(fill no)
			(layer "F.CrtYd")
		)
		(pad "1" smd rect
			(at 0.40005 0)
			(size 0.4572 0.508)
			(layers "F.Cu" "F.Mask" "F.Paste")
			(net "PSU5_CSAHRE")
		)
		(pad "2" smd rect
			(at -0.40005 0)
			(size 0.4572 0.508)
			(layers "F.Cu" "F.Mask" "F.Paste")
			(net "PSU_CSAHRE")
		)
	)
	(footprint ""
		(layer "F.Cu")
		(at 39.461948 -199.56907 -90)
		(property "Reference" "R94"
			(at -0.904494 -3.072892 90)
			(unlocked yes)
			(layer "F.SilkS")
			(effects
				(font
					(size 0.7874 0.5842)
					(thickness 0.1524)
				)
				(justify left)
			)
		)
		(property "Value" ""
			(at 0 0 270)
			(layer "F.Fab")
			(effects
				(font
					(size 1.27 1.27)
				)
			)
		)
		(duplicate_pad_numbers_are_jumpers no)
		(fp_line
			(start -0.7874 0.4064)
			(end -0.7874 -0.4064)
			(stroke
				(width 0.1524)
				(type default)
			)
			(layer "F.SilkS")
		)
		(fp_line
			(start 0.7874 0.4064)
			(end -0.7874 0.4064)
			(stroke
				(width 0.1524)
				(type default)
			)
			(layer "F.SilkS")
		)
		(fp_line
			(start -0.7874 -0.4064)
			(end 0.7874 -0.4064)
			(stroke
				(width 0.1524)
				(type default)
			)
			(layer "F.SilkS")
		)
		(fp_line
			(start 0.7874 -0.4064)
			(end 0.7874 0.4064)
			(stroke
				(width 0.1524)
				(type default)
			)
			(layer "F.SilkS")
		)
		(fp_poly
			(pts
				(xy -0.508 0.2794) (xy -0.508 0.2286) (xy -0.635 0.2286) (xy -0.635 -0.254) (xy -0.5334 -0.254)
				(xy -0.5334 -0.2794) (xy 0.5334 -0.2794) (xy 0.5334 -0.254) (xy 0.635 -0.254) (xy 0.635 0.254) (xy 0.5334 0.254)
				(xy 0.5334 0.2794)
			)
			(stroke
				(width 0)
				(type default)
			)
			(fill no)
			(layer "F.CrtYd")
		)
		(pad "1" smd rect
			(at 0.40005 0 270)
			(size 0.4572 0.508)
			(layers "F.Cu" "F.Mask" "F.Paste")
			(net "PSU3_REMOTE_P")
		)
		(pad "2" smd rect
			(at -0.40005 0 270)
			(size 0.4572 0.508)
			(layers "F.Cu" "F.Mask" "F.Paste")
			(net "PSU3_REMOTE_R_P")
		)
	)
	(footprint ""
		(layer "F.Cu")
		(at 71.11746 -370.601748 -90)
		(property "Reference" "C59"
			(at -2.675128 -0.117856 90)
			(unlocked yes)
			(layer "F.SilkS")
			(effects
				(font
					(size 0.7874 0.5842)
					(thickness 0.1524)
				)
				(justify left)
			)
		)
		(property "Value" ""
			(at 0 0 270)
			(layer "F.Fab")
			(effects
				(font
					(size 1.27 1.27)
				)
			)
		)
		(duplicate_pad_numbers_are_jumpers no)
		(fp_line
			(start -0.7874 0.4064)
			(end -0.7874 -0.4064)
			(stroke
				(width 0.1524)
				(type default)
			)
			(layer "F.SilkS")
		)
		(fp_line
			(start 0.7874 0.4064)
			(end -0.7874 0.4064)
			(stroke
				(width 0.1524)
				(type default)
			)
			(layer "F.SilkS")
		)
		(fp_line
			(start 0 0.381)
			(end 0 -0.381)
			(stroke
				(width 0.1524)
				(type default)
			)
			(layer "F.SilkS")
		)
		(fp_line
			(start -0.7874 -0.4064)
			(end 0.7874 -0.4064)
			(stroke
				(width 0.1524)
				(type default)
			)
			(layer "F.SilkS")
		)
		(fp_line
			(start 0.7874 -0.4064)
			(end 0.7874 0.4064)
			(stroke
				(width 0.1524)
				(type default)
			)
			(layer "F.SilkS")
		)
		(fp_poly
			(pts
				(xy -0.5334 0.254) (xy -0.635 0.254) (xy -0.635 0.2286) (xy -0.635 -0.254) (xy -0.5334 -0.254) (xy -0.5334 -0.2794)
				(xy 0.5334 -0.2794) (xy 0.5334 -0.254) (xy 0.635 -0.254) (xy 0.635 0.254) (xy 0.5334 0.254) (xy 0.5334 0.2794)
				(xy -0.508 0.2794) (xy -0.5334 0.2794)
			)
			(stroke
				(width 0)
				(type default)
			)
			(fill no)
			(layer "F.CrtYd")
		)
		(pad "1" smd rect
			(at 0.40005 0 270)
			(size 0.4572 0.508)
			(layers "F.Cu" "F.Mask" "F.Paste")
			(net "P12V")
		)
		(pad "2" smd rect
			(at -0.40005 0 270)
			(size 0.4572 0.508)
			(layers "F.Cu" "F.Mask" "F.Paste")
			(net "GND")
		)
	)
	(footprint ""
		(layer "F.Cu")
		(at 81.29143 -504.305824 -90)
		(property "Reference" "C79"
			(at -2.739136 0.063246 90)
			(unlocked yes)
			(layer "F.SilkS")
			(effects
				(font
					(size 0.7874 0.5842)
					(thickness 0.1524)
				)
				(justify left)
			)
		)
		(property "Value" ""
			(at 0 0 270)
			(layer "F.Fab")
			(effects
				(font
					(size 1.27 1.27)
				)
			)
		)
		(duplicate_pad_numbers_are_jumpers no)
		(fp_line
			(start -0.7874 0.4064)
			(end -0.7874 -0.4064)
			(stroke
				(width 0.1524)
				(type default)
			)
			(layer "F.SilkS")
		)
		(fp_line
			(start 0.7874 0.4064)
			(end -0.7874 0.4064)
			(stroke
				(width 0.1524)
				(type default)
			)
			(layer "F.SilkS")
		)
		(fp_line
			(start 0 0.381)
			(end 0 -0.381)
			(stroke
				(width 0.1524)
				(type default)
			)
			(layer "F.SilkS")
		)
		(fp_line
			(start -0.7874 -0.4064)
			(end 0.7874 -0.4064)
			(stroke
				(width 0.1524)
				(type default)
			)
			(layer "F.SilkS")
		)
		(fp_line
			(start 0.7874 -0.4064)
			(end 0.7874 0.4064)
			(stroke
				(width 0.1524)
				(type default)
			)
			(layer "F.SilkS")
		)
		(fp_poly
			(pts
				(xy -0.5334 0.254) (xy -0.635 0.254) (xy -0.635 0.2286) (xy -0.635 -0.254) (xy -0.5334 -0.254) (xy -0.5334 -0.2794)
				(xy 0.5334 -0.2794) (xy 0.5334 -0.254) (xy 0.635 -0.254) (xy 0.635 0.254) (xy 0.5334 0.254) (xy 0.5334 0.2794)
				(xy -0.508 0.2794) (xy -0.5334 0.2794)
			)
			(stroke
				(width 0)
				(type default)
			)
			(fill no)
			(layer "F.CrtYd")
		)
		(pad "1" smd rect
			(at 0.40005 0 270)
			(size 0.4572 0.508)
			(layers "F.Cu" "F.Mask" "F.Paste")
			(net "P12V")
		)
		(pad "2" smd rect
			(at -0.40005 0 270)
			(size 0.4572 0.508)
			(layers "F.Cu" "F.Mask" "F.Paste")
			(net "GND")
		)
	)
	(footprint ""
		(layer "F.Cu")
		(at 71.96836 -175.945546 90)
		(property "Reference" "C32"
			(at -4.154678 0.383032 90)
			(unlocked yes)
			(layer "F.SilkS")
			(effects
				(font
					(size 0.7874 0.5842)
					(thickness 0.1524)
				)
				(justify left)
			)
		)
		(property "Value" ""
			(at 0 0 90)
			(layer "F.Fab")
			(effects
				(font
					(size 1.27 1.27)
				)
			)
		)
		(duplicate_pad_numbers_are_jumpers no)
		(fp_line
			(start 0.7874 -0.4064)
			(end 0.7874 0.4064)
			(stroke
				(width 0.1524)
				(type default)
			)
			(layer "F.SilkS")
		)
		(fp_line
			(start -0.7874 -0.4064)
			(end 0.7874 -0.4064)
			(stroke
				(width 0.1524)
				(type default)
			)
			(layer "F.SilkS")
		)
		(fp_line
			(start 0 0.381)
			(end 0 -0.381)
			(stroke
				(width 0.1524)
				(type default)
			)
			(layer "F.SilkS")
		)
		(fp_line
			(start 0.7874 0.4064)
			(end -0.7874 0.4064)
			(stroke
				(width 0.1524)
				(type default)
			)
			(layer "F.SilkS")
		)
		(fp_line
			(start -0.7874 0.4064)
			(end -0.7874 -0.4064)
			(stroke
				(width 0.1524)
				(type default)
			)
			(layer "F.SilkS")
		)
		(fp_poly
			(pts
				(xy -0.5334 0.254) (xy -0.635 0.254) (xy -0.635 0.2286) (xy -0.635 -0.254) (xy -0.5334 -0.254) (xy -0.5334 -0.2794)
				(xy 0.5334 -0.2794) (xy 0.5334 -0.254) (xy 0.635 -0.254) (xy 0.635 0.254) (xy 0.5334 0.254) (xy 0.5334 0.2794)
				(xy -0.508 0.2794) (xy -0.5334 0.2794)
			)
			(stroke
				(width 0)
				(type default)
			)
			(fill no)
			(layer "F.CrtYd")
		)
		(pad "1" smd rect
			(at 0.40005 0 90)
			(size 0.4572 0.508)
			(layers "F.Cu" "F.Mask" "F.Paste")
			(net "P12V")
		)
		(pad "2" smd rect
			(at -0.40005 0 90)
			(size 0.4572 0.508)
			(layers "F.Cu" "F.Mask" "F.Paste")
			(net "GND")
		)
	)
	(footprint ""
		(layer "F.Cu")
		(at 75.316842 -42.631106 90)
		(property "Reference" "C11"
			(at -1.090422 4.586478 90)
			(unlocked yes)
			(layer "F.SilkS")
			(effects
				(font
					(size 0.7874 0.5842)
					(thickness 0.1524)
				)
				(justify left)
			)
		)
		(property "Value" ""
			(at 0 0 90)
			(layer "F.Fab")
			(effects
				(font
					(size 1.27 1.27)
				)
			)
		)
		(duplicate_pad_numbers_are_jumpers no)
		(fp_line
			(start 0.7874 -0.4064)
			(end 0.7874 0.4064)
			(stroke
				(width 0.1524)
				(type default)
			)
			(layer "F.SilkS")
		)
		(fp_line
			(start -0.7874 -0.4064)
			(end 0.7874 -0.4064)
			(stroke
				(width 0.1524)
				(type default)
			)
			(layer "F.SilkS")
		)
		(fp_line
			(start 0 0.381)
			(end 0 -0.381)
			(stroke
				(width 0.1524)
				(type default)
			)
			(layer "F.SilkS")
		)
		(fp_line
			(start 0.7874 0.4064)
			(end -0.7874 0.4064)
			(stroke
				(width 0.1524)
				(type default)
			)
			(layer "F.SilkS")
		)
		(fp_line
			(start -0.7874 0.4064)
			(end -0.7874 -0.4064)
			(stroke
				(width 0.1524)
				(type default)
			)
			(layer "F.SilkS")
		)
		(fp_poly
			(pts
				(xy -0.5334 0.254) (xy -0.635 0.254) (xy -0.635 0.2286) (xy -0.635 -0.254) (xy -0.5334 -0.254) (xy -0.5334 -0.2794)
				(xy 0.5334 -0.2794) (xy 0.5334 -0.254) (xy 0.635 -0.254) (xy 0.635 0.254) (xy 0.5334 0.254) (xy 0.5334 0.2794)
				(xy -0.508 0.2794) (xy -0.5334 0.2794)
			)
			(stroke
				(width 0)
				(type default)
			)
			(fill no)
			(layer "F.CrtYd")
		)
		(pad "1" smd rect
			(at 0.40005 0 90)
			(size 0.4572 0.508)
			(layers "F.Cu" "F.Mask" "F.Paste")
			(net "P12V")
		)
		(pad "2" smd rect
			(at -0.40005 0 90)
			(size 0.4572 0.508)
			(layers "F.Cu" "F.Mask" "F.Paste")
			(net "GND")
		)
	)
	(footprint ""
		(layer "F.Cu")
		(at 71.423276 -237.708694 -90)
		(property "Reference" "C37"
			(at 0.73406 -3.745992 90)
			(unlocked yes)
			(layer "F.SilkS")
			(effects
				(font
					(size 0.7874 0.5842)
					(thickness 0.1524)
				)
				(justify left)
			)
		)
		(property "Value" ""
			(at 0 0 270)
			(layer "F.Fab")
			(effects
				(font
					(size 1.27 1.27)
				)
			)
		)
		(duplicate_pad_numbers_are_jumpers no)
		(fp_line
			(start -0.7874 0.4064)
			(end -0.7874 -0.4064)
			(stroke
				(width 0.1524)
				(type default)
			)
			(layer "F.SilkS")
		)
		(fp_line
			(start 0.7874 0.4064)
			(end -0.7874 0.4064)
			(stroke
				(width 0.1524)
				(type default)
			)
			(layer "F.SilkS")
		)
		(fp_line
			(start 0 0.381)
			(end 0 -0.381)
			(stroke
				(width 0.1524)
				(type default)
			)
			(layer "F.SilkS")
		)
		(fp_line
			(start -0.7874 -0.4064)
			(end 0.7874 -0.4064)
			(stroke
				(width 0.1524)
				(type default)
			)
			(layer "F.SilkS")
		)
		(fp_line
			(start 0.7874 -0.4064)
			(end 0.7874 0.4064)
			(stroke
				(width 0.1524)
				(type default)
			)
			(layer "F.SilkS")
		)
		(fp_poly
			(pts
				(xy -0.5334 0.254) (xy -0.635 0.254) (xy -0.635 0.2286) (xy -0.635 -0.254) (xy -0.5334 -0.254) (xy -0.5334 -0.2794)
				(xy 0.5334 -0.2794) (xy 0.5334 -0.254) (xy 0.635 -0.254) (xy 0.635 0.254) (xy 0.5334 0.254) (xy 0.5334 0.2794)
				(xy -0.508 0.2794) (xy -0.5334 0.2794)
			)
			(stroke
				(width 0)
				(type default)
			)
			(fill no)
			(layer "F.CrtYd")
		)
		(pad "1" smd rect
			(at 0.40005 0 270)
			(size 0.4572 0.508)
			(layers "F.Cu" "F.Mask" "F.Paste")
			(net "P12V")
		)
		(pad "2" smd rect
			(at -0.40005 0 270)
			(size 0.4572 0.508)
			(layers "F.Cu" "F.Mask" "F.Paste")
			(net "GND")
		)
	)
	(footprint ""
		(layer "F.Cu")
		(at 68.697602 -120.313958 180)
		(property "Reference" "R115"
			(at 2.566162 1.311148 0)
			(unlocked yes)
			(layer "F.SilkS")
			(effects
				(font
					(size 0.7874 0.5842)
					(thickness 0.1524)
				)
				(justify left)
			)
		)
		(property "Value" ""
			(at 0 0 180)
			(layer "F.Fab")
			(effects
				(font
					(size 1.27 1.27)
				)
			)
		)
		(duplicate_pad_numbers_are_jumpers no)
		(fp_line
			(start 0.7874 0.4064)
			(end -0.7874 0.4064)
			(stroke
				(width 0.1524)
				(type default)
			)
			(layer "F.SilkS")
		)
		(fp_line
			(start 0.7874 -0.4064)
			(end 0.7874 0.4064)
			(stroke
				(width 0.1524)
				(type default)
			)
			(layer "F.SilkS")
		)
		(fp_line
			(start -0.7874 0.4064)
			(end -0.7874 -0.4064)
			(stroke
				(width 0.1524)
				(type default)
			)
			(layer "F.SilkS")
		)
		(fp_line
			(start -0.7874 -0.4064)
			(end 0.7874 -0.4064)
			(stroke
				(width 0.1524)
				(type default)
			)
			(layer "F.SilkS")
		)
		(fp_poly
			(pts
				(xy -0.508 0.2794) (xy -0.508 0.2286) (xy -0.635 0.2286) (xy -0.635 -0.254) (xy -0.5334 -0.254)
				(xy -0.5334 -0.2794) (xy 0.5334 -0.2794) (xy 0.5334 -0.254) (xy 0.635 -0.254) (xy 0.635 0.254) (xy 0.5334 0.254)
				(xy 0.5334 0.2794)
			)
			(stroke
				(width 0)
				(type default)
			)
			(fill no)
			(layer "F.CrtYd")
		)
		(pad "1" smd rect
			(at 0.40005 0 180)
			(size 0.4572 0.508)
			(layers "F.Cu" "F.Mask" "F.Paste")
			(net "PSU2_REMOTE_R2_P")
		)
		(pad "2" smd rect
			(at -0.40005 0 180)
			(size 0.4572 0.508)
			(layers "F.Cu" "F.Mask" "F.Paste")
			(net "P12V")
		)
	)
	(footprint ""
		(layer "F.Cu")
		(at 25.857708 -364.246414)
		(property "Reference" "R78"
			(at -3.917442 -0.225298 0)
			(unlocked yes)
			(layer "F.SilkS")
			(effects
				(font
					(size 0.7874 0.5842)
					(thickness 0.1524)
				)
				(justify left)
			)
		)
		(property "Value" ""
			(at 0 0 0)
			(layer "F.Fab")
			(effects
				(font
					(size 1.27 1.27)
				)
			)
		)
		(duplicate_pad_numbers_are_jumpers no)
		(fp_line
			(start -0.7874 -0.4064)
			(end 0.7874 -0.4064)
			(stroke
				(width 0.1524)
				(type default)
			)
			(layer "F.SilkS")
		)
		(fp_line
			(start -0.7874 0.4064)
			(end -0.7874 -0.4064)
			(stroke
				(width 0.1524)
				(type default)
			)
			(layer "F.SilkS")
		)
		(fp_line
			(start 0.7874 -0.4064)
			(end 0.7874 0.4064)
			(stroke
				(width 0.1524)
				(type default)
			)
			(layer "F.SilkS")
		)
		(fp_line
			(start 0.7874 0.4064)
			(end -0.7874 0.4064)
			(stroke
				(width 0.1524)
				(type default)
			)
			(layer "F.SilkS")
		)
		(fp_poly
			(pts
				(xy -0.508 0.2794) (xy -0.508 0.2286) (xy -0.635 0.2286) (xy -0.635 -0.254) (xy -0.5334 -0.254)
				(xy -0.5334 -0.2794) (xy 0.5334 -0.2794) (xy 0.5334 -0.254) (xy 0.635 -0.254) (xy 0.635 0.254) (xy 0.5334 0.254)
				(xy 0.5334 0.2794)
			)
			(stroke
				(width 0)
				(type default)
			)
			(fill no)
			(layer "F.CrtYd")
		)
		(pad "1" smd rect
			(at 0.40005 0)
			(size 0.4572 0.508)
			(layers "F.Cu" "F.Mask" "F.Paste")
			(net "PSU5_PS_KILL")
		)
		(pad "2" smd rect
			(at -0.40005 0)
			(size 0.4572 0.508)
			(layers "F.Cu" "F.Mask" "F.Paste")
			(net "P12V_STBY")
		)
	)
	(footprint ""
		(layer "F.Cu")
		(at 30.45968 -171.729908)
		(property "Reference" "J2"
			(at 7.63778 3.119628 0)
			(unlocked yes)
			(layer "F.SilkS")
			(effects
				(font
					(size 0.7874 0.5842)
					(thickness 0.1524)
				)
				(justify left)
			)
		)
		(property "Value" ""
			(at 0 0 0)
			(layer "F.Fab")
			(effects
				(font
					(size 1.27 1.27)
				)
			)
		)
		(duplicate_pad_numbers_are_jumpers no)
		(fp_line
			(start -2.135124 -4.560062)
			(end -2.135124 83.300062)
			(stroke
				(width 0.1524)
				(type default)
			)
			(layer "F.SilkS")
		)
		(fp_line
			(start -2.135124 83.300062)
			(end 7.215124 83.300062)
			(stroke
				(width 0.1524)
				(type default)
			)
			(layer "F.SilkS")
		)
		(fp_line
			(start 7.215124 -4.560062)
			(end -2.135124 -4.560062)
			(stroke
				(width 0.1524)
				(type default)
			)
			(layer "F.SilkS")
		)
		(fp_line
			(start 7.215124 83.300062)
			(end 7.215124 -4.560062)
			(stroke
				(width 0.1524)
				(type default)
			)
			(layer "F.SilkS")
		)
		(fp_poly
			(pts
				(xy -2.557272 -0.130556) (xy -5.257292 -0.83058) (xy -5.257292 0.569468)
			)
			(stroke
				(width 0)
				(type default)
			)
			(fill yes)
			(layer "F.SilkS")
		)
		(fp_poly
			(pts
				(xy -2.28219 -0.127) (xy -4.98221 -0.827024) (xy -4.98221 0.573024)
			)
			(stroke
				(width 0)
				(type default)
			)
			(fill yes)
			(layer "B.SilkS")
		)
		(fp_poly
			(pts
				(xy -0.8636 -0.8636) (xy -0.8636 79.6036) (xy -0.8636 79.629) (xy 5.9436 79.629) (xy 5.9436 79.6036)
				(xy 5.9436 -0.8636) (xy 5.9436 -0.889) (xy -0.8636 -0.889)
			)
			(stroke
				(width 0)
				(type default)
			)
			(fill no)
			(layer "B.CrtYd")
		)
		(fp_rect
			(start -2.135124 -4.560062)
			(end 7.21487 83.300062)
			(stroke
				(width 0)
				(type default)
			)
			(fill no)
			(layer "F.CrtYd")
		)
		(fp_line
			(start -2.135124 -4.560062)
			(end 7.215124 -4.560062)
			(stroke
				(width 0.1)
				(type default)
			)
			(layer "F.Fab")
		)
		(fp_line
			(start -2.135124 83.300062)
			(end -2.135124 -4.560062)
			(stroke
				(width 0.1)
				(type default)
			)
			(layer "F.Fab")
		)
		(fp_line
			(start 7.215124 -4.560062)
			(end 7.215124 83.300062)
			(stroke
				(width 0.1)
				(type default)
			)
			(layer "F.Fab")
		)
		(fp_line
			(start 7.215124 83.300062)
			(end -2.135124 83.300062)
			(stroke
				(width 0.1)
				(type default)
			)
			(layer "F.Fab")
		)
		(fp_text user "32"
			(at -3.674872 78.298802 0)
			(unlocked yes)
			(layer "F.SilkS")
			(effects
				(font
					(size 0.7874 0.5842)
					(thickness 0.1524)
				)
				(justify left)
			)
		)
		(fp_text user "1"
			(at -3.253994 -1.297178 0)
			(unlocked yes)
			(layer "F.SilkS")
			(effects
				(font
					(size 0.7874 0.5842)
					(thickness 0.1524)
				)
				(justify left)
			)
		)
		(fp_text user "64"
			(at 7.640066 -0.704342 0)
			(unlocked yes)
			(layer "F.SilkS")
			(effects
				(font
					(size 0.7874 0.5842)
					(thickness 0.1524)
				)
				(justify left)
			)
		)
		(fp_text user "33"
			(at 7.654544 83.258914 0)
			(unlocked yes)
			(layer "F.SilkS")
			(effects
				(font
					(size 0.7874 0.5842)
					(thickness 0.1524)
				)
				(justify left)
			)
		)
		(fp_text user "1"
			(at -1.619758 -0.610362 0)
			(unlocked yes)
			(layer "B.SilkS")
			(effects
				(font
					(size 0.7874 0.5842)
					(thickness 0.1524)
				)
				(justify left mirror)
			)
		)
		(fp_text user "32"
			(at -1.102868 78.932024 0)
			(unlocked yes)
			(layer "B.SilkS")
			(effects
				(font
					(size 0.7874 0.5842)
					(thickness 0.1524)
				)
				(justify left mirror)
			)
		)
		(fp_text user "64"
			(at 5.791454 -1.569466 0)
			(unlocked yes)
			(layer "B.SilkS")
			(effects
				(font
					(size 0.7874 0.5842)
					(thickness 0.1524)
				)
				(justify left mirror)
			)
		)
		(fp_text user "33"
			(at 6.84784 83.378294 0)
			(unlocked yes)
			(layer "B.SilkS")
			(effects
				(font
					(size 0.7874 0.5842)
					(thickness 0.1524)
				)
				(justify left mirror)
			)
		)
		(pad "1" thru_hole rect
			(at 0 0 270)
			(size 1.6256 1.6256)
			(drill 1.1176)
			(layers "*.Cu" "*.Mask")
			(remove_unused_layers no)
			(net "P12V")
			(clearance 0)
			(padstack
				(mode front_inner_back)
				(layer "Inner"
					(shape circle)
					(size 1.6256 1.6256)
					(clearance 0)
				)
				(layer "B.Cu"
					(shape rect)
					(size 1.6256 1.6256)
					(clearance 0)
				)
			)
		)
		(pad "2" thru_hole circle
			(at 0 2.54 270)
			(size 1.6256 1.6256)
			(drill 1.1176)
			(layers "*.Cu" "*.Mask")
			(remove_unused_layers no)
			(net "P12V")
			(clearance 0)
		)
		(pad "3" thru_hole circle
			(at 0 5.08 270)
			(size 1.6256 1.6256)
			(drill 1.1176)
			(layers "*.Cu" "*.Mask")
			(remove_unused_layers no)
			(net "P12V")
			(clearance 0)
		)
		(pad "4" thru_hole circle
			(at 0 7.62 270)
			(size 1.6256 1.6256)
			(drill 1.1176)
			(layers "*.Cu" "*.Mask")
			(remove_unused_layers no)
			(net "P12V")
			(clearance 0)
		)
		(pad "5" thru_hole circle
			(at 0 10.16 270)
			(size 1.6256 1.6256)
			(drill 1.1176)
			(layers "*.Cu" "*.Mask")
			(remove_unused_layers no)
			(net "P12V")
			(clearance 0)
		)
		(pad "6" thru_hole circle
			(at 0 12.7 270)
			(size 1.6256 1.6256)
			(drill 1.1176)
			(layers "*.Cu" "*.Mask")
			(remove_unused_layers no)
			(net "P12V")
			(clearance 0)
		)
		(pad "7" thru_hole circle
			(at 0 15.24 270)
			(size 1.6256 1.6256)
			(drill 1.1176)
			(layers "*.Cu" "*.Mask")
			(remove_unused_layers no)
			(net "P12V")
			(clearance 0)
		)
		(pad "8" thru_hole circle
			(at 0 17.78 270)
			(size 1.6256 1.6256)
			(drill 1.1176)
			(layers "*.Cu" "*.Mask")
			(remove_unused_layers no)
			(net "P12V")
			(clearance 0)
		)
		(pad "9" thru_hole circle
			(at 0 20.32 270)
			(size 1.6256 1.6256)
			(drill 1.1176)
			(layers "*.Cu" "*.Mask")
			(remove_unused_layers no)
			(net "P12V")
			(clearance 0)
		)
		(pad "10" thru_hole circle
			(at 0 22.86 270)
			(size 1.6256 1.6256)
			(drill 1.1176)
			(layers "*.Cu" "*.Mask")
			(remove_unused_layers no)
			(net "P12V")
			(clearance 0)
		)
		(pad "11" thru_hole circle
			(at 0 25.4 270)
			(size 1.6256 1.6256)
			(drill 1.1176)
			(layers "*.Cu" "*.Mask")
			(remove_unused_layers no)
			(net "P12V")
			(clearance 0)
		)
		(pad "12" thru_hole circle
			(at 0 27.94 270)
			(size 1.6256 1.6256)
			(drill 1.1176)
			(layers "*.Cu" "*.Mask")
			(remove_unused_layers no)
			(net "P12V")
			(clearance 0)
		)
		(pad "13" thru_hole circle
			(at 0 30.48 270)
			(size 1.6256 1.6256)
			(drill 1.1176)
			(layers "*.Cu" "*.Mask")
			(remove_unused_layers no)
			(net "GND")
			(clearance 0)
		)
		(pad "14" thru_hole circle
			(at 0 33.02 270)
			(size 1.6256 1.6256)
			(drill 1.1176)
			(layers "*.Cu" "*.Mask")
			(remove_unused_layers no)
			(net "GND")
			(clearance 0)
		)
		(pad "15" thru_hole circle
			(at 0 35.56 270)
			(size 1.6256 1.6256)
			(drill 1.1176)
			(layers "*.Cu" "*.Mask")
			(remove_unused_layers no)
			(net "GND")
			(clearance 0)
		)
		(pad "16" thru_hole circle
			(at 0 38.1 270)
			(size 1.6256 1.6256)
			(drill 1.1176)
			(layers "*.Cu" "*.Mask")
			(remove_unused_layers no)
			(net "GND")
			(clearance 0)
		)
		(pad "17" thru_hole circle
			(at 0 40.64 270)
			(size 1.6256 1.6256)
			(drill 1.1176)
			(layers "*.Cu" "*.Mask")
			(remove_unused_layers no)
			(net "GND")
			(clearance 0)
		)
		(pad "18" thru_hole circle
			(at 0 43.18 270)
			(size 1.6256 1.6256)
			(drill 1.1176)
			(layers "*.Cu" "*.Mask")
			(remove_unused_layers no)
			(net "GND")
			(clearance 0)
		)
		(pad "19" thru_hole circle
			(at 0 45.72 270)
			(size 1.6256 1.6256)
			(drill 1.1176)
			(layers "*.Cu" "*.Mask")
			(remove_unused_layers no)
			(net "GND")
			(clearance 0)
		)
		(pad "20" thru_hole circle
			(at 0 48.26 270)
			(size 1.6256 1.6256)
			(drill 1.1176)
			(layers "*.Cu" "*.Mask")
			(remove_unused_layers no)
			(net "GND")
			(clearance 0)
		)
		(pad "21" thru_hole circle
			(at 0 50.8 270)
			(size 1.6256 1.6256)
			(drill 1.1176)
			(layers "*.Cu" "*.Mask")
			(remove_unused_layers no)
			(net "GND")
			(clearance 0)
		)
		(pad "22" thru_hole circle
			(at 0 53.34 270)
			(size 1.6256 1.6256)
			(drill 1.1176)
			(layers "*.Cu" "*.Mask")
			(remove_unused_layers no)
			(net "GND")
			(clearance 0)
		)
		(pad "23" thru_hole circle
			(at 0 55.88 270)
			(size 1.6256 1.6256)
			(drill 1.1176)
			(layers "*.Cu" "*.Mask")
			(remove_unused_layers no)
			(net "GND")
			(clearance 0)
		)
		(pad "24" thru_hole circle
			(at 0 58.42 270)
			(size 1.6256 1.6256)
			(drill 1.1176)
			(layers "*.Cu" "*.Mask")
			(remove_unused_layers no)
			(net "GND")
			(clearance 0)
		)
		(pad "25" thru_hole circle
			(at 0 60.96 270)
			(size 1.6256 1.6256)
			(drill 1.1176)
			(layers "*.Cu" "*.Mask")
			(remove_unused_layers no)
			(net "Net_405")
			(clearance 0)
		)
		(pad "26" thru_hole circle
			(at 0 63.5 270)
			(size 1.6256 1.6256)
			(drill 1.1176)
			(layers "*.Cu" "*.Mask")
			(remove_unused_layers no)
			(net "PSU2_REMOTE_N")
			(clearance 0)
		)
		(pad "27" thru_hole circle
			(at 0 66.04 270)
			(size 1.6256 1.6256)
			(drill 1.1176)
			(layers "*.Cu" "*.Mask")
			(remove_unused_layers no)
			(net "PSU2_AC_OK")
			(clearance 0)
		)
		(pad "28" thru_hole circle
			(at 0 68.58 270)
			(size 1.6256 1.6256)
			(drill 1.1176)
			(layers "*.Cu" "*.Mask")
			(remove_unused_layers no)
			(net "PSU2_CSAHRE")
			(clearance 0)
		)
		(pad "29" thru_hole circle
			(at 0 71.12 270)
			(size 1.6256 1.6256)
			(drill 1.1176)
			(layers "*.Cu" "*.Mask")
			(remove_unused_layers no)
			(net "PSU2_PS_ON_N")
			(clearance 0)
		)
		(pad "30" thru_hole circle
			(at 0 73.66 270)
			(size 1.6256 1.6256)
			(drill 1.1176)
			(layers "*.Cu" "*.Mask")
			(remove_unused_layers no)
			(net "PSU2_PS_KILL")
			(clearance 0)
		)
		(pad "31" thru_hole circle
			(at 0 76.2 270)
			(size 1.6256 1.6256)
			(drill 1.1176)
			(layers "*.Cu" "*.Mask")
			(remove_unused_layers no)
			(net "PSU2_RESET")
			(clearance 0)
		)
		(pad "32" thru_hole circle
			(at 0 78.74 270)
			(size 1.6256 1.6256)
			(drill 1.1176)
			(layers "*.Cu" "*.Mask")
			(remove_unused_layers no)
			(net "PSU_ALERT_N")
			(clearance 0)
		)
		(pad "33" thru_hole circle
			(at 5.08 78.74 270)
			(size 1.6256 1.6256)
			(drill 1.1176)
			(layers "*.Cu" "*.Mask")
			(remove_unused_layers no)
			(net "I2C_PSU1_SDA")
			(clearance 0)
		)
		(pad "34" thru_hole circle
			(at 5.08 76.2 270)
			(size 1.6256 1.6256)
			(drill 1.1176)
			(layers "*.Cu" "*.Mask")
			(remove_unused_layers no)
			(net "Net_406")
			(clearance 0)
		)
		(pad "35" thru_hole circle
			(at 5.08 73.66 270)
			(size 1.6256 1.6256)
			(drill 1.1176)
			(layers "*.Cu" "*.Mask")
			(remove_unused_layers no)
			(net "I2C_PSU1_SCL")
			(clearance 0)
		)
		(pad "36" thru_hole circle
			(at 5.08 71.12 270)
			(size 1.6256 1.6256)
			(drill 1.1176)
			(layers "*.Cu" "*.Mask")
			(remove_unused_layers no)
			(net "PSU2_RETURN")
			(clearance 0)
		)
		(pad "37" thru_hole circle
			(at 5.08 68.58 270)
			(size 1.6256 1.6256)
			(drill 1.1176)
			(layers "*.Cu" "*.Mask")
			(remove_unused_layers no)
			(net "PSU2_DC_OK")
			(clearance 0)
		)
		(pad "38" thru_hole circle
			(at 5.08 66.04 270)
			(size 1.6256 1.6256)
			(drill 1.1176)
			(layers "*.Cu" "*.Mask")
			(remove_unused_layers no)
			(net "PSU2_AD0")
			(clearance 0)
		)
		(pad "39" thru_hole circle
			(at 5.08 63.5 270)
			(size 1.6256 1.6256)
			(drill 1.1176)
			(layers "*.Cu" "*.Mask")
			(remove_unused_layers no)
			(net "P12V_STBY")
			(clearance 0)
		)
		(pad "40" thru_hole circle
			(at 5.08 60.96 270)
			(size 1.6256 1.6256)
			(drill 1.1176)
			(layers "*.Cu" "*.Mask")
			(remove_unused_layers no)
			(net "PSU2_REMOTE_P")
			(clearance 0)
		)
		(pad "41" thru_hole circle
			(at 5.08 58.42 270)
			(size 1.6256 1.6256)
			(drill 1.1176)
			(layers "*.Cu" "*.Mask")
			(remove_unused_layers no)
			(net "GND")
			(clearance 0)
		)
		(pad "42" thru_hole circle
			(at 5.08 55.88 270)
			(size 1.6256 1.6256)
			(drill 1.1176)
			(layers "*.Cu" "*.Mask")
			(remove_unused_layers no)
			(net "GND")
			(clearance 0)
		)
		(pad "43" thru_hole circle
			(at 5.08 53.34 270)
			(size 1.6256 1.6256)
			(drill 1.1176)
			(layers "*.Cu" "*.Mask")
			(remove_unused_layers no)
			(net "GND")
			(clearance 0)
		)
		(pad "44" thru_hole circle
			(at 5.08 50.8 270)
			(size 1.6256 1.6256)
			(drill 1.1176)
			(layers "*.Cu" "*.Mask")
			(remove_unused_layers no)
			(net "GND")
			(clearance 0)
		)
		(pad "45" thru_hole circle
			(at 5.08 48.26 270)
			(size 1.6256 1.6256)
			(drill 1.1176)
			(layers "*.Cu" "*.Mask")
			(remove_unused_layers no)
			(net "GND")
			(clearance 0)
		)
		(pad "46" thru_hole circle
			(at 5.08 45.72 270)
			(size 1.6256 1.6256)
			(drill 1.1176)
			(layers "*.Cu" "*.Mask")
			(remove_unused_layers no)
			(net "GND")
			(clearance 0)
		)
		(pad "47" thru_hole circle
			(at 5.08 43.18 270)
			(size 1.6256 1.6256)
			(drill 1.1176)
			(layers "*.Cu" "*.Mask")
			(remove_unused_layers no)
			(net "GND")
			(clearance 0)
		)
		(pad "48" thru_hole circle
			(at 5.08 40.64 270)
			(size 1.6256 1.6256)
			(drill 1.1176)
			(layers "*.Cu" "*.Mask")
			(remove_unused_layers no)
			(net "GND")
			(clearance 0)
		)
		(pad "49" thru_hole circle
			(at 5.08 38.1 270)
			(size 1.6256 1.6256)
			(drill 1.1176)
			(layers "*.Cu" "*.Mask")
			(remove_unused_layers no)
			(net "GND")
			(clearance 0)
		)
		(pad "50" thru_hole circle
			(at 5.08 35.56 270)
			(size 1.6256 1.6256)
			(drill 1.1176)
			(layers "*.Cu" "*.Mask")
			(remove_unused_layers no)
			(net "GND")
			(clearance 0)
		)
		(pad "51" thru_hole circle
			(at 5.08 33.02 270)
			(size 1.6256 1.6256)
			(drill 1.1176)
			(layers "*.Cu" "*.Mask")
			(remove_unused_layers no)
			(net "GND")
			(clearance 0)
		)
		(pad "52" thru_hole circle
			(at 5.08 30.48 270)
			(size 1.6256 1.6256)
			(drill 1.1176)
			(layers "*.Cu" "*.Mask")
			(remove_unused_layers no)
			(net "GND")
			(clearance 0)
		)
		(pad "53" thru_hole circle
			(at 5.08 27.94 270)
			(size 1.6256 1.6256)
			(drill 1.1176)
			(layers "*.Cu" "*.Mask")
			(remove_unused_layers no)
			(net "P12V")
			(clearance 0)
		)
		(pad "54" thru_hole circle
			(at 5.08 25.4 270)
			(size 1.6256 1.6256)
			(drill 1.1176)
			(layers "*.Cu" "*.Mask")
			(remove_unused_layers no)
			(net "P12V")
			(clearance 0)
		)
		(pad "55" thru_hole circle
			(at 5.08 22.86 270)
			(size 1.6256 1.6256)
			(drill 1.1176)
			(layers "*.Cu" "*.Mask")
			(remove_unused_layers no)
			(net "P12V")
			(clearance 0)
		)
		(pad "56" thru_hole circle
			(at 5.08 20.32 270)
			(size 1.6256 1.6256)
			(drill 1.1176)
			(layers "*.Cu" "*.Mask")
			(remove_unused_layers no)
			(net "P12V")
			(clearance 0)
		)
		(pad "57" thru_hole circle
			(at 5.08 17.78 270)
			(size 1.6256 1.6256)
			(drill 1.1176)
			(layers "*.Cu" "*.Mask")
			(remove_unused_layers no)
			(net "P12V")
			(clearance 0)
		)
		(pad "58" thru_hole circle
			(at 5.08 15.24 270)
			(size 1.6256 1.6256)
			(drill 1.1176)
			(layers "*.Cu" "*.Mask")
			(remove_unused_layers no)
			(net "P12V")
			(clearance 0)
		)
		(pad "59" thru_hole circle
			(at 5.08 12.7 270)
			(size 1.6256 1.6256)
			(drill 1.1176)
			(layers "*.Cu" "*.Mask")
			(remove_unused_layers no)
			(net "P12V")
			(clearance 0)
		)
		(pad "60" thru_hole circle
			(at 5.08 10.16 270)
			(size 1.6256 1.6256)
			(drill 1.1176)
			(layers "*.Cu" "*.Mask")
			(remove_unused_layers no)
			(net "P12V")
			(clearance 0)
		)
		(pad "61" thru_hole circle
			(at 5.08 7.62 270)
			(size 1.6256 1.6256)
			(drill 1.1176)
			(layers "*.Cu" "*.Mask")
			(remove_unused_layers no)
			(net "P12V")
			(clearance 0)
		)
		(pad "62" thru_hole circle
			(at 5.08 5.08 270)
			(size 1.6256 1.6256)
			(drill 1.1176)
			(layers "*.Cu" "*.Mask")
			(remove_unused_layers no)
			(net "P12V")
			(clearance 0)
		)
		(pad "63" thru_hole circle
			(at 5.08 2.54 270)
			(size 1.6256 1.6256)
			(drill 1.1176)
			(layers "*.Cu" "*.Mask")
			(remove_unused_layers no)
			(net "P12V")
			(clearance 0)
		)
		(pad "64" thru_hole circle
			(at 5.08 0 270)
			(size 1.6256 1.6256)
			(drill 1.1176)
			(layers "*.Cu" "*.Mask")
			(remove_unused_layers no)
			(net "P12V")
			(clearance 0)
		)
	)
	(footprint ""
		(layer "F.Cu")
		(at 73.532746 -442.84646 90)
		(property "Reference" "C74"
			(at -3.89128 0.190754 90)
			(unlocked yes)
			(layer "F.SilkS")
			(effects
				(font
					(size 0.7874 0.5842)
					(thickness 0.1524)
				)
				(justify left)
			)
		)
		(property "Value" ""
			(at 0 0 90)
			(layer "F.Fab")
			(effects
				(font
					(size 1.27 1.27)
				)
			)
		)
		(duplicate_pad_numbers_are_jumpers no)
		(fp_line
			(start 0.7874 -0.4064)
			(end 0.7874 0.4064)
			(stroke
				(width 0.1524)
				(type default)
			)
			(layer "F.SilkS")
		)
		(fp_line
			(start -0.7874 -0.4064)
			(end 0.7874 -0.4064)
			(stroke
				(width 0.1524)
				(type default)
			)
			(layer "F.SilkS")
		)
		(fp_line
			(start 0 0.381)
			(end 0 -0.381)
			(stroke
				(width 0.1524)
				(type default)
			)
			(layer "F.SilkS")
		)
		(fp_line
			(start 0.7874 0.4064)
			(end -0.7874 0.4064)
			(stroke
				(width 0.1524)
				(type default)
			)
			(layer "F.SilkS")
		)
		(fp_line
			(start -0.7874 0.4064)
			(end -0.7874 -0.4064)
			(stroke
				(width 0.1524)
				(type default)
			)
			(layer "F.SilkS")
		)
		(fp_poly
			(pts
				(xy -0.5334 0.254) (xy -0.635 0.254) (xy -0.635 0.2286) (xy -0.635 -0.254) (xy -0.5334 -0.254) (xy -0.5334 -0.2794)
				(xy 0.5334 -0.2794) (xy 0.5334 -0.254) (xy 0.635 -0.254) (xy 0.635 0.254) (xy 0.5334 0.254) (xy 0.5334 0.2794)
				(xy -0.508 0.2794) (xy -0.5334 0.2794)
			)
			(stroke
				(width 0)
				(type default)
			)
			(fill no)
			(layer "F.CrtYd")
		)
		(pad "1" smd rect
			(at 0.40005 0 90)
			(size 0.4572 0.508)
			(layers "F.Cu" "F.Mask" "F.Paste")
			(net "P12V")
		)
		(pad "2" smd rect
			(at -0.40005 0 90)
			(size 0.4572 0.508)
			(layers "F.Cu" "F.Mask" "F.Paste")
			(net "GND")
		)
	)
	(footprint ""
		(layer "F.Cu")
		(at 66.891916 -29.351986 180)
		(property "Reference" "R112"
			(at 1.430782 -1.257046 0)
			(unlocked yes)
			(layer "F.SilkS")
			(effects
				(font
					(size 0.7874 0.5842)
					(thickness 0.1524)
				)
				(justify left)
			)
		)
		(property "Value" ""
			(at 0 0 180)
			(layer "F.Fab")
			(effects
				(font
					(size 1.27 1.27)
				)
			)
		)
		(duplicate_pad_numbers_are_jumpers no)
		(fp_line
			(start 0.7874 0.4064)
			(end -0.7874 0.4064)
			(stroke
				(width 0.1524)
				(type default)
			)
			(layer "F.SilkS")
		)
		(fp_line
			(start 0.7874 -0.4064)
			(end 0.7874 0.4064)
			(stroke
				(width 0.1524)
				(type default)
			)
			(layer "F.SilkS")
		)
		(fp_line
			(start -0.7874 0.4064)
			(end -0.7874 -0.4064)
			(stroke
				(width 0.1524)
				(type default)
			)
			(layer "F.SilkS")
		)
		(fp_line
			(start -0.7874 -0.4064)
			(end 0.7874 -0.4064)
			(stroke
				(width 0.1524)
				(type default)
			)
			(layer "F.SilkS")
		)
		(fp_poly
			(pts
				(xy -0.508 0.2794) (xy -0.508 0.2286) (xy -0.635 0.2286) (xy -0.635 -0.254) (xy -0.5334 -0.254)
				(xy -0.5334 -0.2794) (xy 0.5334 -0.2794) (xy 0.5334 -0.254) (xy 0.635 -0.254) (xy 0.635 0.254) (xy 0.5334 0.254)
				(xy 0.5334 0.2794)
			)
			(stroke
				(width 0)
				(type default)
			)
			(fill no)
			(layer "F.CrtYd")
		)
		(pad "1" smd rect
			(at 0.40005 0 180)
			(size 0.4572 0.508)
			(layers "F.Cu" "F.Mask" "F.Paste")
			(net "PSU1_REMOTE_R2_N")
		)
		(pad "2" smd rect
			(at -0.40005 0 180)
			(size 0.4572 0.508)
			(layers "F.Cu" "F.Mask" "F.Paste")
			(net "GND")
		)
	)
	(footprint ""
		(layer "F.Cu")
		(at 71.45147 -220.425772 90)
		(property "Reference" "C40"
			(at -3.909568 -0.112014 90)
			(unlocked yes)
			(layer "F.SilkS")
			(effects
				(font
					(size 0.7874 0.5842)
					(thickness 0.1524)
				)
				(justify left)
			)
		)
		(property "Value" ""
			(at 0 0 90)
			(layer "F.Fab")
			(effects
				(font
					(size 1.27 1.27)
				)
			)
		)
		(duplicate_pad_numbers_are_jumpers no)
		(fp_line
			(start 0.7874 -0.4064)
			(end 0.7874 0.4064)
			(stroke
				(width 0.1524)
				(type default)
			)
			(layer "F.SilkS")
		)
		(fp_line
			(start -0.7874 -0.4064)
			(end 0.7874 -0.4064)
			(stroke
				(width 0.1524)
				(type default)
			)
			(layer "F.SilkS")
		)
		(fp_line
			(start 0 0.381)
			(end 0 -0.381)
			(stroke
				(width 0.1524)
				(type default)
			)
			(layer "F.SilkS")
		)
		(fp_line
			(start 0.7874 0.4064)
			(end -0.7874 0.4064)
			(stroke
				(width 0.1524)
				(type default)
			)
			(layer "F.SilkS")
		)
		(fp_line
			(start -0.7874 0.4064)
			(end -0.7874 -0.4064)
			(stroke
				(width 0.1524)
				(type default)
			)
			(layer "F.SilkS")
		)
		(fp_poly
			(pts
				(xy -0.5334 0.254) (xy -0.635 0.254) (xy -0.635 0.2286) (xy -0.635 -0.254) (xy -0.5334 -0.254) (xy -0.5334 -0.2794)
				(xy 0.5334 -0.2794) (xy 0.5334 -0.254) (xy 0.635 -0.254) (xy 0.635 0.254) (xy 0.5334 0.254) (xy 0.5334 0.2794)
				(xy -0.508 0.2794) (xy -0.5334 0.2794)
			)
			(stroke
				(width 0)
				(type default)
			)
			(fill no)
			(layer "F.CrtYd")
		)
		(pad "1" smd rect
			(at 0.40005 0 90)
			(size 0.4572 0.508)
			(layers "F.Cu" "F.Mask" "F.Paste")
			(net "P12V")
		)
		(pad "2" smd rect
			(at -0.40005 0 90)
			(size 0.4572 0.508)
			(layers "F.Cu" "F.Mask" "F.Paste")
			(net "GND")
		)
	)
	(footprint ""
		(layer "F.Cu")
		(at 26.125678 -278.486362 180)
		(property "Reference" "R52"
			(at 3.845306 0.107188 0)
			(unlocked yes)
			(layer "F.SilkS")
			(effects
				(font
					(size 0.7874 0.5842)
					(thickness 0.1524)
				)
				(justify left)
			)
		)
		(property "Value" ""
			(at 0 0 180)
			(layer "F.Fab")
			(effects
				(font
					(size 1.27 1.27)
				)
			)
		)
		(duplicate_pad_numbers_are_jumpers no)
		(fp_line
			(start 0.7874 0.4064)
			(end -0.7874 0.4064)
			(stroke
				(width 0.1524)
				(type default)
			)
			(layer "F.SilkS")
		)
		(fp_line
			(start 0.7874 -0.4064)
			(end 0.7874 0.4064)
			(stroke
				(width 0.1524)
				(type default)
			)
			(layer "F.SilkS")
		)
		(fp_line
			(start -0.7874 0.4064)
			(end -0.7874 -0.4064)
			(stroke
				(width 0.1524)
				(type default)
			)
			(layer "F.SilkS")
		)
		(fp_line
			(start -0.7874 -0.4064)
			(end 0.7874 -0.4064)
			(stroke
				(width 0.1524)
				(type default)
			)
			(layer "F.SilkS")
		)
		(fp_poly
			(pts
				(xy -0.508 0.2794) (xy -0.508 0.2286) (xy -0.635 0.2286) (xy -0.635 -0.254) (xy -0.5334 -0.254)
				(xy -0.5334 -0.2794) (xy 0.5334 -0.2794) (xy 0.5334 -0.254) (xy 0.635 -0.254) (xy 0.635 0.254) (xy 0.5334 0.254)
				(xy 0.5334 0.2794)
			)
			(stroke
				(width 0)
				(type default)
			)
			(fill no)
			(layer "F.CrtYd")
		)
		(pad "1" smd rect
			(at 0.40005 0 180)
			(size 0.4572 0.508)
			(layers "F.Cu" "F.Mask" "F.Paste")
			(net "GND")
		)
		(pad "2" smd rect
			(at -0.40005 0 180)
			(size 0.4572 0.508)
			(layers "F.Cu" "F.Mask" "F.Paste")
			(net "PSU4_PS_ON_N")
		)
	)
	(footprint ""
		(layer "F.Cu")
		(at 16.21028 -146.178778 -90)
		(property "Reference" "R149"
			(at 1.268476 -0.9398 90)
			(unlocked yes)
			(layer "F.SilkS")
			(effects
				(font
					(size 0.7874 0.5842)
					(thickness 0.1524)
				)
				(justify left)
			)
		)
		(property "Value" ""
			(at 0 0 270)
			(layer "F.Fab")
			(effects
				(font
					(size 1.27 1.27)
				)
			)
		)
		(duplicate_pad_numbers_are_jumpers no)
		(fp_line
			(start -0.7874 0.4064)
			(end -0.7874 -0.4064)
			(stroke
				(width 0.1524)
				(type default)
			)
			(layer "F.SilkS")
		)
		(fp_line
			(start 0.7874 0.4064)
			(end -0.7874 0.4064)
			(stroke
				(width 0.1524)
				(type default)
			)
			(layer "F.SilkS")
		)
		(fp_line
			(start -0.7874 -0.4064)
			(end 0.7874 -0.4064)
			(stroke
				(width 0.1524)
				(type default)
			)
			(layer "F.SilkS")
		)
		(fp_line
			(start 0.7874 -0.4064)
			(end 0.7874 0.4064)
			(stroke
				(width 0.1524)
				(type default)
			)
			(layer "F.SilkS")
		)
		(fp_poly
			(pts
				(xy -0.508 0.2794) (xy -0.508 0.2286) (xy -0.635 0.2286) (xy -0.635 -0.254) (xy -0.5334 -0.254)
				(xy -0.5334 -0.2794) (xy 0.5334 -0.2794) (xy 0.5334 -0.254) (xy 0.635 -0.254) (xy 0.635 0.254) (xy 0.5334 0.254)
				(xy 0.5334 0.2794)
			)
			(stroke
				(width 0)
				(type default)
			)
			(fill no)
			(layer "F.CrtYd")
		)
		(pad "1" smd rect
			(at 0.40005 0 270)
			(size 0.4572 0.508)
			(layers "F.Cu" "F.Mask" "F.Paste")
			(net "N42126764")
		)
		(pad "2" smd rect
			(at -0.40005 0 270)
			(size 0.4572 0.508)
			(layers "F.Cu" "F.Mask" "F.Paste")
			(net "GND")
		)
	)
	(footprint ""
		(layer "F.Cu")
		(at 77.999844 -32.29991)
		(property "Reference" "H12"
			(at 7.171944 -6.474206 0)
			(unlocked yes)
			(layer "F.SilkS")
			(effects
				(font
					(size 0.7874 0.5842)
					(thickness 0.1524)
				)
				(justify left)
			)
		)
		(property "Value" ""
			(at 0 0 0)
			(layer "F.Fab")
			(effects
				(font
					(size 1.27 1.27)
				)
			)
		)
		(duplicate_pad_numbers_are_jumpers no)
		(fp_circle
			(center 0 0)
			(end 7.999984 0)
			(stroke
				(width 0.1524)
				(type default)
			)
			(fill no)
			(layer "F.SilkS")
		)
		(fp_circle
			(center 0 0)
			(end 14.7066 0)
			(stroke
				(width 0.1524)
				(type default)
			)
			(fill no)
			(layer "B.SilkS")
		)
		(fp_poly
			(pts
				(arc
					(start 5.0038 0)
					(mid -5.0038 0)
					(end 5.0038 0)
				)
			)
			(stroke
				(width 0)
				(type default)
			)
			(fill no)
			(layer "F.CrtYd")
		)
		(pad "" np_thru_hole circle
			(at 0 0)
			(size 4.0132 4.0132)
			(drill 4.0132)
			(layers "*.Cu" "*.Mask")
			(clearance 0.381)
			(thermal_gap 0.381)
		)
		(pad "2" thru_hole circle
			(at 0 -3.50012)
			(size 0.762 0.762)
			(drill 0.5588)
			(layers "*.Cu" "*.Mask")
			(remove_unused_layers no)
			(net "GND")
			(clearance 0.1524)
			(thermal_gap 0.1524)
		)
		(pad "3" thru_hole circle
			(at -2.500122 -2.500122)
			(size 0.762 0.762)
			(drill 0.5588)
			(layers "*.Cu" "*.Mask")
			(remove_unused_layers no)
			(net "GND")
			(clearance 0.1524)
			(thermal_gap 0.1524)
		)
		(pad "4" thru_hole circle
			(at -3.50012 0)
			(size 0.762 0.762)
			(drill 0.5588)
			(layers "*.Cu" "*.Mask")
			(remove_unused_layers no)
			(net "GND")
			(clearance 0.1524)
			(thermal_gap 0.1524)
		)
		(pad "5" thru_hole circle
			(at -2.500122 2.500122)
			(size 0.762 0.762)
			(drill 0.5588)
			(layers "*.Cu" "*.Mask")
			(remove_unused_layers no)
			(net "GND")
			(clearance 0.1524)
			(thermal_gap 0.1524)
		)
		(pad "6" thru_hole circle
			(at 0 3.50012)
			(size 0.762 0.762)
			(drill 0.5588)
			(layers "*.Cu" "*.Mask")
			(remove_unused_layers no)
			(net "GND")
			(clearance 0.1524)
			(thermal_gap 0.1524)
		)
		(pad "7" thru_hole circle
			(at 2.500122 2.500122)
			(size 0.762 0.762)
			(drill 0.5588)
			(layers "*.Cu" "*.Mask")
			(remove_unused_layers no)
			(net "GND")
			(clearance 0.1524)
			(thermal_gap 0.1524)
		)
		(pad "8" thru_hole circle
			(at 3.50012 0)
			(size 0.762 0.762)
			(drill 0.5588)
			(layers "*.Cu" "*.Mask")
			(remove_unused_layers no)
			(net "GND")
			(clearance 0.1524)
			(thermal_gap 0.1524)
		)
		(pad "9" thru_hole circle
			(at 2.500122 -2.500122)
			(size 0.762 0.762)
			(drill 0.5588)
			(layers "*.Cu" "*.Mask")
			(remove_unused_layers no)
			(net "GND")
			(clearance 0.1524)
			(thermal_gap 0.1524)
		)
		(zone
			(layer "F.Cu")
			(hatch none 0.5)
			(connect_pads
				(clearance 0)
			)
			(min_thickness 0.25)
			(keepout
				(tracks not_allowed)
				(vias allowed)
				(pads allowed)
				(copperpour not_allowed)
				(footprints allowed)
			)
			(placement
				(enabled no)
				(sheetname "")
			)
			(fill
				(thermal_gap 0.5)
				(thermal_bridge_width 0.5)
				(island_removal_mode 0)
			)
			(polygon
				(pts
					(arc
						(start 77.999844 -40.30091)
						(mid 69.998844 -32.29991)
						(end 77.999844 -24.29891)
					)
					(arc
						(start 77.999844 -24.29891)
						(mid 79.434944 -25.73401)
						(end 77.999844 -27.16911)
					)
					(arc
						(start 77.999844 -27.16911)
						(mid 72.869044 -32.29991)
						(end 77.999844 -37.43071)
					)
					(arc
						(start 77.999844 -37.43071)
						(mid 79.434944 -38.86581)
						(end 77.999844 -40.30091)
					)
				)
			)
		)
		(zone
			(layer "F.Cu")
			(hatch none 0.5)
			(connect_pads
				(clearance 0)
			)
			(min_thickness 0.25)
			(keepout
				(tracks not_allowed)
				(vias allowed)
				(pads allowed)
				(copperpour not_allowed)
				(footprints allowed)
			)
			(placement
				(enabled no)
				(sheetname "")
			)
			(fill
				(thermal_gap 0.5)
				(thermal_bridge_width 0.5)
				(island_removal_mode 0)
			)
			(polygon
				(pts
					(arc
						(start 77.999844 -40.30091)
						(mid 86.000844 -32.29991)
						(end 77.999844 -24.29891)
					)
					(arc
						(start 77.999844 -24.29891)
						(mid 76.564744 -25.73401)
						(end 77.999844 -27.16911)
					)
					(arc
						(start 77.999844 -27.16911)
						(mid 83.130644 -32.29991)
						(end 77.999844 -37.43071)
					)
					(arc
						(start 77.999844 -37.43071)
						(mid 76.564744 -38.86581)
						(end 77.999844 -40.30091)
					)
				)
			)
		)
		(zone
			(layers "F.Cu" "B.Cu" "In1.Cu" "In2.Cu" "In3.Cu" "In4.Cu" "In5.Cu" "In6.Cu")
			(hatch none 0.5)
			(connect_pads
				(clearance 0)
			)
			(min_thickness 0.25)
			(keepout
				(tracks not_allowed)
				(vias allowed)
				(pads allowed)
				(copperpour not_allowed)
				(footprints allowed)
			)
			(placement
				(enabled no)
				(sheetname "")
			)
			(fill
				(thermal_gap 0.5)
				(thermal_bridge_width 0.5)
				(island_removal_mode 0)
			)
			(polygon
				(pts
					(arc
						(start 80.511904 -32.29991)
						(mid 75.487784 -32.29991)
						(end 80.511904 -32.29991)
					)
				)
			)
		)
	)
	(footprint ""
		(layer "F.Cu")
		(at 77.999844 -341.250016)
		(property "Reference" "H5"
			(at -6.4516 -7.127748 0)
			(unlocked yes)
			(layer "F.SilkS")
			(effects
				(font
					(size 0.7874 0.5842)
					(thickness 0.1524)
				)
				(justify left)
			)
		)
		(property "Value" ""
			(at 0 0 0)
			(layer "F.Fab")
			(effects
				(font
					(size 1.27 1.27)
				)
			)
		)
		(duplicate_pad_numbers_are_jumpers no)
		(fp_circle
			(center 0 0)
			(end 7.999984 0)
			(stroke
				(width 0.1524)
				(type default)
			)
			(fill no)
			(layer "F.SilkS")
		)
		(fp_circle
			(center 0 0)
			(end 14.7066 0)
			(stroke
				(width 0.1524)
				(type default)
			)
			(fill no)
			(layer "B.SilkS")
		)
		(fp_poly
			(pts
				(arc
					(start 5.0038 0)
					(mid -5.0038 0)
					(end 5.0038 0)
				)
			)
			(stroke
				(width 0)
				(type default)
			)
			(fill no)
			(layer "F.CrtYd")
		)
		(pad "" np_thru_hole circle
			(at 0 0)
			(size 4.0132 4.0132)
			(drill 4.0132)
			(layers "*.Cu" "*.Mask")
			(clearance 0.381)
			(thermal_gap 0.381)
		)
		(pad "2" thru_hole circle
			(at 0 -3.50012)
			(size 0.762 0.762)
			(drill 0.5588)
			(layers "*.Cu" "*.Mask")
			(remove_unused_layers no)
			(net "GND")
			(clearance 0.1524)
			(thermal_gap 0.1524)
		)
		(pad "3" thru_hole circle
			(at -2.500122 -2.500122)
			(size 0.762 0.762)
			(drill 0.5588)
			(layers "*.Cu" "*.Mask")
			(remove_unused_layers no)
			(net "GND")
			(clearance 0.1524)
			(thermal_gap 0.1524)
		)
		(pad "4" thru_hole circle
			(at -3.50012 0)
			(size 0.762 0.762)
			(drill 0.5588)
			(layers "*.Cu" "*.Mask")
			(remove_unused_layers no)
			(net "GND")
			(clearance 0.1524)
			(thermal_gap 0.1524)
		)
		(pad "5" thru_hole circle
			(at -2.500122 2.500122)
			(size 0.762 0.762)
			(drill 0.5588)
			(layers "*.Cu" "*.Mask")
			(remove_unused_layers no)
			(net "GND")
			(clearance 0.1524)
			(thermal_gap 0.1524)
		)
		(pad "6" thru_hole circle
			(at 0 3.50012)
			(size 0.762 0.762)
			(drill 0.5588)
			(layers "*.Cu" "*.Mask")
			(remove_unused_layers no)
			(net "GND")
			(clearance 0.1524)
			(thermal_gap 0.1524)
		)
		(pad "7" thru_hole circle
			(at 2.500122 2.500122)
			(size 0.762 0.762)
			(drill 0.5588)
			(layers "*.Cu" "*.Mask")
			(remove_unused_layers no)
			(net "GND")
			(clearance 0.1524)
			(thermal_gap 0.1524)
		)
		(pad "8" thru_hole circle
			(at 3.50012 0)
			(size 0.762 0.762)
			(drill 0.5588)
			(layers "*.Cu" "*.Mask")
			(remove_unused_layers no)
			(net "GND")
			(clearance 0.1524)
			(thermal_gap 0.1524)
		)
		(pad "9" thru_hole circle
			(at 2.500122 -2.500122)
			(size 0.762 0.762)
			(drill 0.5588)
			(layers "*.Cu" "*.Mask")
			(remove_unused_layers no)
			(net "GND")
			(clearance 0.1524)
			(thermal_gap 0.1524)
		)
		(zone
			(layer "F.Cu")
			(hatch none 0.5)
			(connect_pads
				(clearance 0)
			)
			(min_thickness 0.25)
			(keepout
				(tracks not_allowed)
				(vias allowed)
				(pads allowed)
				(copperpour not_allowed)
				(footprints allowed)
			)
			(placement
				(enabled no)
				(sheetname "")
			)
			(fill
				(thermal_gap 0.5)
				(thermal_bridge_width 0.5)
				(island_removal_mode 0)
			)
			(polygon
				(pts
					(arc
						(start 77.999844 -349.251016)
						(mid 69.998844 -341.250016)
						(end 77.999844 -333.249016)
					)
					(arc
						(start 77.999844 -333.249016)
						(mid 79.434944 -334.684116)
						(end 77.999844 -336.119216)
					)
					(arc
						(start 77.999844 -336.119216)
						(mid 72.869044 -341.250016)
						(end 77.999844 -346.380816)
					)
					(arc
						(start 77.999844 -346.380816)
						(mid 79.434944 -347.815916)
						(end 77.999844 -349.251016)
					)
				)
			)
		)
		(zone
			(layer "F.Cu")
			(hatch none 0.5)
			(connect_pads
				(clearance 0)
			)
			(min_thickness 0.25)
			(keepout
				(tracks not_allowed)
				(vias allowed)
				(pads allowed)
				(copperpour not_allowed)
				(footprints allowed)
			)
			(placement
				(enabled no)
				(sheetname "")
			)
			(fill
				(thermal_gap 0.5)
				(thermal_bridge_width 0.5)
				(island_removal_mode 0)
			)
			(polygon
				(pts
					(arc
						(start 77.999844 -349.251016)
						(mid 86.000844 -341.250016)
						(end 77.999844 -333.249016)
					)
					(arc
						(start 77.999844 -333.249016)
						(mid 76.564744 -334.684116)
						(end 77.999844 -336.119216)
					)
					(arc
						(start 77.999844 -336.119216)
						(mid 83.130644 -341.250016)
						(end 77.999844 -346.380816)
					)
					(arc
						(start 77.999844 -346.380816)
						(mid 76.564744 -347.815916)
						(end 77.999844 -349.251016)
					)
				)
			)
		)
		(zone
			(layers "F.Cu" "B.Cu" "In1.Cu" "In2.Cu" "In3.Cu" "In4.Cu" "In5.Cu" "In6.Cu")
			(hatch none 0.5)
			(connect_pads
				(clearance 0)
			)
			(min_thickness 0.25)
			(keepout
				(tracks not_allowed)
				(vias allowed)
				(pads allowed)
				(copperpour not_allowed)
				(footprints allowed)
			)
			(placement
				(enabled no)
				(sheetname "")
			)
			(fill
				(thermal_gap 0.5)
				(thermal_bridge_width 0.5)
				(island_removal_mode 0)
			)
			(polygon
				(pts
					(arc
						(start 80.511904 -341.250016)
						(mid 75.487784 -341.250016)
						(end 80.511904 -341.250016)
					)
				)
			)
		)
	)
	(footprint ""
		(layer "F.Cu")
		(at 39.863776 -199.171814 180)
		(property "Reference" "R2"
			(at -1.93802 0.367792 0)
			(unlocked yes)
			(layer "F.SilkS")
			(effects
				(font
					(size 0.7874 0.5842)
					(thickness 0.1524)
				)
				(justify left)
			)
		)
		(property "Value" ""
			(at 0 0 180)
			(layer "F.Fab")
			(effects
				(font
					(size 1.27 1.27)
				)
			)
		)
		(duplicate_pad_numbers_are_jumpers no)
		(fp_line
			(start 0.7874 0.4064)
			(end -0.7874 0.4064)
			(stroke
				(width 0.1524)
				(type default)
			)
			(layer "F.SilkS")
		)
		(fp_line
			(start 0.7874 -0.4064)
			(end 0.7874 0.4064)
			(stroke
				(width 0.1524)
				(type default)
			)
			(layer "F.SilkS")
		)
		(fp_line
			(start -0.7874 0.4064)
			(end -0.7874 -0.4064)
			(stroke
				(width 0.1524)
				(type default)
			)
			(layer "F.SilkS")
		)
		(fp_line
			(start -0.7874 -0.4064)
			(end 0.7874 -0.4064)
			(stroke
				(width 0.1524)
				(type default)
			)
			(layer "F.SilkS")
		)
		(fp_poly
			(pts
				(xy -0.508 0.2794) (xy -0.508 0.2286) (xy -0.635 0.2286) (xy -0.635 -0.254) (xy -0.5334 -0.254)
				(xy -0.5334 -0.2794) (xy 0.5334 -0.2794) (xy 0.5334 -0.254) (xy 0.635 -0.254) (xy 0.635 0.254) (xy 0.5334 0.254)
				(xy 0.5334 0.2794)
			)
			(stroke
				(width 0)
				(type default)
			)
			(fill no)
			(layer "F.CrtYd")
		)
		(pad "1" smd rect
			(at 0.40005 0 180)
			(size 0.4572 0.508)
			(layers "F.Cu" "F.Mask" "F.Paste")
			(net "PSU3_REMOTE_P")
		)
		(pad "2" smd rect
			(at -0.40005 0 180)
			(size 0.4572 0.508)
			(layers "F.Cu" "F.Mask" "F.Paste")
			(net "P12V")
		)
	)
	(footprint ""
		(layer "F.Cu")
		(at 69.549518 -487.29138 90)
		(property "Reference" "C84"
			(at -4.090162 -0.14605 90)
			(unlocked yes)
			(layer "F.SilkS")
			(effects
				(font
					(size 0.7874 0.5842)
					(thickness 0.1524)
				)
				(justify left)
			)
		)
		(property "Value" ""
			(at 0 0 90)
			(layer "F.Fab")
			(effects
				(font
					(size 1.27 1.27)
				)
			)
		)
		(duplicate_pad_numbers_are_jumpers no)
		(fp_line
			(start 0.7874 -0.4064)
			(end 0.7874 0.4064)
			(stroke
				(width 0.1524)
				(type default)
			)
			(layer "F.SilkS")
		)
		(fp_line
			(start -0.7874 -0.4064)
			(end 0.7874 -0.4064)
			(stroke
				(width 0.1524)
				(type default)
			)
			(layer "F.SilkS")
		)
		(fp_line
			(start 0 0.381)
			(end 0 -0.381)
			(stroke
				(width 0.1524)
				(type default)
			)
			(layer "F.SilkS")
		)
		(fp_line
			(start 0.7874 0.4064)
			(end -0.7874 0.4064)
			(stroke
				(width 0.1524)
				(type default)
			)
			(layer "F.SilkS")
		)
		(fp_line
			(start -0.7874 0.4064)
			(end -0.7874 -0.4064)
			(stroke
				(width 0.1524)
				(type default)
			)
			(layer "F.SilkS")
		)
		(fp_poly
			(pts
				(xy -0.5334 0.254) (xy -0.635 0.254) (xy -0.635 0.2286) (xy -0.635 -0.254) (xy -0.5334 -0.254) (xy -0.5334 -0.2794)
				(xy 0.5334 -0.2794) (xy 0.5334 -0.254) (xy 0.635 -0.254) (xy 0.635 0.254) (xy 0.5334 0.254) (xy 0.5334 0.2794)
				(xy -0.508 0.2794) (xy -0.5334 0.2794)
			)
			(stroke
				(width 0)
				(type default)
			)
			(fill no)
			(layer "F.CrtYd")
		)
		(pad "1" smd rect
			(at 0.40005 0 90)
			(size 0.4572 0.508)
			(layers "F.Cu" "F.Mask" "F.Paste")
			(net "P12V")
		)
		(pad "2" smd rect
			(at -0.40005 0 90)
			(size 0.4572 0.508)
			(layers "F.Cu" "F.Mask" "F.Paste")
			(net "GND")
		)
	)
	(footprint ""
		(layer "F.Cu")
		(at 39.577264 -375.589546 90)
		(property "Reference" "R126"
			(at -0.735076 2.494026 0)
			(unlocked yes)
			(layer "F.SilkS")
			(effects
				(font
					(size 0.7874 0.5842)
					(thickness 0.1524)
				)
				(justify left)
			)
		)
		(property "Value" ""
			(at 0 0 90)
			(layer "F.Fab")
			(effects
				(font
					(size 1.27 1.27)
				)
			)
		)
		(duplicate_pad_numbers_are_jumpers no)
		(fp_line
			(start 0.7874 -0.4064)
			(end 0.7874 0.4064)
			(stroke
				(width 0.1524)
				(type default)
			)
			(layer "F.SilkS")
		)
		(fp_line
			(start -0.7874 -0.4064)
			(end 0.7874 -0.4064)
			(stroke
				(width 0.1524)
				(type default)
			)
			(layer "F.SilkS")
		)
		(fp_line
			(start 0.7874 0.4064)
			(end -0.7874 0.4064)
			(stroke
				(width 0.1524)
				(type default)
			)
			(layer "F.SilkS")
		)
		(fp_line
			(start -0.7874 0.4064)
			(end -0.7874 -0.4064)
			(stroke
				(width 0.1524)
				(type default)
			)
			(layer "F.SilkS")
		)
		(fp_poly
			(pts
				(xy -0.508 0.2794) (xy -0.508 0.2286) (xy -0.635 0.2286) (xy -0.635 -0.254) (xy -0.5334 -0.254)
				(xy -0.5334 -0.2794) (xy 0.5334 -0.2794) (xy 0.5334 -0.254) (xy 0.635 -0.254) (xy 0.635 0.254) (xy 0.5334 0.254)
				(xy 0.5334 0.2794)
			)
			(stroke
				(width 0)
				(type default)
			)
			(fill no)
			(layer "F.CrtYd")
		)
		(pad "1" smd rect
			(at 0.40005 0 90)
			(size 0.4572 0.508)
			(layers "F.Cu" "F.Mask" "F.Paste")
			(net "PSU5_REMOTE_P")
		)
		(pad "2" smd rect
			(at -0.40005 0 90)
			(size 0.4572 0.508)
			(layers "F.Cu" "F.Mask" "F.Paste")
			(net "PSU5_REMOTE_R2_P")
		)
	)
	(footprint ""
		(layer "F.Cu")
		(at 50.418238 -439.763154 180)
		(property "Reference" "CE20"
			(at -4.84124 2.782824 0)
			(unlocked yes)
			(layer "F.SilkS")
			(effects
				(font
					(size 0.7874 0.5842)
					(thickness 0.1524)
				)
				(justify left)
			)
		)
		(property "Value" ""
			(at 0 0 180)
			(layer "F.Fab")
			(effects
				(font
					(size 1.27 1.27)
				)
			)
		)
		(duplicate_pad_numbers_are_jumpers no)
		(fp_line
			(start 0 -4.2672)
			(end 0 4.2672)
			(stroke
				(width 0.1524)
				(type default)
			)
			(layer "F.SilkS")
		)
		(fp_circle
			(center 0 0)
			(end -4.2672 0)
			(stroke
				(width 0.1524)
				(type default)
			)
			(fill no)
			(layer "F.SilkS")
		)
		(fp_poly
			(pts
				(arc
					(start 0 -4.2672)
					(mid 4.2672 0)
					(end 0 4.2672)
				)
			)
			(stroke
				(width 0)
				(type default)
			)
			(fill yes)
			(layer "F.SilkS")
		)
		(fp_poly
			(pts
				(xy -2.5146 -0.762) (xy -0.9906 -0.762) (xy -0.9906 0.762) (xy -2.5146 0.762)
			)
			(stroke
				(width 0)
				(type default)
			)
			(fill no)
			(layer "B.CrtYd")
		)
		(fp_poly
			(pts
				(arc
					(start 1.7526 0.762)
					(mid 2.291415 -0.538815)
					(end 0.9906 0)
				)
				(arc
					(start 0.9906 0.0254)
					(mid 1.206345 0.546255)
					(end 1.7272 0.762)
				)
			)
			(stroke
				(width 0)
				(type default)
			)
			(fill no)
			(layer "B.CrtYd")
		)
		(fp_poly
			(pts
				(arc
					(start -4.2672 0)
					(mid 4.2672 0)
					(end -4.2672 0)
				)
			)
			(stroke
				(width 0)
				(type default)
			)
			(fill no)
			(layer "F.CrtYd")
		)
		(fp_circle
			(center 0 0)
			(end -4.2672 0)
			(stroke
				(width 0.1)
				(type default)
			)
			(fill no)
			(layer "F.Fab")
		)
		(fp_text user "+"
			(at -5.6642 0.15367 180)
			(unlocked yes)
			(layer "F.SilkS")
			(effects
				(font
					(size 0.7874 0.5842)
					(thickness 0.1524)
				)
				(justify left)
			)
		)
		(fp_text user "+"
			(at -5.6642 -0.34925 180)
			(unlocked yes)
			(layer "F.Fab")
			(effects
				(font
					(size 1.905 1.4224)
					(thickness 0.000001)
				)
				(justify left)
			)
		)
		(pad "1" thru_hole rect
			(at -1.75006 0 180)
			(size 1.397 1.397)
			(drill 0.9144)
			(layers "*.Cu" "*.Mask")
			(remove_unused_layers no)
			(net "P12V")
			(clearance 0.0127)
			(thermal_gap 0.0127)
			(padstack
				(mode front_inner_back)
				(layer "Inner"
					(shape circle)
					(size 1.397 1.397)
					(clearance 0.0127)
				)
				(layer "B.Cu"
					(shape rect)
					(size 1.397 1.397)
					(clearance 0.0127)
				)
			)
		)
		(pad "2" thru_hole circle
			(at 1.75006 0 180)
			(size 1.397 1.397)
			(drill 0.9144)
			(layers "*.Cu" "*.Mask")
			(remove_unused_layers no)
			(net "GND")
			(clearance 0.0127)
			(thermal_gap 0.0127)
		)
	)
	(footprint ""
		(layer "F.Cu")
		(at 39.462964 -21.994368 90)
		(property "Reference" "R110"
			(at -0.675132 1.446022 0)
			(unlocked yes)
			(layer "F.SilkS")
			(effects
				(font
					(size 0.7874 0.5842)
					(thickness 0.1524)
				)
				(justify left)
			)
		)
		(property "Value" ""
			(at 0 0 90)
			(layer "F.Fab")
			(effects
				(font
					(size 1.27 1.27)
				)
			)
		)
		(duplicate_pad_numbers_are_jumpers no)
		(fp_line
			(start 0.7874 -0.4064)
			(end 0.7874 0.4064)
			(stroke
				(width 0.1524)
				(type default)
			)
			(layer "F.SilkS")
		)
		(fp_line
			(start -0.7874 -0.4064)
			(end 0.7874 -0.4064)
			(stroke
				(width 0.1524)
				(type default)
			)
			(layer "F.SilkS")
		)
		(fp_line
			(start 0.7874 0.4064)
			(end -0.7874 0.4064)
			(stroke
				(width 0.1524)
				(type default)
			)
			(layer "F.SilkS")
		)
		(fp_line
			(start -0.7874 0.4064)
			(end -0.7874 -0.4064)
			(stroke
				(width 0.1524)
				(type default)
			)
			(layer "F.SilkS")
		)
		(fp_poly
			(pts
				(xy -0.508 0.2794) (xy -0.508 0.2286) (xy -0.635 0.2286) (xy -0.635 -0.254) (xy -0.5334 -0.254)
				(xy -0.5334 -0.2794) (xy 0.5334 -0.2794) (xy 0.5334 -0.254) (xy 0.635 -0.254) (xy 0.635 0.254) (xy 0.5334 0.254)
				(xy 0.5334 0.2794)
			)
			(stroke
				(width 0)
				(type default)
			)
			(fill no)
			(layer "F.CrtYd")
		)
		(pad "1" smd rect
			(at 0.40005 0 90)
			(size 0.4572 0.508)
			(layers "F.Cu" "F.Mask" "F.Paste")
			(net "PSU1_REMOTE_P")
		)
		(pad "2" smd rect
			(at -0.40005 0 90)
			(size 0.4572 0.508)
			(layers "F.Cu" "F.Mask" "F.Paste")
			(net "PSU1_REMOTE_R2_P")
		)
	)
	(footprint ""
		(layer "F.Cu")
		(at 25.931622 -96.872044)
		(property "Reference" "R68"
			(at -4.080256 -0.075692 0)
			(unlocked yes)
			(layer "F.SilkS")
			(effects
				(font
					(size 0.7874 0.5842)
					(thickness 0.1524)
				)
				(justify left)
			)
		)
		(property "Value" ""
			(at 0 0 0)
			(layer "F.Fab")
			(effects
				(font
					(size 1.27 1.27)
				)
			)
		)
		(duplicate_pad_numbers_are_jumpers no)
		(fp_line
			(start -0.7874 -0.4064)
			(end 0.7874 -0.4064)
			(stroke
				(width 0.1524)
				(type default)
			)
			(layer "F.SilkS")
		)
		(fp_line
			(start -0.7874 0.4064)
			(end -0.7874 -0.4064)
			(stroke
				(width 0.1524)
				(type default)
			)
			(layer "F.SilkS")
		)
		(fp_line
			(start 0.7874 -0.4064)
			(end 0.7874 0.4064)
			(stroke
				(width 0.1524)
				(type default)
			)
			(layer "F.SilkS")
		)
		(fp_line
			(start 0.7874 0.4064)
			(end -0.7874 0.4064)
			(stroke
				(width 0.1524)
				(type default)
			)
			(layer "F.SilkS")
		)
		(fp_poly
			(pts
				(xy -0.508 0.2794) (xy -0.508 0.2286) (xy -0.635 0.2286) (xy -0.635 -0.254) (xy -0.5334 -0.254)
				(xy -0.5334 -0.2794) (xy 0.5334 -0.2794) (xy 0.5334 -0.254) (xy 0.635 -0.254) (xy 0.635 0.254) (xy 0.5334 0.254)
				(xy 0.5334 0.2794)
			)
			(stroke
				(width 0)
				(type default)
			)
			(fill no)
			(layer "F.CrtYd")
		)
		(pad "1" smd rect
			(at 0.40005 0)
			(size 0.4572 0.508)
			(layers "F.Cu" "F.Mask" "F.Paste")
			(net "PSU2_RESET")
		)
		(pad "2" smd rect
			(at -0.40005 0)
			(size 0.4572 0.508)
			(layers "F.Cu" "F.Mask" "F.Paste")
			(net "P12V_STBY")
		)
	)
	(footprint ""
		(layer "F.Cu")
		(at 39.581836 -376.389646 -90)
		(property "Reference" "R102"
			(at -1.34493 0.095758 90)
			(unlocked yes)
			(layer "F.SilkS")
			(effects
				(font
					(size 0.7874 0.5842)
					(thickness 0.1524)
				)
				(justify left)
			)
		)
		(property "Value" ""
			(at 0 0 270)
			(layer "F.Fab")
			(effects
				(font
					(size 1.27 1.27)
				)
			)
		)
		(duplicate_pad_numbers_are_jumpers no)
		(fp_line
			(start -0.7874 0.4064)
			(end -0.7874 -0.4064)
			(stroke
				(width 0.1524)
				(type default)
			)
			(layer "F.SilkS")
		)
		(fp_line
			(start 0.7874 0.4064)
			(end -0.7874 0.4064)
			(stroke
				(width 0.1524)
				(type default)
			)
			(layer "F.SilkS")
		)
		(fp_line
			(start -0.7874 -0.4064)
			(end 0.7874 -0.4064)
			(stroke
				(width 0.1524)
				(type default)
			)
			(layer "F.SilkS")
		)
		(fp_line
			(start 0.7874 -0.4064)
			(end 0.7874 0.4064)
			(stroke
				(width 0.1524)
				(type default)
			)
			(layer "F.SilkS")
		)
		(fp_poly
			(pts
				(xy -0.508 0.2794) (xy -0.508 0.2286) (xy -0.635 0.2286) (xy -0.635 -0.254) (xy -0.5334 -0.254)
				(xy -0.5334 -0.2794) (xy 0.5334 -0.2794) (xy 0.5334 -0.254) (xy 0.635 -0.254) (xy 0.635 0.254) (xy 0.5334 0.254)
				(xy 0.5334 0.2794)
			)
			(stroke
				(width 0)
				(type default)
			)
			(fill no)
			(layer "F.CrtYd")
		)
		(pad "1" smd rect
			(at 0.40005 0 270)
			(size 0.4572 0.508)
			(layers "F.Cu" "F.Mask" "F.Paste")
			(net "PSU5_REMOTE_P")
		)
		(pad "2" smd rect
			(at -0.40005 0 270)
			(size 0.4572 0.508)
			(layers "F.Cu" "F.Mask" "F.Paste")
			(net "PSU5_REMOTE_R_P")
		)
	)
	(footprint ""
		(layer "F.Cu")
		(at 50.478944 -196.729604 180)
		(property "Reference" "CE10"
			(at -4.974844 0.065278 0)
			(unlocked yes)
			(layer "F.SilkS")
			(effects
				(font
					(size 0.7874 0.5842)
					(thickness 0.1524)
				)
				(justify left)
			)
		)
		(property "Value" ""
			(at 0 0 180)
			(layer "F.Fab")
			(effects
				(font
					(size 1.27 1.27)
				)
			)
		)
		(duplicate_pad_numbers_are_jumpers no)
		(fp_line
			(start 0 -4.2672)
			(end 0 4.2672)
			(stroke
				(width 0.1524)
				(type default)
			)
			(layer "F.SilkS")
		)
		(fp_circle
			(center 0 0)
			(end -4.2672 0)
			(stroke
				(width 0.1524)
				(type default)
			)
			(fill no)
			(layer "F.SilkS")
		)
		(fp_poly
			(pts
				(arc
					(start 0 -4.2672)
					(mid 4.2672 0)
					(end 0 4.2672)
				)
			)
			(stroke
				(width 0)
				(type default)
			)
			(fill yes)
			(layer "F.SilkS")
		)
		(fp_poly
			(pts
				(xy -2.5146 -0.762) (xy -0.9906 -0.762) (xy -0.9906 0.762) (xy -2.5146 0.762)
			)
			(stroke
				(width 0)
				(type default)
			)
			(fill no)
			(layer "B.CrtYd")
		)
		(fp_poly
			(pts
				(arc
					(start 1.7526 0.762)
					(mid 2.291415 -0.538815)
					(end 0.9906 0)
				)
				(arc
					(start 0.9906 0.0254)
					(mid 1.206345 0.546255)
					(end 1.7272 0.762)
				)
			)
			(stroke
				(width 0)
				(type default)
			)
			(fill no)
			(layer "B.CrtYd")
		)
		(fp_poly
			(pts
				(arc
					(start -4.2672 0)
					(mid 4.2672 0)
					(end -4.2672 0)
				)
			)
			(stroke
				(width 0)
				(type default)
			)
			(fill no)
			(layer "F.CrtYd")
		)
		(fp_circle
			(center 0 0)
			(end -4.2672 0)
			(stroke
				(width 0.1)
				(type default)
			)
			(fill no)
			(layer "F.Fab")
		)
		(fp_text user "+"
			(at -5.846572 -1.215136 180)
			(unlocked yes)
			(layer "F.SilkS")
			(effects
				(font
					(size 0.7874 0.5842)
					(thickness 0.1524)
				)
				(justify left)
			)
		)
		(fp_text user "+"
			(at -5.6642 -0.34925 180)
			(unlocked yes)
			(layer "F.Fab")
			(effects
				(font
					(size 1.905 1.4224)
					(thickness 0.000001)
				)
				(justify left)
			)
		)
		(pad "1" thru_hole rect
			(at -1.75006 0 180)
			(size 1.397 1.397)
			(drill 0.9144)
			(layers "*.Cu" "*.Mask")
			(remove_unused_layers no)
			(net "P12V")
			(clearance 0.0127)
			(thermal_gap 0.0127)
			(padstack
				(mode front_inner_back)
				(layer "Inner"
					(shape circle)
					(size 1.397 1.397)
					(clearance 0.0127)
				)
				(layer "B.Cu"
					(shape rect)
					(size 1.397 1.397)
					(clearance 0.0127)
				)
			)
		)
		(pad "2" thru_hole circle
			(at 1.75006 0 180)
			(size 1.397 1.397)
			(drill 0.9144)
			(layers "*.Cu" "*.Mask")
			(remove_unused_layers no)
			(net "GND")
			(clearance 0.0127)
			(thermal_gap 0.0127)
		)
	)
	(footprint ""
		(layer "F.Cu")
		(at 14.9225 -146.162014 -90)
		(property "Reference" "R148"
			(at 1.076452 1.187704 90)
			(unlocked yes)
			(layer "F.SilkS")
			(effects
				(font
					(size 0.7874 0.5842)
					(thickness 0.1524)
				)
				(justify left)
			)
		)
		(property "Value" ""
			(at 0 0 270)
			(layer "F.Fab")
			(effects
				(font
					(size 1.27 1.27)
				)
			)
		)
		(duplicate_pad_numbers_are_jumpers no)
		(fp_line
			(start -0.7874 0.4064)
			(end -0.7874 -0.4064)
			(stroke
				(width 0.1524)
				(type default)
			)
			(layer "F.SilkS")
		)
		(fp_line
			(start 0.7874 0.4064)
			(end -0.7874 0.4064)
			(stroke
				(width 0.1524)
				(type default)
			)
			(layer "F.SilkS")
		)
		(fp_line
			(start -0.7874 -0.4064)
			(end 0.7874 -0.4064)
			(stroke
				(width 0.1524)
				(type default)
			)
			(layer "F.SilkS")
		)
		(fp_line
			(start 0.7874 -0.4064)
			(end 0.7874 0.4064)
			(stroke
				(width 0.1524)
				(type default)
			)
			(layer "F.SilkS")
		)
		(fp_poly
			(pts
				(xy -0.508 0.2794) (xy -0.508 0.2286) (xy -0.635 0.2286) (xy -0.635 -0.254) (xy -0.5334 -0.254)
				(xy -0.5334 -0.2794) (xy 0.5334 -0.2794) (xy 0.5334 -0.254) (xy 0.635 -0.254) (xy 0.635 0.254) (xy 0.5334 0.254)
				(xy 0.5334 0.2794)
			)
			(stroke
				(width 0)
				(type default)
			)
			(fill no)
			(layer "F.CrtYd")
		)
		(pad "1" smd rect
			(at 0.40005 0 270)
			(size 0.4572 0.508)
			(layers "F.Cu" "F.Mask" "F.Paste")
			(net "N42126673")
		)
		(pad "2" smd rect
			(at -0.40005 0 270)
			(size 0.4572 0.508)
			(layers "F.Cu" "F.Mask" "F.Paste")
			(net "GND")
		)
	)
	(footprint ""
		(layer "F.Cu")
		(at 27.640026 -284.62986 90)
		(property "Reference" "R125"
			(at -3.83413 -1.65354 90)
			(unlocked yes)
			(layer "F.SilkS")
			(effects
				(font
					(size 0.7874 0.5842)
					(thickness 0.1524)
				)
				(justify left)
			)
		)
		(property "Value" ""
			(at 0 0 90)
			(layer "F.Fab")
			(effects
				(font
					(size 1.27 1.27)
				)
			)
		)
		(duplicate_pad_numbers_are_jumpers no)
		(fp_line
			(start 0.7874 -0.4064)
			(end 0.7874 0.4064)
			(stroke
				(width 0.1524)
				(type default)
			)
			(layer "F.SilkS")
		)
		(fp_line
			(start -0.7874 -0.4064)
			(end 0.7874 -0.4064)
			(stroke
				(width 0.1524)
				(type default)
			)
			(layer "F.SilkS")
		)
		(fp_line
			(start 0.7874 0.4064)
			(end -0.7874 0.4064)
			(stroke
				(width 0.1524)
				(type default)
			)
			(layer "F.SilkS")
		)
		(fp_line
			(start -0.7874 0.4064)
			(end -0.7874 -0.4064)
			(stroke
				(width 0.1524)
				(type default)
			)
			(layer "F.SilkS")
		)
		(fp_poly
			(pts
				(xy -0.508 0.2794) (xy -0.508 0.2286) (xy -0.635 0.2286) (xy -0.635 -0.254) (xy -0.5334 -0.254)
				(xy -0.5334 -0.2794) (xy 0.5334 -0.2794) (xy 0.5334 -0.254) (xy 0.635 -0.254) (xy 0.635 0.254) (xy 0.5334 0.254)
				(xy 0.5334 0.2794)
			)
			(stroke
				(width 0)
				(type default)
			)
			(fill no)
			(layer "F.CrtYd")
		)
		(pad "1" smd rect
			(at 0.40005 0 90)
			(size 0.4572 0.508)
			(layers "F.Cu" "F.Mask" "F.Paste")
			(net "PSU4_REMOTE_N")
		)
		(pad "2" smd rect
			(at -0.40005 0 90)
			(size 0.4572 0.508)
			(layers "F.Cu" "F.Mask" "F.Paste")
			(net "PSU4_REMOTE_R2_N")
		)
	)
	(footprint ""
		(layer "F.Cu")
		(at 27.052778 -10.617962)
		(property "Reference" "R50"
			(at -4.020312 -0.32258 0)
			(unlocked yes)
			(layer "F.SilkS")
			(effects
				(font
					(size 0.7874 0.5842)
					(thickness 0.1524)
				)
				(justify left)
			)
		)
		(property "Value" ""
			(at 0 0 0)
			(layer "F.Fab")
			(effects
				(font
					(size 1.27 1.27)
				)
			)
		)
		(duplicate_pad_numbers_are_jumpers no)
		(fp_line
			(start -0.7874 -0.4064)
			(end 0.7874 -0.4064)
			(stroke
				(width 0.1524)
				(type default)
			)
			(layer "F.SilkS")
		)
		(fp_line
			(start -0.7874 0.4064)
			(end -0.7874 -0.4064)
			(stroke
				(width 0.1524)
				(type default)
			)
			(layer "F.SilkS")
		)
		(fp_line
			(start 0.7874 -0.4064)
			(end 0.7874 0.4064)
			(stroke
				(width 0.1524)
				(type default)
			)
			(layer "F.SilkS")
		)
		(fp_line
			(start 0.7874 0.4064)
			(end -0.7874 0.4064)
			(stroke
				(width 0.1524)
				(type default)
			)
			(layer "F.SilkS")
		)
		(fp_poly
			(pts
				(xy -0.508 0.2794) (xy -0.508 0.2286) (xy -0.635 0.2286) (xy -0.635 -0.254) (xy -0.5334 -0.254)
				(xy -0.5334 -0.2794) (xy 0.5334 -0.2794) (xy 0.5334 -0.254) (xy 0.635 -0.254) (xy 0.635 0.254) (xy 0.5334 0.254)
				(xy 0.5334 0.2794)
			)
			(stroke
				(width 0)
				(type default)
			)
			(fill no)
			(layer "F.CrtYd")
		)
		(pad "1" smd rect
			(at 0.40005 0)
			(size 0.4572 0.508)
			(layers "F.Cu" "F.Mask" "F.Paste")
			(net "GND")
		)
		(pad "2" smd rect
			(at -0.40005 0)
			(size 0.4572 0.508)
			(layers "F.Cu" "F.Mask" "F.Paste")
			(net "PSU2_PS_ON_N")
		)
	)
	(footprint ""
		(layer "F.Cu")
		(at 2.439924 -373.875046 90)
		(property "Reference" "J31"
			(at -1.76022 4.875022 90)
			(unlocked yes)
			(layer "F.SilkS")
			(effects
				(font
					(size 0.7874 0.5842)
					(thickness 0.1524)
				)
				(justify left)
			)
		)
		(property "Value" ""
			(at 0 0 90)
			(layer "F.Fab")
			(effects
				(font
					(size 1.27 1.27)
				)
			)
		)
		(duplicate_pad_numbers_are_jumpers no)
		(fp_line
			(start 1.849882 -1.999996)
			(end -3.02006 -1.999996)
			(stroke
				(width 0.1524)
				(type default)
			)
			(layer "F.SilkS")
		)
		(fp_line
			(start -3.02006 -1.999996)
			(end -3.02006 3.999992)
			(stroke
				(width 0.1524)
				(type default)
			)
			(layer "F.SilkS")
		)
		(fp_line
			(start 1.35001 -1.500124)
			(end -2.519934 -1.500124)
			(stroke
				(width 0.1524)
				(type default)
			)
			(layer "F.SilkS")
		)
		(fp_line
			(start -2.519934 -1.500124)
			(end -2.519934 3.50012)
			(stroke
				(width 0.1524)
				(type default)
			)
			(layer "F.SilkS")
		)
		(fp_line
			(start 1.849882 0.500126)
			(end 1.35001 0.500126)
			(stroke
				(width 0.1524)
				(type default)
			)
			(layer "F.SilkS")
		)
		(fp_line
			(start 1.35001 0.500126)
			(end 1.35001 -1.500124)
			(stroke
				(width 0.1524)
				(type default)
			)
			(layer "F.SilkS")
		)
		(fp_line
			(start 1.35001 1.500124)
			(end 1.849882 1.500124)
			(stroke
				(width 0.1524)
				(type default)
			)
			(layer "F.SilkS")
		)
		(fp_line
			(start 1.35001 3.50012)
			(end 1.35001 1.500124)
			(stroke
				(width 0.1524)
				(type default)
			)
			(layer "F.SilkS")
		)
		(fp_line
			(start -2.519934 3.50012)
			(end 1.35001 3.50012)
			(stroke
				(width 0.1524)
				(type default)
			)
			(layer "F.SilkS")
		)
		(fp_line
			(start 1.849882 3.999992)
			(end 1.849882 -1.999996)
			(stroke
				(width 0.1524)
				(type default)
			)
			(layer "F.SilkS")
		)
		(fp_line
			(start -3.02006 3.999992)
			(end 1.849882 3.999992)
			(stroke
				(width 0.1524)
				(type default)
			)
			(layer "F.SilkS")
		)
		(fp_poly
			(pts
				(xy 2.01041 0) (xy 3.06959 -0.52959) (xy 3.06959 0.52959)
			)
			(stroke
				(width 0)
				(type default)
			)
			(fill yes)
			(layer "F.SilkS")
		)
		(fp_poly
			(pts
				(xy -0.8382 2.8194) (xy 0.8382 2.8194) (xy 0.8382 -0.8382) (xy -0.8382 -0.8382)
			)
			(stroke
				(width 0)
				(type default)
			)
			(fill no)
			(layer "B.CrtYd")
		)
		(fp_poly
			(pts
				(xy -3.02006 3.999992) (xy 1.849882 3.999992) (xy 1.849882 -1.999996) (xy -3.02006 -1.999996)
			)
			(stroke
				(width 0)
				(type default)
			)
			(fill no)
			(layer "F.CrtYd")
		)
		(fp_line
			(start 1.849882 -1.999996)
			(end -3.02006 -1.999996)
			(stroke
				(width 0.1)
				(type default)
			)
			(layer "F.Fab")
		)
		(fp_line
			(start -3.02006 -1.999996)
			(end -3.02006 3.999992)
			(stroke
				(width 0.1)
				(type default)
			)
			(layer "F.Fab")
		)
		(fp_line
			(start 1.849882 3.999992)
			(end 1.849882 -1.999996)
			(stroke
				(width 0.1)
				(type default)
			)
			(layer "F.Fab")
		)
		(fp_line
			(start -3.02006 3.999992)
			(end 1.849882 3.999992)
			(stroke
				(width 0.1)
				(type default)
			)
			(layer "F.Fab")
		)
		(fp_poly
			(pts
				(xy 2.01041 0) (xy 3.06959 -0.52959) (xy 3.06959 0.52959)
			)
			(stroke
				(width 0)
				(type default)
			)
			(fill yes)
			(layer "F.Fab")
		)
		(fp_text user "2"
			(at 2.5527 2.16535 90)
			(unlocked yes)
			(layer "F.SilkS")
			(effects
				(font
					(size 0.7874 0.5842)
					(thickness 0.1524)
				)
			)
		)
		(fp_text user "1"
			(at 1.2192 0.00127 90)
			(unlocked yes)
			(layer "B.SilkS")
			(effects
				(font
					(size 0.7874 0.5842)
					(thickness 0.1524)
				)
				(justify mirror)
			)
		)
		(fp_text user "2"
			(at 1.2192 2.001266 90)
			(unlocked yes)
			(layer "B.SilkS")
			(effects
				(font
					(size 0.7874 0.5842)
					(thickness 0.1524)
				)
				(justify mirror)
			)
		)
		(fp_text user "1"
			(at 1.2192 0.00127 90)
			(unlocked yes)
			(layer "B.Fab")
			(effects
				(font
					(size 0.7874 0.5842)
					(thickness 0.1524)
				)
				(justify mirror)
			)
		)
		(fp_text user "2"
			(at 1.2192 2.001266 90)
			(unlocked yes)
			(layer "B.Fab")
			(effects
				(font
					(size 0.7874 0.5842)
					(thickness 0.1524)
				)
				(justify mirror)
			)
		)
		(fp_text user "2"
			(at 2.5527 2.16535 90)
			(unlocked yes)
			(layer "F.Fab")
			(effects
				(font
					(size 0.7874 0.5842)
					(thickness 0.1524)
				)
			)
		)
		(pad "1" thru_hole rect
			(at 0 0 90)
			(size 1.524 1.524)
			(drill 1.016)
			(layers "*.Cu" "*.Mask")
			(remove_unused_layers no)
			(net "POWER_SW2_PWR_CTR_12V")
			(clearance 0)
			(padstack
				(mode front_inner_back)
				(layer "Inner"
					(shape circle)
					(size 1.524 1.524)
					(clearance 0)
				)
				(layer "B.Cu"
					(shape rect)
					(size 1.524 1.524)
					(clearance 0)
				)
			)
		)
		(pad "2" thru_hole circle
			(at 0 1.999996 90)
			(size 1.524 1.524)
			(drill 1.016)
			(layers "*.Cu" "*.Mask")
			(remove_unused_layers no)
			(net "GND")
			(clearance 0)
		)
	)
	(footprint ""
		(layer "F.Cu")
		(at 25.931622 -98.10369)
		(property "Reference" "R66"
			(at -4.080256 -0.075692 0)
			(unlocked yes)
			(layer "F.SilkS")
			(effects
				(font
					(size 0.7874 0.5842)
					(thickness 0.1524)
				)
				(justify left)
			)
		)
		(property "Value" ""
			(at 0 0 0)
			(layer "F.Fab")
			(effects
				(font
					(size 1.27 1.27)
				)
			)
		)
		(duplicate_pad_numbers_are_jumpers no)
		(fp_line
			(start -0.7874 -0.4064)
			(end 0.7874 -0.4064)
			(stroke
				(width 0.1524)
				(type default)
			)
			(layer "F.SilkS")
		)
		(fp_line
			(start -0.7874 0.4064)
			(end -0.7874 -0.4064)
			(stroke
				(width 0.1524)
				(type default)
			)
			(layer "F.SilkS")
		)
		(fp_line
			(start 0.7874 -0.4064)
			(end 0.7874 0.4064)
			(stroke
				(width 0.1524)
				(type default)
			)
			(layer "F.SilkS")
		)
		(fp_line
			(start 0.7874 0.4064)
			(end -0.7874 0.4064)
			(stroke
				(width 0.1524)
				(type default)
			)
			(layer "F.SilkS")
		)
		(fp_poly
			(pts
				(xy -0.508 0.2794) (xy -0.508 0.2286) (xy -0.635 0.2286) (xy -0.635 -0.254) (xy -0.5334 -0.254)
				(xy -0.5334 -0.2794) (xy 0.5334 -0.2794) (xy 0.5334 -0.254) (xy 0.635 -0.254) (xy 0.635 0.254) (xy 0.5334 0.254)
				(xy 0.5334 0.2794)
			)
			(stroke
				(width 0)
				(type default)
			)
			(fill no)
			(layer "F.CrtYd")
		)
		(pad "1" smd rect
			(at 0.40005 0)
			(size 0.4572 0.508)
			(layers "F.Cu" "F.Mask" "F.Paste")
			(net "PSU2_PS_KILL")
		)
		(pad "2" smd rect
			(at -0.40005 0)
			(size 0.4572 0.508)
			(layers "F.Cu" "F.Mask" "F.Paste")
			(net "P12V_STBY")
		)
	)
	(footprint ""
		(layer "F.Cu")
		(at 91.399868 -375.61012)
		(property "Reference" "H23"
			(at -5.1308 -5.23113 0)
			(unlocked yes)
			(layer "F.SilkS")
			(effects
				(font
					(size 0.7874 0.5842)
					(thickness 0.1524)
				)
				(justify left)
			)
		)
		(property "Value" ""
			(at 0 0 0)
			(layer "F.Fab")
			(effects
				(font
					(size 1.27 1.27)
				)
			)
		)
		(duplicate_pad_numbers_are_jumpers no)
		(fp_circle
			(center 0 0)
			(end 4.826 0)
			(stroke
				(width 0.1524)
				(type default)
			)
			(fill no)
			(layer "F.SilkS")
		)
		(fp_circle
			(center 0 0)
			(end 4.826 0)
			(stroke
				(width 0.1524)
				(type default)
			)
			(fill no)
			(layer "B.SilkS")
		)
		(fp_poly
			(pts
				(arc
					(start 0 4.0132)
					(mid 0 -4.0132)
					(end 0 4.0132)
				)
			)
			(stroke
				(width 0)
				(type default)
			)
			(fill no)
			(layer "F.CrtYd")
		)
		(pad "" np_thru_hole circle
			(at 0 0)
			(size 8.001 8.001)
			(drill 8.001)
			(layers "*.Cu" "*.Mask")
			(clearance 0.381)
			(thermal_gap 0.381)
		)
		(zone
			(layers "F.Cu" "B.Cu" "In1.Cu" "In2.Cu" "In3.Cu" "In4.Cu" "In5.Cu" "In6.Cu")
			(hatch none 0.5)
			(connect_pads
				(clearance 0)
			)
			(min_thickness 0.25)
			(keepout
				(tracks not_allowed)
				(vias allowed)
				(pads allowed)
				(copperpour not_allowed)
				(footprints allowed)
			)
			(placement
				(enabled no)
				(sheetname "")
			)
			(fill
				(thermal_gap 0.5)
				(thermal_bridge_width 0.5)
				(island_removal_mode 0)
			)
			(polygon
				(pts
					(arc
						(start 91.399868 -371.08892)
						(mid 91.399868 -380.13132)
						(end 91.399868 -371.08892)
					)
				)
			)
		)
	)
	(footprint ""
		(layer "F.Cu")
		(at 39.97325 -192.216278 180)
		(property "Reference" "R10"
			(at -1.626616 -0.081026 0)
			(unlocked yes)
			(layer "F.SilkS")
			(effects
				(font
					(size 0.7874 0.5842)
					(thickness 0.1524)
				)
				(justify left)
			)
		)
		(property "Value" ""
			(at 0 0 180)
			(layer "F.Fab")
			(effects
				(font
					(size 1.27 1.27)
				)
			)
		)
		(duplicate_pad_numbers_are_jumpers no)
		(fp_line
			(start 0.7874 0.4064)
			(end -0.7874 0.4064)
			(stroke
				(width 0.1524)
				(type default)
			)
			(layer "F.SilkS")
		)
		(fp_line
			(start 0.7874 -0.4064)
			(end 0.7874 0.4064)
			(stroke
				(width 0.1524)
				(type default)
			)
			(layer "F.SilkS")
		)
		(fp_line
			(start -0.7874 0.4064)
			(end -0.7874 -0.4064)
			(stroke
				(width 0.1524)
				(type default)
			)
			(layer "F.SilkS")
		)
		(fp_line
			(start -0.7874 -0.4064)
			(end 0.7874 -0.4064)
			(stroke
				(width 0.1524)
				(type default)
			)
			(layer "F.SilkS")
		)
		(fp_poly
			(pts
				(xy -0.508 0.2794) (xy -0.508 0.2286) (xy -0.635 0.2286) (xy -0.635 -0.254) (xy -0.5334 -0.254)
				(xy -0.5334 -0.2794) (xy 0.5334 -0.2794) (xy 0.5334 -0.254) (xy 0.635 -0.254) (xy 0.635 0.254) (xy 0.5334 0.254)
				(xy 0.5334 0.2794)
			)
			(stroke
				(width 0)
				(type default)
			)
			(fill no)
			(layer "F.CrtYd")
		)
		(pad "1" smd rect
			(at 0.40005 0 180)
			(size 0.4572 0.508)
			(layers "F.Cu" "F.Mask" "F.Paste")
			(net "PSU3_RETURN")
		)
		(pad "2" smd rect
			(at -0.40005 0 180)
			(size 0.4572 0.508)
			(layers "F.Cu" "F.Mask" "F.Paste")
			(net "GND")
		)
	)
	(footprint ""
		(layer "F.Cu")
		(at 74.798682 -15.447772 -90)
		(property "Reference" "C1"
			(at -2.757424 -0.074422 90)
			(unlocked yes)
			(layer "F.SilkS")
			(effects
				(font
					(size 0.7874 0.5842)
					(thickness 0.1524)
				)
			)
		)
		(property "Value" ""
			(at 0 0 270)
			(layer "F.Fab")
			(effects
				(font
					(size 1.27 1.27)
				)
			)
		)
		(duplicate_pad_numbers_are_jumpers no)
		(fp_line
			(start -1.2954 0.5842)
			(end -1.2954 -0.5842)
			(stroke
				(width 0.1524)
				(type default)
			)
			(layer "F.SilkS")
		)
		(fp_line
			(start 1.2954 0.5842)
			(end -1.2954 0.5842)
			(stroke
				(width 0.1524)
				(type default)
			)
			(layer "F.SilkS")
		)
		(fp_line
			(start -1.2954 -0.5842)
			(end 1.2954 -0.5842)
			(stroke
				(width 0.1524)
				(type default)
			)
			(layer "F.SilkS")
		)
		(fp_line
			(start 0 -0.5842)
			(end 0 0.5842)
			(stroke
				(width 0.1524)
				(type default)
			)
			(layer "F.SilkS")
		)
		(fp_line
			(start 1.2954 -0.5842)
			(end 1.2954 0.5842)
			(stroke
				(width 0.1524)
				(type default)
			)
			(layer "F.SilkS")
		)
		(fp_poly
			(pts
				(xy 0.8636 -0.4572) (xy 0.8636 -0.3556) (xy 1.143 -0.3556) (xy 1.143 0.3556) (xy 0.8636 0.3556)
				(xy 0.8636 0.4572) (xy -0.8636 0.4572) (xy -0.8636 0.3556) (xy -1.143 0.3556) (xy -1.143 -0.3556)
				(xy -0.8636 -0.3556) (xy -0.8636 -0.4572)
			)
			(stroke
				(width 0)
				(type default)
			)
			(fill no)
			(layer "F.CrtYd")
		)
		(fp_line
			(start -0.884936 0.504952)
			(end -0.884936 -0.504952)
			(stroke
				(width 0.1)
				(type default)
			)
			(layer "F.Fab")
		)
		(fp_line
			(start 0.884936 0.504952)
			(end -0.884936 0.504952)
			(stroke
				(width 0.1)
				(type default)
			)
			(layer "F.Fab")
		)
		(fp_line
			(start -0.884936 -0.504952)
			(end 0.884936 -0.504952)
			(stroke
				(width 0.1)
				(type default)
			)
			(layer "F.Fab")
		)
		(fp_line
			(start 0.884936 -0.504952)
			(end 0.884936 0.504952)
			(stroke
				(width 0.1)
				(type default)
			)
			(layer "F.Fab")
		)
		(pad "1" smd rect
			(at 0.7366 0)
			(size 0.7112 0.8128)
			(layers "F.Cu" "F.Mask" "F.Paste")
			(net "P12V")
		)
		(pad "2" smd rect
			(at -0.7366 0)
			(size 0.7112 0.8128)
			(layers "F.Cu" "F.Mask" "F.Paste")
			(net "GND")
		)
	)
	(footprint ""
		(layer "F.Cu")
		(at 25.874472 -367.771426 180)
		(property "Reference" "R53"
			(at 3.856228 0.385064 0)
			(unlocked yes)
			(layer "F.SilkS")
			(effects
				(font
					(size 0.7874 0.5842)
					(thickness 0.1524)
				)
				(justify left)
			)
		)
		(property "Value" ""
			(at 0 0 180)
			(layer "F.Fab")
			(effects
				(font
					(size 1.27 1.27)
				)
			)
		)
		(duplicate_pad_numbers_are_jumpers no)
		(fp_line
			(start 0.7874 0.4064)
			(end -0.7874 0.4064)
			(stroke
				(width 0.1524)
				(type default)
			)
			(layer "F.SilkS")
		)
		(fp_line
			(start 0.7874 -0.4064)
			(end 0.7874 0.4064)
			(stroke
				(width 0.1524)
				(type default)
			)
			(layer "F.SilkS")
		)
		(fp_line
			(start -0.7874 0.4064)
			(end -0.7874 -0.4064)
			(stroke
				(width 0.1524)
				(type default)
			)
			(layer "F.SilkS")
		)
		(fp_line
			(start -0.7874 -0.4064)
			(end 0.7874 -0.4064)
			(stroke
				(width 0.1524)
				(type default)
			)
			(layer "F.SilkS")
		)
		(fp_poly
			(pts
				(xy -0.508 0.2794) (xy -0.508 0.2286) (xy -0.635 0.2286) (xy -0.635 -0.254) (xy -0.5334 -0.254)
				(xy -0.5334 -0.2794) (xy 0.5334 -0.2794) (xy 0.5334 -0.254) (xy 0.635 -0.254) (xy 0.635 0.254) (xy 0.5334 0.254)
				(xy 0.5334 0.2794)
			)
			(stroke
				(width 0)
				(type default)
			)
			(fill no)
			(layer "F.CrtYd")
		)
		(pad "1" smd rect
			(at 0.40005 0 180)
			(size 0.4572 0.508)
			(layers "F.Cu" "F.Mask" "F.Paste")
			(net "GND")
		)
		(pad "2" smd rect
			(at -0.40005 0 180)
			(size 0.4572 0.508)
			(layers "F.Cu" "F.Mask" "F.Paste")
			(net "PSU5_PS_ON_N")
		)
	)
	(footprint ""
		(layer "B.Cu")
		(at 44.040044 -186.06008 90)
		(property "Reference" "J11"
			(at 6.252972 -4.579366 0)
			(unlocked yes)
			(layer "B.SilkS")
			(effects
				(font
					(size 0.7874 0.5842)
					(thickness 0.1524)
				)
				(justify left mirror)
			)
		)
		(property "Value" ""
			(at 0 0 90)
			(layer "B.Fab")
			(effects
				(font
					(size 1.27 1.27)
				)
				(justify mirror)
			)
		)
		(duplicate_pad_numbers_are_jumpers no)
		(fp_line
			(start 5.275072 -13.910056)
			(end -7.975092 -13.910056)
			(stroke
				(width 0.1524)
				(type default)
			)
			(layer "F.SilkS")
		)
		(fp_line
			(start -7.975092 -13.910056)
			(end -7.975092 62.170056)
			(stroke
				(width 0.1524)
				(type default)
			)
			(layer "F.SilkS")
		)
		(fp_line
			(start 5.275072 62.170056)
			(end 5.275072 -13.910056)
			(stroke
				(width 0.1524)
				(type default)
			)
			(layer "F.SilkS")
		)
		(fp_line
			(start -7.975092 62.170056)
			(end 5.275072 62.170056)
			(stroke
				(width 0.1524)
				(type default)
			)
			(layer "F.SilkS")
		)
		(fp_line
			(start 5.275072 -13.910056)
			(end -7.975092 -13.910056)
			(stroke
				(width 0.1524)
				(type default)
			)
			(layer "B.SilkS")
		)
		(fp_line
			(start -7.975092 -13.910056)
			(end -7.975092 62.170056)
			(stroke
				(width 0.1524)
				(type default)
			)
			(layer "B.SilkS")
		)
		(fp_line
			(start 2.275078 -10.910062)
			(end 2.275078 59.170062)
			(stroke
				(width 0.1524)
				(type default)
			)
			(layer "B.SilkS")
		)
		(fp_line
			(start -4.975098 -10.910062)
			(end 2.275078 -10.910062)
			(stroke
				(width 0.1524)
				(type default)
			)
			(layer "B.SilkS")
		)
		(fp_line
			(start 2.275078 59.170062)
			(end -4.975098 59.170062)
			(stroke
				(width 0.1524)
				(type default)
			)
			(layer "B.SilkS")
		)
		(fp_line
			(start -4.975098 59.170062)
			(end -4.975098 -10.910062)
			(stroke
				(width 0.1524)
				(type default)
			)
			(layer "B.SilkS")
		)
		(fp_line
			(start 5.275072 62.170056)
			(end 5.275072 -13.910056)
			(stroke
				(width 0.1524)
				(type default)
			)
			(layer "B.SilkS")
		)
		(fp_line
			(start -7.975092 62.170056)
			(end 5.275072 62.170056)
			(stroke
				(width 0.1524)
				(type default)
			)
			(layer "B.SilkS")
		)
		(fp_poly
			(pts
				(xy 4.103878 -0.759206) (xy 4.103878 0.764794) (xy 2.579878 0.002794)
			)
			(stroke
				(width 0)
				(type default)
			)
			(fill yes)
			(layer "B.SilkS")
		)
		(fp_poly
			(pts
				(xy 2.275078 -10.910062) (xy 2.275078 59.170062) (xy -4.975098 59.170062) (xy -4.975098 -10.910062)
			)
			(stroke
				(width 0)
				(type default)
			)
			(fill no)
			(layer "B.CrtYd")
		)
		(fp_poly
			(pts
				(xy 1.1938 40.9702) (xy 1.1938 48.6156) (xy -3.9116 48.6156) (xy -3.9116 40.9702) (xy -3.9116 40.9448)
				(xy 1.1938 40.9448)
			)
			(stroke
				(width 0)
				(type default)
			)
			(fill no)
			(layer "F.CrtYd")
		)
		(fp_poly
			(pts
				(xy -3.3274 -0.6604) (xy 0.635 -0.6604) (xy 0.635 38.735) (xy 0.635 38.7604) (xy -3.3274 38.7604)
				(xy -3.3528 38.7604) (xy -3.3528 -0.6604)
			)
			(stroke
				(width 0)
				(type default)
			)
			(fill no)
			(layer "F.CrtYd")
		)
		(fp_poly
			(pts
				(arc
					(start -1.35001 -1.01219)
					(mid -1.35001 -4.06781)
					(end -1.35001 -1.01219)
				)
			)
			(stroke
				(width 0)
				(type default)
			)
			(fill no)
			(layer "F.CrtYd")
		)
		(fp_poly
			(pts
				(arc
					(start 0 52.33162)
					(mid 0 49.26838)
					(end 0 52.33162)
				)
			)
			(stroke
				(width 0)
				(type default)
			)
			(fill no)
			(layer "F.CrtYd")
		)
		(fp_line
			(start 2.275078 -10.910062)
			(end 2.275078 59.170062)
			(stroke
				(width 0.1)
				(type default)
			)
			(layer "B.Fab")
		)
		(fp_line
			(start -4.975098 -10.910062)
			(end 2.275078 -10.910062)
			(stroke
				(width 0.1)
				(type default)
			)
			(layer "B.Fab")
		)
		(fp_line
			(start 2.275078 59.170062)
			(end -4.975098 59.170062)
			(stroke
				(width 0.1)
				(type default)
			)
			(layer "B.Fab")
		)
		(fp_line
			(start -4.975098 59.170062)
			(end -4.975098 -10.910062)
			(stroke
				(width 0.1)
				(type default)
			)
			(layer "B.Fab")
		)
		(fp_poly
			(pts
				(xy 4.103878 -0.759206) (xy 4.103878 0.764794) (xy 2.579878 0.002794)
			)
			(stroke
				(width 0)
				(type default)
			)
			(fill yes)
			(layer "B.Fab")
		)
		(fp_line
			(start 5.275072 -13.910056)
			(end -7.975092 -13.910056)
			(stroke
				(width 0.1)
				(type default)
			)
			(layer "F.Fab")
		)
		(fp_line
			(start -7.975092 -13.910056)
			(end -7.975092 62.170056)
			(stroke
				(width 0.1)
				(type default)
			)
			(layer "F.Fab")
		)
		(fp_line
			(start 5.275072 62.170056)
			(end 5.275072 -13.910056)
			(stroke
				(width 0.1)
				(type default)
			)
			(layer "F.Fab")
		)
		(fp_line
			(start -7.975092 62.170056)
			(end 5.275072 62.170056)
			(stroke
				(width 0.1)
				(type default)
			)
			(layer "F.Fab")
		)
		(fp_text user "P1"
			(at 1.568704 0.009906 0)
			(unlocked yes)
			(layer "F.SilkS")
			(effects
				(font
					(size 0.7874 0.5842)
					(thickness 0.1524)
				)
			)
		)
		(fp_text user "P32"
			(at -4.080002 0.018288 0)
			(unlocked yes)
			(layer "F.SilkS")
			(effects
				(font
					(size 0.7874 0.5842)
					(thickness 0.1524)
				)
			)
		)
		(fp_text user "PRESS-FIT"
			(at -9.227566 16.405098 0)
			(unlocked yes)
			(layer "F.SilkS")
			(effects
				(font
					(size 0.7874 0.5842)
					(thickness 0.1524)
				)
				(justify left)
			)
		)
		(fp_text user "P16"
			(at 6.213348 37.464238 0)
			(unlocked yes)
			(layer "F.SilkS")
			(effects
				(font
					(size 0.7874 0.5842)
					(thickness 0.1524)
				)
			)
		)
		(fp_text user "P17"
			(at -9.541764 37.899848 0)
			(unlocked yes)
			(layer "F.SilkS")
			(effects
				(font
					(size 0.7874 0.5842)
					(thickness 0.1524)
				)
			)
		)
		(fp_text user "S12"
			(at -8.851392 40.402764 0)
			(unlocked yes)
			(layer "F.SilkS")
			(effects
				(font
					(size 0.7874 0.5842)
					(thickness 0.1524)
				)
			)
		)
		(fp_text user "S1"
			(at 6.246876 41.875456 0)
			(unlocked yes)
			(layer "F.SilkS")
			(effects
				(font
					(size 0.7874 0.5842)
					(thickness 0.1524)
				)
			)
		)
		(fp_text user "S6"
			(at 6.012942 47.5234 0)
			(unlocked yes)
			(layer "F.SilkS")
			(effects
				(font
					(size 0.7874 0.5842)
					(thickness 0.1524)
				)
			)
		)
		(fp_text user "S7"
			(at -9.227566 49.996344 0)
			(unlocked yes)
			(layer "F.SilkS")
			(effects
				(font
					(size 0.7874 0.5842)
					(thickness 0.1524)
				)
			)
		)
		(fp_text user "P1"
			(at 2.944368 -1.463802 0)
			(unlocked yes)
			(layer "B.SilkS")
			(effects
				(font
					(size 0.7874 0.5842)
					(thickness 0.1524)
				)
				(justify mirror)
			)
		)
		(fp_text user "P32"
			(at -5.975604 -0.435356 0)
			(unlocked yes)
			(layer "B.SilkS")
			(effects
				(font
					(size 0.7874 0.5842)
					(thickness 0.1524)
				)
				(justify mirror)
			)
		)
		(fp_text user "PRESS-FIT"
			(at -7.18947 29.8831 0)
			(unlocked yes)
			(layer "B.SilkS")
			(effects
				(font
					(size 0.7874 0.5842)
					(thickness 0.1524)
				)
				(justify left mirror)
			)
		)
		(fp_text user "P17"
			(at -5.899658 37.6174 0)
			(unlocked yes)
			(layer "B.SilkS")
			(effects
				(font
					(size 0.7874 0.5842)
					(thickness 0.1524)
				)
				(justify mirror)
			)
		)
		(fp_text user "P16"
			(at 3.13182 37.89172 0)
			(unlocked yes)
			(layer "B.SilkS")
			(effects
				(font
					(size 0.7874 0.5842)
					(thickness 0.1524)
				)
				(justify mirror)
			)
		)
		(fp_text user "S1"
			(at 3.024632 41.766236 0)
			(unlocked yes)
			(layer "B.SilkS")
			(effects
				(font
					(size 0.7874 0.5842)
					(thickness 0.1524)
				)
				(justify mirror)
			)
		)
		(fp_text user "S12"
			(at -5.827268 42.067988 0)
			(unlocked yes)
			(layer "B.SilkS")
			(effects
				(font
					(size 0.7874 0.5842)
					(thickness 0.1524)
				)
				(justify mirror)
			)
		)
		(fp_text user "S6"
			(at 3.123438 47.701454 0)
			(unlocked yes)
			(layer "B.SilkS")
			(effects
				(font
					(size 0.7874 0.5842)
					(thickness 0.1524)
				)
				(justify mirror)
			)
		)
		(fp_text user "S7"
			(at -5.907532 47.803816 0)
			(unlocked yes)
			(layer "B.SilkS")
			(effects
				(font
					(size 0.7874 0.5842)
					(thickness 0.1524)
				)
				(justify mirror)
			)
		)
		(fp_text user "P1"
			(at 3.108452 -1.27 180)
			(unlocked yes)
			(layer "B.Fab")
			(effects
				(font
					(size 0.7874 0.5842)
					(thickness 0.000001)
				)
				(justify mirror)
			)
		)
		(fp_text user "P32"
			(at -5.781548 -0.0508 180)
			(unlocked yes)
			(layer "B.Fab")
			(effects
				(font
					(size 0.7874 0.5842)
					(thickness 0.000001)
				)
				(justify mirror)
			)
		)
		(fp_text user "PRESS-FIT"
			(at -6.82371 29.8831 0)
			(unlocked yes)
			(layer "B.Fab")
			(effects
				(font
					(size 1.6002 1.1938)
					(thickness 0.000001)
				)
				(justify left mirror)
			)
		)
		(fp_text user "P17"
			(at -5.72135 38.0746 180)
			(unlocked yes)
			(layer "B.Fab")
			(effects
				(font
					(size 0.7874 0.5842)
					(thickness 0.000001)
				)
				(justify mirror)
			)
		)
		(fp_text user "P16"
			(at 3.159252 38.3794 180)
			(unlocked yes)
			(layer "B.Fab")
			(effects
				(font
					(size 0.7874 0.5842)
					(thickness 0.000001)
				)
				(justify mirror)
			)
		)
		(fp_text user "S12"
			(at -5.79374 41.42232 180)
			(unlocked yes)
			(layer "B.Fab")
			(effects
				(font
					(size 0.7874 0.5842)
					(thickness 0.000001)
				)
				(justify mirror)
			)
		)
		(fp_text user "S1"
			(at 3.09626 41.656 180)
			(unlocked yes)
			(layer "B.Fab")
			(effects
				(font
					(size 0.7874 0.5842)
					(thickness 0.000001)
				)
				(justify mirror)
			)
		)
		(fp_text user "S6"
			(at 3.133852 48.0822 180)
			(unlocked yes)
			(layer "B.Fab")
			(effects
				(font
					(size 0.7874 0.5842)
					(thickness 0.000001)
				)
				(justify mirror)
			)
		)
		(fp_text user "S7"
			(at -5.781548 48.0822 180)
			(unlocked yes)
			(layer "B.Fab")
			(effects
				(font
					(size 0.7874 0.5842)
					(thickness 0.000001)
				)
				(justify mirror)
			)
		)
		(fp_text user "P32"
			(at -4.071112 -0.0762 180)
			(unlocked yes)
			(layer "F.Fab")
			(effects
				(font
					(size 0.7874 0.5842)
					(thickness 0.000001)
				)
			)
		)
		(fp_text user "P1"
			(at 1.516888 0 180)
			(unlocked yes)
			(layer "F.Fab")
			(effects
				(font
					(size 0.7874 0.5842)
					(thickness 0.000001)
				)
			)
		)
		(fp_text user "PRESS-FIT"
			(at -6.762496 16.251428 0)
			(unlocked yes)
			(layer "F.Fab")
			(effects
				(font
					(size 1.6002 1.1938)
					(thickness 0.000001)
				)
				(justify left)
			)
		)
		(fp_text user "P17"
			(at -4.366768 38.227 180)
			(unlocked yes)
			(layer "F.Fab")
			(effects
				(font
					(size 0.7874 0.5842)
					(thickness 0.000001)
				)
			)
		)
		(fp_text user "P16"
			(at 2.228088 38.354 180)
			(unlocked yes)
			(layer "F.Fab")
			(effects
				(font
					(size 0.7874 0.5842)
					(thickness 0.000001)
				)
			)
		)
		(fp_text user "S12"
			(at -4.362958 41.09212 180)
			(unlocked yes)
			(layer "F.Fab")
			(effects
				(font
					(size 0.7874 0.5842)
					(thickness 0.000001)
				)
			)
		)
		(fp_text user "S1"
			(at 2.164842 41.6306 180)
			(unlocked yes)
			(layer "F.Fab")
			(effects
				(font
					(size 0.7874 0.5842)
					(thickness 0.000001)
				)
			)
		)
		(fp_text user "S6"
			(at 1.923288 48.133 180)
			(unlocked yes)
			(layer "F.Fab")
			(effects
				(font
					(size 0.7874 0.5842)
					(thickness 0.000001)
				)
			)
		)
		(fp_text user "S7"
			(at -4.426712 48.2346 180)
			(unlocked yes)
			(layer "F.Fab")
			(effects
				(font
					(size 0.7874 0.5842)
					(thickness 0.000001)
				)
			)
		)
		(pad "" np_thru_hole circle
			(at -1.35001 -2.54)
			(size 2.5146 2.5146)
			(drill 2.5146)
			(layers "*.Cu" "*.Mask")
			(clearance 0.381)
			(thermal_gap 0.381)
		)
		(pad "" np_thru_hole circle
			(at 0 50.8)
			(size 2.5146 2.5146)
			(drill 2.5146)
			(layers "*.Cu" "*.Mask")
			(clearance 0.381)
			(thermal_gap 0.381)
		)
		(pad "P1" thru_hole rect
			(at 0 0)
			(size 1.1684 1.1684)
			(drill 0.762)
			(layers "*.Cu" "*.Mask")
			(remove_unused_layers no)
			(net "GND")
			(clearance 0.0508)
			(padstack
				(mode front_inner_back)
				(layer "Inner"
					(shape circle)
					(size 1.1684 1.1684)
					(clearance 0.0508)
				)
				(layer "B.Cu"
					(shape rect)
					(size 1.1684 1.1684)
					(thermal_gap 0.0508)
					(clearance 0.0508)
				)
			)
		)
		(pad "P2" thru_hole circle
			(at 0 2.54)
			(size 1.1684 1.1684)
			(drill 0.762)
			(layers "*.Cu" "*.Mask")
			(remove_unused_layers no)
			(net "GND")
			(clearance 0.0508)
			(thermal_gap 0.0508)
		)
		(pad "P3" thru_hole circle
			(at 0 5.08)
			(size 1.1684 1.1684)
			(drill 0.762)
			(layers "*.Cu" "*.Mask")
			(remove_unused_layers no)
			(net "GND")
			(clearance 0.0508)
			(thermal_gap 0.0508)
		)
		(pad "P4" thru_hole circle
			(at 0 7.62)
			(size 1.1684 1.1684)
			(drill 0.762)
			(layers "*.Cu" "*.Mask")
			(remove_unused_layers no)
			(net "GND")
			(clearance 0.0508)
			(thermal_gap 0.0508)
		)
		(pad "P5" thru_hole circle
			(at 0 10.16)
			(size 1.1684 1.1684)
			(drill 0.762)
			(layers "*.Cu" "*.Mask")
			(remove_unused_layers no)
			(net "GND")
			(clearance 0.0508)
			(thermal_gap 0.0508)
		)
		(pad "P6" thru_hole circle
			(at 0 12.7)
			(size 1.1684 1.1684)
			(drill 0.762)
			(layers "*.Cu" "*.Mask")
			(remove_unused_layers no)
			(net "GND")
			(clearance 0.0508)
			(thermal_gap 0.0508)
		)
		(pad "P7" thru_hole circle
			(at 0 15.24)
			(size 1.1684 1.1684)
			(drill 0.762)
			(layers "*.Cu" "*.Mask")
			(remove_unused_layers no)
			(net "GND")
			(clearance 0.0508)
			(thermal_gap 0.0508)
		)
		(pad "P8" thru_hole circle
			(at 0 17.78)
			(size 1.1684 1.1684)
			(drill 0.762)
			(layers "*.Cu" "*.Mask")
			(remove_unused_layers no)
			(net "GND")
			(clearance 0.0508)
			(thermal_gap 0.0508)
		)
		(pad "P9" thru_hole circle
			(at 0 20.32)
			(size 1.1684 1.1684)
			(drill 0.762)
			(layers "*.Cu" "*.Mask")
			(remove_unused_layers no)
			(net "P12V")
			(clearance 0.0508)
			(thermal_gap 0.0508)
		)
		(pad "P10" thru_hole circle
			(at 0 22.86)
			(size 1.1684 1.1684)
			(drill 0.762)
			(layers "*.Cu" "*.Mask")
			(remove_unused_layers no)
			(net "P12V")
			(clearance 0.0508)
			(thermal_gap 0.0508)
		)
		(pad "P11" thru_hole circle
			(at 0 25.4)
			(size 1.1684 1.1684)
			(drill 0.762)
			(layers "*.Cu" "*.Mask")
			(remove_unused_layers no)
			(net "P12V")
			(clearance 0.0508)
			(thermal_gap 0.0508)
		)
		(pad "P12" thru_hole circle
			(at 0 27.94)
			(size 1.1684 1.1684)
			(drill 0.762)
			(layers "*.Cu" "*.Mask")
			(remove_unused_layers no)
			(net "P12V")
			(clearance 0.0508)
			(thermal_gap 0.0508)
		)
		(pad "P13" thru_hole circle
			(at 0 30.48)
			(size 1.1684 1.1684)
			(drill 0.762)
			(layers "*.Cu" "*.Mask")
			(remove_unused_layers no)
			(net "P12V")
			(clearance 0.0508)
			(thermal_gap 0.0508)
		)
		(pad "P14" thru_hole circle
			(at 0 33.02)
			(size 1.1684 1.1684)
			(drill 0.762)
			(layers "*.Cu" "*.Mask")
			(remove_unused_layers no)
			(net "P12V")
			(clearance 0.0508)
			(thermal_gap 0.0508)
		)
		(pad "P15" thru_hole circle
			(at 0 35.56)
			(size 1.1684 1.1684)
			(drill 0.762)
			(layers "*.Cu" "*.Mask")
			(remove_unused_layers no)
			(net "P12V")
			(clearance 0.0508)
			(thermal_gap 0.0508)
		)
		(pad "P16" thru_hole circle
			(at 0 38.1)
			(size 1.1684 1.1684)
			(drill 0.762)
			(layers "*.Cu" "*.Mask")
			(remove_unused_layers no)
			(net "P12V")
			(clearance 0.0508)
			(thermal_gap 0.0508)
		)
		(pad "P17" thru_hole circle
			(at -2.70002 38.1)
			(size 1.1684 1.1684)
			(drill 0.762)
			(layers "*.Cu" "*.Mask")
			(remove_unused_layers no)
			(net "P12V")
			(clearance 0.0508)
			(thermal_gap 0.0508)
		)
		(pad "P18" thru_hole circle
			(at -2.70002 35.56)
			(size 1.1684 1.1684)
			(drill 0.762)
			(layers "*.Cu" "*.Mask")
			(remove_unused_layers no)
			(net "P12V")
			(clearance 0.0508)
			(thermal_gap 0.0508)
		)
		(pad "P19" thru_hole circle
			(at -2.70002 33.02)
			(size 1.1684 1.1684)
			(drill 0.762)
			(layers "*.Cu" "*.Mask")
			(remove_unused_layers no)
			(net "P12V")
			(clearance 0.0508)
			(thermal_gap 0.0508)
		)
		(pad "P20" thru_hole circle
			(at -2.70002 30.48)
			(size 1.1684 1.1684)
			(drill 0.762)
			(layers "*.Cu" "*.Mask")
			(remove_unused_layers no)
			(net "P12V")
			(clearance 0.0508)
			(thermal_gap 0.0508)
		)
		(pad "P21" thru_hole circle
			(at -2.70002 27.94)
			(size 1.1684 1.1684)
			(drill 0.762)
			(layers "*.Cu" "*.Mask")
			(remove_unused_layers no)
			(net "P12V")
			(clearance 0.0508)
			(thermal_gap 0.0508)
		)
		(pad "P22" thru_hole circle
			(at -2.70002 25.4)
			(size 1.1684 1.1684)
			(drill 0.762)
			(layers "*.Cu" "*.Mask")
			(remove_unused_layers no)
			(net "P12V")
			(clearance 0.0508)
			(thermal_gap 0.0508)
		)
		(pad "P23" thru_hole circle
			(at -2.70002 22.86)
			(size 1.1684 1.1684)
			(drill 0.762)
			(layers "*.Cu" "*.Mask")
			(remove_unused_layers no)
			(net "P12V")
			(clearance 0.0508)
			(thermal_gap 0.0508)
		)
		(pad "P24" thru_hole circle
			(at -2.70002 20.32)
			(size 1.1684 1.1684)
			(drill 0.762)
			(layers "*.Cu" "*.Mask")
			(remove_unused_layers no)
			(net "P12V")
			(clearance 0.0508)
			(thermal_gap 0.0508)
		)
		(pad "P25" thru_hole circle
			(at -2.70002 17.78)
			(size 1.1684 1.1684)
			(drill 0.762)
			(layers "*.Cu" "*.Mask")
			(remove_unused_layers no)
			(net "GND")
			(clearance 0.0508)
			(thermal_gap 0.0508)
		)
		(pad "P26" thru_hole circle
			(at -2.70002 15.24)
			(size 1.1684 1.1684)
			(drill 0.762)
			(layers "*.Cu" "*.Mask")
			(remove_unused_layers no)
			(net "GND")
			(clearance 0.0508)
			(thermal_gap 0.0508)
		)
		(pad "P27" thru_hole circle
			(at -2.70002 12.7)
			(size 1.1684 1.1684)
			(drill 0.762)
			(layers "*.Cu" "*.Mask")
			(remove_unused_layers no)
			(net "GND")
			(clearance 0.0508)
			(thermal_gap 0.0508)
		)
		(pad "P28" thru_hole circle
			(at -2.70002 10.16)
			(size 1.1684 1.1684)
			(drill 0.762)
			(layers "*.Cu" "*.Mask")
			(remove_unused_layers no)
			(net "GND")
			(clearance 0.0508)
			(thermal_gap 0.0508)
		)
		(pad "P29" thru_hole circle
			(at -2.70002 7.62)
			(size 1.1684 1.1684)
			(drill 0.762)
			(layers "*.Cu" "*.Mask")
			(remove_unused_layers no)
			(net "GND")
			(clearance 0.0508)
			(thermal_gap 0.0508)
		)
		(pad "P30" thru_hole circle
			(at -2.70002 5.08)
			(size 1.1684 1.1684)
			(drill 0.762)
			(layers "*.Cu" "*.Mask")
			(remove_unused_layers no)
			(net "GND")
			(clearance 0.0508)
			(thermal_gap 0.0508)
		)
		(pad "P31" thru_hole circle
			(at -2.70002 2.54)
			(size 1.1684 1.1684)
			(drill 0.762)
			(layers "*.Cu" "*.Mask")
			(remove_unused_layers no)
			(net "GND")
			(clearance 0.0508)
			(thermal_gap 0.0508)
		)
		(pad "P32" thru_hole circle
			(at -2.70002 0)
			(size 1.1684 1.1684)
			(drill 0.762)
			(layers "*.Cu" "*.Mask")
			(remove_unused_layers no)
			(net "GND")
			(clearance 0.0508)
			(thermal_gap 0.0508)
		)
		(pad "S1" thru_hole circle
			(at 0.55499 41.60012)
			(size 1.1684 1.1684)
			(drill 0.762)
			(layers "*.Cu" "*.Mask")
			(remove_unused_layers no)
			(net "T5_BLAD1_TXD")
			(clearance 0.0508)
			(thermal_gap 0.0508)
		)
		(pad "S2" thru_hole circle
			(at -0.71501 42.87012)
			(size 1.1684 1.1684)
			(drill 0.762)
			(layers "*.Cu" "*.Mask")
			(remove_unused_layers no)
			(net "T5_BLAD1_RXD")
			(clearance 0.0508)
			(thermal_gap 0.0508)
		)
		(pad "S3" thru_hole circle
			(at 0.55499 44.14012)
			(size 1.1684 1.1684)
			(drill 0.762)
			(layers "*.Cu" "*.Mask")
			(remove_unused_layers no)
			(net "T5_BLAD1_EN")
			(clearance 0.0508)
			(thermal_gap 0.0508)
		)
		(pad "S4" thru_hole circle
			(at -0.71501 45.41012)
			(size 1.1684 1.1684)
			(drill 0.762)
			(layers "*.Cu" "*.Mask")
			(remove_unused_layers no)
			(net "T5_BLAD2_EN")
			(clearance 0.0508)
			(thermal_gap 0.0508)
		)
		(pad "S5" thru_hole circle
			(at 0.55499 46.68012)
			(size 1.1684 1.1684)
			(drill 0.762)
			(layers "*.Cu" "*.Mask")
			(remove_unused_layers no)
			(net "T5_BLAD2_TXD")
			(clearance 0.0508)
			(thermal_gap 0.0508)
		)
		(pad "S6" thru_hole circle
			(at -0.71501 47.95012)
			(size 1.1684 1.1684)
			(drill 0.762)
			(layers "*.Cu" "*.Mask")
			(remove_unused_layers no)
			(net "T5_BLAD2_RXD")
			(clearance 0.0508)
			(thermal_gap 0.0508)
		)
		(pad "S7" thru_hole circle
			(at -3.25501 47.95012)
			(size 1.1684 1.1684)
			(drill 0.762)
			(layers "*.Cu" "*.Mask")
			(remove_unused_layers no)
			(net "T5_BLAD4_RXD")
			(clearance 0.0508)
			(thermal_gap 0.0508)
		)
		(pad "S8" thru_hole circle
			(at -1.98501 46.68012)
			(size 1.1684 1.1684)
			(drill 0.762)
			(layers "*.Cu" "*.Mask")
			(remove_unused_layers no)
			(net "T5_BLAD4_TXD")
			(clearance 0.0508)
			(thermal_gap 0.0508)
		)
		(pad "S9" thru_hole circle
			(at -3.25501 45.41012)
			(size 1.1684 1.1684)
			(drill 0.762)
			(layers "*.Cu" "*.Mask")
			(remove_unused_layers no)
			(net "T5_BLAD4_EN")
			(clearance 0.0508)
			(thermal_gap 0.0508)
		)
		(pad "S10" thru_hole circle
			(at -1.98501 44.14012)
			(size 1.1684 1.1684)
			(drill 0.762)
			(layers "*.Cu" "*.Mask")
			(remove_unused_layers no)
			(net "T5_BLAD3_EN")
			(clearance 0.0508)
			(thermal_gap 0.0508)
		)
		(pad "S11" thru_hole circle
			(at -3.25501 42.87012)
			(size 1.1684 1.1684)
			(drill 0.762)
			(layers "*.Cu" "*.Mask")
			(remove_unused_layers no)
			(net "T5_BLAD3_RXD")
			(clearance 0.0508)
			(thermal_gap 0.0508)
		)
		(pad "S12" thru_hole circle
			(at -1.98501 41.60012)
			(size 1.1684 1.1684)
			(drill 0.762)
			(layers "*.Cu" "*.Mask")
			(remove_unused_layers no)
			(net "T5_BLAD3_TXD")
			(clearance 0.0508)
			(thermal_gap 0.0508)
		)
		(zone
			(layer "F.Cu")
			(hatch none 0.5)
			(connect_pads
				(clearance 0)
			)
			(min_thickness 0.25)
			(keepout
				(tracks allowed)
				(vias not_allowed)
				(pads allowed)
				(copperpour not_allowed)
				(footprints allowed)
			)
			(placement
				(enabled no)
				(sheetname "")
			)
			(fill
				(thermal_gap 0.5)
				(thermal_bridge_width 0.5)
				(island_removal_mode 0)
			)
			(polygon
				(pts
					(xy 85.010244 -187.25388) (xy 92.655644 -187.25388) (xy 92.655644 -182.14848) (xy 85.010244 -182.14848)
					(xy 84.984844 -182.14848) (xy 84.984844 -187.25388)
				)
			)
		)
		(zone
			(layer "F.Cu")
			(hatch none 0.5)
			(connect_pads
				(clearance 0)
			)
			(min_thickness 0.25)
			(keepout
				(tracks allowed)
				(vias not_allowed)
				(pads allowed)
				(copperpour not_allowed)
				(footprints allowed)
			)
			(placement
				(enabled no)
				(sheetname "")
			)
			(fill
				(thermal_gap 0.5)
				(thermal_bridge_width 0.5)
				(island_removal_mode 0)
			)
			(polygon
				(pts
					(xy 43.379644 -182.73268) (xy 43.379644 -186.69508) (xy 82.775044 -186.69508) (xy 82.800444 -186.69508)
					(xy 82.800444 -182.73268) (xy 82.800444 -182.70728) (xy 43.379644 -182.70728)
				)
			)
		)
		(zone
			(layers "F.Cu" "B.Cu" "In1.Cu" "In2.Cu" "In3.Cu" "In4.Cu" "In5.Cu" "In6.Cu")
			(hatch none 0.5)
			(connect_pads
				(clearance 0)
			)
			(min_thickness 0.25)
			(keepout
				(tracks not_allowed)
				(vias allowed)
				(pads allowed)
				(copperpour not_allowed)
				(footprints allowed)
			)
			(placement
				(enabled no)
				(sheetname "")
			)
			(fill
				(thermal_gap 0.5)
				(thermal_bridge_width 0.5)
				(island_removal_mode 0)
			)
			(polygon
				(pts
					(arc
						(start 43.180254 -184.71007)
						(mid 39.819834 -184.71007)
						(end 43.180254 -184.71007)
					)
				)
			)
		)
		(zone
			(layers "F.Cu" "B.Cu" "In1.Cu" "In2.Cu" "In3.Cu" "In4.Cu" "In5.Cu" "In6.Cu")
			(hatch none 0.5)
			(connect_pads
				(clearance 0)
			)
			(min_thickness 0.25)
			(keepout
				(tracks not_allowed)
				(vias allowed)
				(pads allowed)
				(copperpour not_allowed)
				(footprints allowed)
			)
			(placement
				(enabled no)
				(sheetname "")
			)
			(fill
				(thermal_gap 0.5)
				(thermal_bridge_width 0.5)
				(island_removal_mode 0)
			)
			(polygon
				(pts
					(arc
						(start 96.524064 -186.06008)
						(mid 93.156024 -186.06008)
						(end 96.524064 -186.06008)
					)
				)
			)
		)
	)
	(footprint ""
		(layer "B.Cu")
		(at 44.03979 -230.51008 90)
		(property "Reference" "J12"
			(at 6.153658 -3.773932 0)
			(unlocked yes)
			(layer "B.SilkS")
			(effects
				(font
					(size 0.7874 0.5842)
					(thickness 0.1524)
				)
				(justify left mirror)
			)
		)
		(property "Value" ""
			(at 0 0 90)
			(layer "B.Fab")
			(effects
				(font
					(size 1.27 1.27)
				)
				(justify mirror)
			)
		)
		(duplicate_pad_numbers_are_jumpers no)
		(fp_line
			(start 5.275072 -13.910056)
			(end -7.975092 -13.910056)
			(stroke
				(width 0.1524)
				(type default)
			)
			(layer "F.SilkS")
		)
		(fp_line
			(start -7.975092 -13.910056)
			(end -7.975092 62.170056)
			(stroke
				(width 0.1524)
				(type default)
			)
			(layer "F.SilkS")
		)
		(fp_line
			(start 5.275072 62.170056)
			(end 5.275072 -13.910056)
			(stroke
				(width 0.1524)
				(type default)
			)
			(layer "F.SilkS")
		)
		(fp_line
			(start -7.975092 62.170056)
			(end 5.275072 62.170056)
			(stroke
				(width 0.1524)
				(type default)
			)
			(layer "F.SilkS")
		)
		(fp_line
			(start 5.275072 -13.910056)
			(end -7.975092 -13.910056)
			(stroke
				(width 0.1524)
				(type default)
			)
			(layer "B.SilkS")
		)
		(fp_line
			(start -7.975092 -13.910056)
			(end -7.975092 62.170056)
			(stroke
				(width 0.1524)
				(type default)
			)
			(layer "B.SilkS")
		)
		(fp_line
			(start 2.275078 -10.910062)
			(end 2.275078 59.170062)
			(stroke
				(width 0.1524)
				(type default)
			)
			(layer "B.SilkS")
		)
		(fp_line
			(start -4.975098 -10.910062)
			(end 2.275078 -10.910062)
			(stroke
				(width 0.1524)
				(type default)
			)
			(layer "B.SilkS")
		)
		(fp_line
			(start 2.275078 59.170062)
			(end -4.975098 59.170062)
			(stroke
				(width 0.1524)
				(type default)
			)
			(layer "B.SilkS")
		)
		(fp_line
			(start -4.975098 59.170062)
			(end -4.975098 -10.910062)
			(stroke
				(width 0.1524)
				(type default)
			)
			(layer "B.SilkS")
		)
		(fp_line
			(start 5.275072 62.170056)
			(end 5.275072 -13.910056)
			(stroke
				(width 0.1524)
				(type default)
			)
			(layer "B.SilkS")
		)
		(fp_line
			(start -7.975092 62.170056)
			(end 5.275072 62.170056)
			(stroke
				(width 0.1524)
				(type default)
			)
			(layer "B.SilkS")
		)
		(fp_poly
			(pts
				(xy 4.103878 -0.759206) (xy 4.103878 0.764794) (xy 2.579878 0.002794)
			)
			(stroke
				(width 0)
				(type default)
			)
			(fill yes)
			(layer "B.SilkS")
		)
		(fp_poly
			(pts
				(xy 2.275078 -10.910062) (xy 2.275078 59.170062) (xy -4.975098 59.170062) (xy -4.975098 -10.910062)
			)
			(stroke
				(width 0)
				(type default)
			)
			(fill no)
			(layer "B.CrtYd")
		)
		(fp_poly
			(pts
				(xy 1.1938 40.9702) (xy 1.1938 48.6156) (xy -3.9116 48.6156) (xy -3.9116 40.9702) (xy -3.9116 40.9448)
				(xy 1.1938 40.9448)
			)
			(stroke
				(width 0)
				(type default)
			)
			(fill no)
			(layer "F.CrtYd")
		)
		(fp_poly
			(pts
				(xy -3.3274 -0.6604) (xy 0.635 -0.6604) (xy 0.635 38.735) (xy 0.635 38.7604) (xy -3.3274 38.7604)
				(xy -3.3528 38.7604) (xy -3.3528 -0.6604)
			)
			(stroke
				(width 0)
				(type default)
			)
			(fill no)
			(layer "F.CrtYd")
		)
		(fp_poly
			(pts
				(arc
					(start -1.35001 -1.01219)
					(mid -1.35001 -4.06781)
					(end -1.35001 -1.01219)
				)
			)
			(stroke
				(width 0)
				(type default)
			)
			(fill no)
			(layer "F.CrtYd")
		)
		(fp_poly
			(pts
				(arc
					(start 0 52.33162)
					(mid 0 49.26838)
					(end 0 52.33162)
				)
			)
			(stroke
				(width 0)
				(type default)
			)
			(fill no)
			(layer "F.CrtYd")
		)
		(fp_line
			(start 2.275078 -10.910062)
			(end 2.275078 59.170062)
			(stroke
				(width 0.1)
				(type default)
			)
			(layer "B.Fab")
		)
		(fp_line
			(start -4.975098 -10.910062)
			(end 2.275078 -10.910062)
			(stroke
				(width 0.1)
				(type default)
			)
			(layer "B.Fab")
		)
		(fp_line
			(start 2.275078 59.170062)
			(end -4.975098 59.170062)
			(stroke
				(width 0.1)
				(type default)
			)
			(layer "B.Fab")
		)
		(fp_line
			(start -4.975098 59.170062)
			(end -4.975098 -10.910062)
			(stroke
				(width 0.1)
				(type default)
			)
			(layer "B.Fab")
		)
		(fp_poly
			(pts
				(xy 4.103878 -0.759206) (xy 4.103878 0.764794) (xy 2.579878 0.002794)
			)
			(stroke
				(width 0)
				(type default)
			)
			(fill yes)
			(layer "B.Fab")
		)
		(fp_line
			(start 5.275072 -13.910056)
			(end -7.975092 -13.910056)
			(stroke
				(width 0.1)
				(type default)
			)
			(layer "F.Fab")
		)
		(fp_line
			(start -7.975092 -13.910056)
			(end -7.975092 62.170056)
			(stroke
				(width 0.1)
				(type default)
			)
			(layer "F.Fab")
		)
		(fp_line
			(start 5.275072 62.170056)
			(end 5.275072 -13.910056)
			(stroke
				(width 0.1)
				(type default)
			)
			(layer "F.Fab")
		)
		(fp_line
			(start -7.975092 62.170056)
			(end 5.275072 62.170056)
			(stroke
				(width 0.1)
				(type default)
			)
			(layer "F.Fab")
		)
		(fp_text user "P32"
			(at -8.861298 -0.466344 0)
			(unlocked yes)
			(layer "F.SilkS")
			(effects
				(font
					(size 0.7874 0.5842)
					(thickness 0.1524)
				)
			)
		)
		(fp_text user "P1"
			(at 6.37794 -0.065278 0)
			(unlocked yes)
			(layer "F.SilkS")
			(effects
				(font
					(size 0.7874 0.5842)
					(thickness 0.1524)
				)
			)
		)
		(fp_text user "PRESS-FIT"
			(at -9.734296 11.81989 0)
			(unlocked yes)
			(layer "F.SilkS")
			(effects
				(font
					(size 0.7874 0.5842)
					(thickness 0.1524)
				)
				(justify left)
			)
		)
		(fp_text user "P16"
			(at 6.310884 36.695888 0)
			(unlocked yes)
			(layer "F.SilkS")
			(effects
				(font
					(size 0.7874 0.5842)
					(thickness 0.1524)
				)
			)
		)
		(fp_text user "P17"
			(at -8.967216 37.91077 0)
			(unlocked yes)
			(layer "F.SilkS")
			(effects
				(font
					(size 0.7874 0.5842)
					(thickness 0.1524)
				)
			)
		)
		(fp_text user "S12"
			(at -9.073388 41.345104 0)
			(unlocked yes)
			(layer "F.SilkS")
			(effects
				(font
					(size 0.7874 0.5842)
					(thickness 0.1524)
				)
			)
		)
		(fp_text user "S1"
			(at 6.17728 41.508172 0)
			(unlocked yes)
			(layer "F.SilkS")
			(effects
				(font
					(size 0.7874 0.5842)
					(thickness 0.1524)
				)
			)
		)
		(fp_text user "S7"
			(at -9.281922 47.823374 0)
			(unlocked yes)
			(layer "F.SilkS")
			(effects
				(font
					(size 0.7874 0.5842)
					(thickness 0.1524)
				)
			)
		)
		(fp_text user "S6"
			(at 6.043676 48.258984 0)
			(unlocked yes)
			(layer "F.SilkS")
			(effects
				(font
					(size 0.7874 0.5842)
					(thickness 0.1524)
				)
			)
		)
		(fp_text user "P1"
			(at 3.060954 -1.497584 0)
			(unlocked yes)
			(layer "B.SilkS")
			(effects
				(font
					(size 0.7874 0.5842)
					(thickness 0.1524)
				)
				(justify mirror)
			)
		)
		(fp_text user "P32"
			(at -5.927344 0.109474 0)
			(unlocked yes)
			(layer "B.SilkS")
			(effects
				(font
					(size 0.7874 0.5842)
					(thickness 0.1524)
				)
				(justify mirror)
			)
		)
		(fp_text user "PRESS-FIT"
			(at -6.743192 17.254474 0)
			(unlocked yes)
			(layer "B.SilkS")
			(effects
				(font
					(size 0.7874 0.5842)
					(thickness 0.1524)
				)
				(justify left mirror)
			)
		)
		(fp_text user "P17"
			(at -5.677916 37.79774 0)
			(unlocked yes)
			(layer "B.SilkS")
			(effects
				(font
					(size 0.7874 0.5842)
					(thickness 0.1524)
				)
				(justify mirror)
			)
		)
		(fp_text user "P16"
			(at 2.911094 37.867336 0)
			(unlocked yes)
			(layer "B.SilkS")
			(effects
				(font
					(size 0.7874 0.5842)
					(thickness 0.1524)
				)
				(justify mirror)
			)
		)
		(fp_text user "S1"
			(at 2.94005 41.810178 0)
			(unlocked yes)
			(layer "B.SilkS")
			(effects
				(font
					(size 0.7874 0.5842)
					(thickness 0.1524)
				)
				(justify mirror)
			)
		)
		(fp_text user "S12"
			(at -5.724652 41.924732 0)
			(unlocked yes)
			(layer "B.SilkS")
			(effects
				(font
					(size 0.7874 0.5842)
					(thickness 0.1524)
				)
				(justify mirror)
			)
		)
		(fp_text user "S7"
			(at -5.584952 45.016166 0)
			(unlocked yes)
			(layer "B.SilkS")
			(effects
				(font
					(size 0.7874 0.5842)
					(thickness 0.1524)
				)
				(justify mirror)
			)
		)
		(fp_text user "S6"
			(at 2.970276 47.91583 0)
			(unlocked yes)
			(layer "B.SilkS")
			(effects
				(font
					(size 0.7874 0.5842)
					(thickness 0.1524)
				)
				(justify mirror)
			)
		)
		(fp_text user "P1"
			(at 3.108452 -1.27 180)
			(unlocked yes)
			(layer "B.Fab")
			(effects
				(font
					(size 0.7874 0.5842)
					(thickness 0.000001)
				)
				(justify mirror)
			)
		)
		(fp_text user "P32"
			(at -5.781548 -0.0508 180)
			(unlocked yes)
			(layer "B.Fab")
			(effects
				(font
					(size 0.7874 0.5842)
					(thickness 0.000001)
				)
				(justify mirror)
			)
		)
		(fp_text user "PRESS-FIT"
			(at -6.82371 29.8831 0)
			(unlocked yes)
			(layer "B.Fab")
			(effects
				(font
					(size 1.6002 1.1938)
					(thickness 0.000001)
				)
				(justify left mirror)
			)
		)
		(fp_text user "P17"
			(at -5.72135 38.0746 180)
			(unlocked yes)
			(layer "B.Fab")
			(effects
				(font
					(size 0.7874 0.5842)
					(thickness 0.000001)
				)
				(justify mirror)
			)
		)
		(fp_text user "P16"
			(at 3.159252 38.3794 180)
			(unlocked yes)
			(layer "B.Fab")
			(effects
				(font
					(size 0.7874 0.5842)
					(thickness 0.000001)
				)
				(justify mirror)
			)
		)
		(fp_text user "S12"
			(at -5.79374 41.42232 180)
			(unlocked yes)
			(layer "B.Fab")
			(effects
				(font
					(size 0.7874 0.5842)
					(thickness 0.000001)
				)
				(justify mirror)
			)
		)
		(fp_text user "S1"
			(at 3.09626 41.656 180)
			(unlocked yes)
			(layer "B.Fab")
			(effects
				(font
					(size 0.7874 0.5842)
					(thickness 0.000001)
				)
				(justify mirror)
			)
		)
		(fp_text user "S6"
			(at 3.133852 48.0822 180)
			(unlocked yes)
			(layer "B.Fab")
			(effects
				(font
					(size 0.7874 0.5842)
					(thickness 0.000001)
				)
				(justify mirror)
			)
		)
		(fp_text user "S7"
			(at -5.781548 48.0822 180)
			(unlocked yes)
			(layer "B.Fab")
			(effects
				(font
					(size 0.7874 0.5842)
					(thickness 0.000001)
				)
				(justify mirror)
			)
		)
		(fp_text user "P32"
			(at -4.071112 -0.0762 180)
			(unlocked yes)
			(layer "F.Fab")
			(effects
				(font
					(size 0.7874 0.5842)
					(thickness 0.000001)
				)
			)
		)
		(fp_text user "P1"
			(at 1.516888 0 180)
			(unlocked yes)
			(layer "F.Fab")
			(effects
				(font
					(size 0.7874 0.5842)
					(thickness 0.000001)
				)
			)
		)
		(fp_text user "PRESS-FIT"
			(at -6.762496 16.251428 0)
			(unlocked yes)
			(layer "F.Fab")
			(effects
				(font
					(size 1.6002 1.1938)
					(thickness 0.000001)
				)
				(justify left)
			)
		)
		(fp_text user "P17"
			(at -4.366768 38.227 180)
			(unlocked yes)
			(layer "F.Fab")
			(effects
				(font
					(size 0.7874 0.5842)
					(thickness 0.000001)
				)
			)
		)
		(fp_text user "P16"
			(at 2.228088 38.354 180)
			(unlocked yes)
			(layer "F.Fab")
			(effects
				(font
					(size 0.7874 0.5842)
					(thickness 0.000001)
				)
			)
		)
		(fp_text user "S12"
			(at -4.362958 41.09212 180)
			(unlocked yes)
			(layer "F.Fab")
			(effects
				(font
					(size 0.7874 0.5842)
					(thickness 0.000001)
				)
			)
		)
		(fp_text user "S1"
			(at 2.164842 41.6306 180)
			(unlocked yes)
			(layer "F.Fab")
			(effects
				(font
					(size 0.7874 0.5842)
					(thickness 0.000001)
				)
			)
		)
		(fp_text user "S6"
			(at 1.923288 48.133 180)
			(unlocked yes)
			(layer "F.Fab")
			(effects
				(font
					(size 0.7874 0.5842)
					(thickness 0.000001)
				)
			)
		)
		(fp_text user "S7"
			(at -4.426712 48.2346 180)
			(unlocked yes)
			(layer "F.Fab")
			(effects
				(font
					(size 0.7874 0.5842)
					(thickness 0.000001)
				)
			)
		)
		(pad "" np_thru_hole circle
			(at -1.35001 -2.54)
			(size 2.5146 2.5146)
			(drill 2.5146)
			(layers "*.Cu" "*.Mask")
			(clearance 0.381)
			(thermal_gap 0.381)
		)
		(pad "" np_thru_hole circle
			(at 0 50.8)
			(size 2.5146 2.5146)
			(drill 2.5146)
			(layers "*.Cu" "*.Mask")
			(clearance 0.381)
			(thermal_gap 0.381)
		)
		(pad "P1" thru_hole rect
			(at 0 0)
			(size 1.1684 1.1684)
			(drill 0.762)
			(layers "*.Cu" "*.Mask")
			(remove_unused_layers no)
			(net "GND")
			(clearance 0.0508)
			(padstack
				(mode front_inner_back)
				(layer "Inner"
					(shape circle)
					(size 1.1684 1.1684)
					(clearance 0.0508)
				)
				(layer "B.Cu"
					(shape rect)
					(size 1.1684 1.1684)
					(thermal_gap 0.0508)
					(clearance 0.0508)
				)
			)
		)
		(pad "P2" thru_hole circle
			(at 0 2.54)
			(size 1.1684 1.1684)
			(drill 0.762)
			(layers "*.Cu" "*.Mask")
			(remove_unused_layers no)
			(net "GND")
			(clearance 0.0508)
			(thermal_gap 0.0508)
		)
		(pad "P3" thru_hole circle
			(at 0 5.08)
			(size 1.1684 1.1684)
			(drill 0.762)
			(layers "*.Cu" "*.Mask")
			(remove_unused_layers no)
			(net "GND")
			(clearance 0.0508)
			(thermal_gap 0.0508)
		)
		(pad "P4" thru_hole circle
			(at 0 7.62)
			(size 1.1684 1.1684)
			(drill 0.762)
			(layers "*.Cu" "*.Mask")
			(remove_unused_layers no)
			(net "GND")
			(clearance 0.0508)
			(thermal_gap 0.0508)
		)
		(pad "P5" thru_hole circle
			(at 0 10.16)
			(size 1.1684 1.1684)
			(drill 0.762)
			(layers "*.Cu" "*.Mask")
			(remove_unused_layers no)
			(net "GND")
			(clearance 0.0508)
			(thermal_gap 0.0508)
		)
		(pad "P6" thru_hole circle
			(at 0 12.7)
			(size 1.1684 1.1684)
			(drill 0.762)
			(layers "*.Cu" "*.Mask")
			(remove_unused_layers no)
			(net "GND")
			(clearance 0.0508)
			(thermal_gap 0.0508)
		)
		(pad "P7" thru_hole circle
			(at 0 15.24)
			(size 1.1684 1.1684)
			(drill 0.762)
			(layers "*.Cu" "*.Mask")
			(remove_unused_layers no)
			(net "GND")
			(clearance 0.0508)
			(thermal_gap 0.0508)
		)
		(pad "P8" thru_hole circle
			(at 0 17.78)
			(size 1.1684 1.1684)
			(drill 0.762)
			(layers "*.Cu" "*.Mask")
			(remove_unused_layers no)
			(net "GND")
			(clearance 0.0508)
			(thermal_gap 0.0508)
		)
		(pad "P9" thru_hole circle
			(at 0 20.32)
			(size 1.1684 1.1684)
			(drill 0.762)
			(layers "*.Cu" "*.Mask")
			(remove_unused_layers no)
			(net "P12V")
			(clearance 0.0508)
			(thermal_gap 0.0508)
		)
		(pad "P10" thru_hole circle
			(at 0 22.86)
			(size 1.1684 1.1684)
			(drill 0.762)
			(layers "*.Cu" "*.Mask")
			(remove_unused_layers no)
			(net "P12V")
			(clearance 0.0508)
			(thermal_gap 0.0508)
		)
		(pad "P11" thru_hole circle
			(at 0 25.4)
			(size 1.1684 1.1684)
			(drill 0.762)
			(layers "*.Cu" "*.Mask")
			(remove_unused_layers no)
			(net "P12V")
			(clearance 0.0508)
			(thermal_gap 0.0508)
		)
		(pad "P12" thru_hole circle
			(at 0 27.94)
			(size 1.1684 1.1684)
			(drill 0.762)
			(layers "*.Cu" "*.Mask")
			(remove_unused_layers no)
			(net "P12V")
			(clearance 0.0508)
			(thermal_gap 0.0508)
		)
		(pad "P13" thru_hole circle
			(at 0 30.48)
			(size 1.1684 1.1684)
			(drill 0.762)
			(layers "*.Cu" "*.Mask")
			(remove_unused_layers no)
			(net "P12V")
			(clearance 0.0508)
			(thermal_gap 0.0508)
		)
		(pad "P14" thru_hole circle
			(at 0 33.02)
			(size 1.1684 1.1684)
			(drill 0.762)
			(layers "*.Cu" "*.Mask")
			(remove_unused_layers no)
			(net "P12V")
			(clearance 0.0508)
			(thermal_gap 0.0508)
		)
		(pad "P15" thru_hole circle
			(at 0 35.56)
			(size 1.1684 1.1684)
			(drill 0.762)
			(layers "*.Cu" "*.Mask")
			(remove_unused_layers no)
			(net "P12V")
			(clearance 0.0508)
			(thermal_gap 0.0508)
		)
		(pad "P16" thru_hole circle
			(at 0 38.1)
			(size 1.1684 1.1684)
			(drill 0.762)
			(layers "*.Cu" "*.Mask")
			(remove_unused_layers no)
			(net "P12V")
			(clearance 0.0508)
			(thermal_gap 0.0508)
		)
		(pad "P17" thru_hole circle
			(at -2.70002 38.1)
			(size 1.1684 1.1684)
			(drill 0.762)
			(layers "*.Cu" "*.Mask")
			(remove_unused_layers no)
			(net "P12V")
			(clearance 0.0508)
			(thermal_gap 0.0508)
		)
		(pad "P18" thru_hole circle
			(at -2.70002 35.56)
			(size 1.1684 1.1684)
			(drill 0.762)
			(layers "*.Cu" "*.Mask")
			(remove_unused_layers no)
			(net "P12V")
			(clearance 0.0508)
			(thermal_gap 0.0508)
		)
		(pad "P19" thru_hole circle
			(at -2.70002 33.02)
			(size 1.1684 1.1684)
			(drill 0.762)
			(layers "*.Cu" "*.Mask")
			(remove_unused_layers no)
			(net "P12V")
			(clearance 0.0508)
			(thermal_gap 0.0508)
		)
		(pad "P20" thru_hole circle
			(at -2.70002 30.48)
			(size 1.1684 1.1684)
			(drill 0.762)
			(layers "*.Cu" "*.Mask")
			(remove_unused_layers no)
			(net "P12V")
			(clearance 0.0508)
			(thermal_gap 0.0508)
		)
		(pad "P21" thru_hole circle
			(at -2.70002 27.94)
			(size 1.1684 1.1684)
			(drill 0.762)
			(layers "*.Cu" "*.Mask")
			(remove_unused_layers no)
			(net "P12V")
			(clearance 0.0508)
			(thermal_gap 0.0508)
		)
		(pad "P22" thru_hole circle
			(at -2.70002 25.4)
			(size 1.1684 1.1684)
			(drill 0.762)
			(layers "*.Cu" "*.Mask")
			(remove_unused_layers no)
			(net "P12V")
			(clearance 0.0508)
			(thermal_gap 0.0508)
		)
		(pad "P23" thru_hole circle
			(at -2.70002 22.86)
			(size 1.1684 1.1684)
			(drill 0.762)
			(layers "*.Cu" "*.Mask")
			(remove_unused_layers no)
			(net "P12V")
			(clearance 0.0508)
			(thermal_gap 0.0508)
		)
		(pad "P24" thru_hole circle
			(at -2.70002 20.32)
			(size 1.1684 1.1684)
			(drill 0.762)
			(layers "*.Cu" "*.Mask")
			(remove_unused_layers no)
			(net "P12V")
			(clearance 0.0508)
			(thermal_gap 0.0508)
		)
		(pad "P25" thru_hole circle
			(at -2.70002 17.78)
			(size 1.1684 1.1684)
			(drill 0.762)
			(layers "*.Cu" "*.Mask")
			(remove_unused_layers no)
			(net "GND")
			(clearance 0.0508)
			(thermal_gap 0.0508)
		)
		(pad "P26" thru_hole circle
			(at -2.70002 15.24)
			(size 1.1684 1.1684)
			(drill 0.762)
			(layers "*.Cu" "*.Mask")
			(remove_unused_layers no)
			(net "GND")
			(clearance 0.0508)
			(thermal_gap 0.0508)
		)
		(pad "P27" thru_hole circle
			(at -2.70002 12.7)
			(size 1.1684 1.1684)
			(drill 0.762)
			(layers "*.Cu" "*.Mask")
			(remove_unused_layers no)
			(net "GND")
			(clearance 0.0508)
			(thermal_gap 0.0508)
		)
		(pad "P28" thru_hole circle
			(at -2.70002 10.16)
			(size 1.1684 1.1684)
			(drill 0.762)
			(layers "*.Cu" "*.Mask")
			(remove_unused_layers no)
			(net "GND")
			(clearance 0.0508)
			(thermal_gap 0.0508)
		)
		(pad "P29" thru_hole circle
			(at -2.70002 7.62)
			(size 1.1684 1.1684)
			(drill 0.762)
			(layers "*.Cu" "*.Mask")
			(remove_unused_layers no)
			(net "GND")
			(clearance 0.0508)
			(thermal_gap 0.0508)
		)
		(pad "P30" thru_hole circle
			(at -2.70002 5.08)
			(size 1.1684 1.1684)
			(drill 0.762)
			(layers "*.Cu" "*.Mask")
			(remove_unused_layers no)
			(net "GND")
			(clearance 0.0508)
			(thermal_gap 0.0508)
		)
		(pad "P31" thru_hole circle
			(at -2.70002 2.54)
			(size 1.1684 1.1684)
			(drill 0.762)
			(layers "*.Cu" "*.Mask")
			(remove_unused_layers no)
			(net "GND")
			(clearance 0.0508)
			(thermal_gap 0.0508)
		)
		(pad "P32" thru_hole circle
			(at -2.70002 0)
			(size 1.1684 1.1684)
			(drill 0.762)
			(layers "*.Cu" "*.Mask")
			(remove_unused_layers no)
			(net "GND")
			(clearance 0.0508)
			(thermal_gap 0.0508)
		)
		(pad "S1" thru_hole circle
			(at 0.55499 41.60012)
			(size 1.1684 1.1684)
			(drill 0.762)
			(layers "*.Cu" "*.Mask")
			(remove_unused_layers no)
			(net "T6_BLAD1_TXD")
			(clearance 0.0508)
			(thermal_gap 0.0508)
		)
		(pad "S2" thru_hole circle
			(at -0.71501 42.87012)
			(size 1.1684 1.1684)
			(drill 0.762)
			(layers "*.Cu" "*.Mask")
			(remove_unused_layers no)
			(net "T6_BLAD1_RXD")
			(clearance 0.0508)
			(thermal_gap 0.0508)
		)
		(pad "S3" thru_hole circle
			(at 0.55499 44.14012)
			(size 1.1684 1.1684)
			(drill 0.762)
			(layers "*.Cu" "*.Mask")
			(remove_unused_layers no)
			(net "T6_BLAD1_EN")
			(clearance 0.0508)
			(thermal_gap 0.0508)
		)
		(pad "S4" thru_hole circle
			(at -0.71501 45.41012)
			(size 1.1684 1.1684)
			(drill 0.762)
			(layers "*.Cu" "*.Mask")
			(remove_unused_layers no)
			(net "T6_BLAD2_EN")
			(clearance 0.0508)
			(thermal_gap 0.0508)
		)
		(pad "S5" thru_hole circle
			(at 0.55499 46.68012)
			(size 1.1684 1.1684)
			(drill 0.762)
			(layers "*.Cu" "*.Mask")
			(remove_unused_layers no)
			(net "T6_BLAD2_TXD")
			(clearance 0.0508)
			(thermal_gap 0.0508)
		)
		(pad "S6" thru_hole circle
			(at -0.71501 47.95012)
			(size 1.1684 1.1684)
			(drill 0.762)
			(layers "*.Cu" "*.Mask")
			(remove_unused_layers no)
			(net "T6_BLAD2_RXD")
			(clearance 0.0508)
			(thermal_gap 0.0508)
		)
		(pad "S7" thru_hole circle
			(at -3.25501 47.95012)
			(size 1.1684 1.1684)
			(drill 0.762)
			(layers "*.Cu" "*.Mask")
			(remove_unused_layers no)
			(net "T6_BLAD4_RXD")
			(clearance 0.0508)
			(thermal_gap 0.0508)
		)
		(pad "S8" thru_hole circle
			(at -1.98501 46.68012)
			(size 1.1684 1.1684)
			(drill 0.762)
			(layers "*.Cu" "*.Mask")
			(remove_unused_layers no)
			(net "T6_BLAD4_TXD")
			(clearance 0.0508)
			(thermal_gap 0.0508)
		)
		(pad "S9" thru_hole circle
			(at -3.25501 45.41012)
			(size 1.1684 1.1684)
			(drill 0.762)
			(layers "*.Cu" "*.Mask")
			(remove_unused_layers no)
			(net "T6_BLAD4_EN")
			(clearance 0.0508)
			(thermal_gap 0.0508)
		)
		(pad "S10" thru_hole circle
			(at -1.98501 44.14012)
			(size 1.1684 1.1684)
			(drill 0.762)
			(layers "*.Cu" "*.Mask")
			(remove_unused_layers no)
			(net "T6_BLAD3_EN")
			(clearance 0.0508)
			(thermal_gap 0.0508)
		)
		(pad "S11" thru_hole circle
			(at -3.25501 42.87012)
			(size 1.1684 1.1684)
			(drill 0.762)
			(layers "*.Cu" "*.Mask")
			(remove_unused_layers no)
			(net "T6_BLAD3_RXD")
			(clearance 0.0508)
			(thermal_gap 0.0508)
		)
		(pad "S12" thru_hole circle
			(at -1.98501 41.60012)
			(size 1.1684 1.1684)
			(drill 0.762)
			(layers "*.Cu" "*.Mask")
			(remove_unused_layers no)
			(net "T6_BLAD3_TXD")
			(clearance 0.0508)
			(thermal_gap 0.0508)
		)
		(zone
			(layer "F.Cu")
			(hatch none 0.5)
			(connect_pads
				(clearance 0)
			)
			(min_thickness 0.25)
			(keepout
				(tracks allowed)
				(vias not_allowed)
				(pads allowed)
				(copperpour not_allowed)
				(footprints allowed)
			)
			(placement
				(enabled no)
				(sheetname "")
			)
			(fill
				(thermal_gap 0.5)
				(thermal_bridge_width 0.5)
				(island_removal_mode 0)
			)
			(polygon
				(pts
					(xy 85.00999 -231.70388) (xy 92.65539 -231.70388) (xy 92.65539 -226.59848) (xy 85.00999 -226.59848)
					(xy 84.98459 -226.59848) (xy 84.98459 -231.70388)
				)
			)
		)
		(zone
			(layer "F.Cu")
			(hatch none 0.5)
			(connect_pads
				(clearance 0)
			)
			(min_thickness 0.25)
			(keepout
				(tracks allowed)
				(vias not_allowed)
				(pads allowed)
				(copperpour not_allowed)
				(footprints allowed)
			)
			(placement
				(enabled no)
				(sheetname "")
			)
			(fill
				(thermal_gap 0.5)
				(thermal_bridge_width 0.5)
				(island_removal_mode 0)
			)
			(polygon
				(pts
					(xy 43.37939 -227.18268) (xy 43.37939 -231.14508) (xy 82.77479 -231.14508) (xy 82.80019 -231.14508)
					(xy 82.80019 -227.18268) (xy 82.80019 -227.15728) (xy 43.37939 -227.15728)
				)
			)
		)
		(zone
			(layers "F.Cu" "B.Cu" "In1.Cu" "In2.Cu" "In3.Cu" "In4.Cu" "In5.Cu" "In6.Cu")
			(hatch none 0.5)
			(connect_pads
				(clearance 0)
			)
			(min_thickness 0.25)
			(keepout
				(tracks not_allowed)
				(vias allowed)
				(pads allowed)
				(copperpour not_allowed)
				(footprints allowed)
			)
			(placement
				(enabled no)
				(sheetname "")
			)
			(fill
				(thermal_gap 0.5)
				(thermal_bridge_width 0.5)
				(island_removal_mode 0)
			)
			(polygon
				(pts
					(arc
						(start 43.18 -229.16007)
						(mid 39.81958 -229.16007)
						(end 43.18 -229.16007)
					)
				)
			)
		)
		(zone
			(layers "F.Cu" "B.Cu" "In1.Cu" "In2.Cu" "In3.Cu" "In4.Cu" "In5.Cu" "In6.Cu")
			(hatch none 0.5)
			(connect_pads
				(clearance 0)
			)
			(min_thickness 0.25)
			(keepout
				(tracks not_allowed)
				(vias allowed)
				(pads allowed)
				(copperpour not_allowed)
				(footprints allowed)
			)
			(placement
				(enabled no)
				(sheetname "")
			)
			(fill
				(thermal_gap 0.5)
				(thermal_bridge_width 0.5)
				(island_removal_mode 0)
			)
			(polygon
				(pts
					(arc
						(start 96.52381 -230.51008)
						(mid 93.15577 -230.51008)
						(end 96.52381 -230.51008)
					)
				)
			)
		)
	)
	(footprint ""
		(layer "B.Cu")
		(at 44.03979 -319.41008 90)
		(property "Reference" "J14"
			(at 6.291834 -4.21005 0)
			(unlocked yes)
			(layer "B.SilkS")
			(effects
				(font
					(size 0.7874 0.5842)
					(thickness 0.1524)
				)
				(justify left mirror)
			)
		)
		(property "Value" ""
			(at 0 0 90)
			(layer "B.Fab")
			(effects
				(font
					(size 1.27 1.27)
				)
				(justify mirror)
			)
		)
		(duplicate_pad_numbers_are_jumpers no)
		(fp_line
			(start 5.275072 -13.910056)
			(end -7.975092 -13.910056)
			(stroke
				(width 0.1524)
				(type default)
			)
			(layer "F.SilkS")
		)
		(fp_line
			(start -7.975092 -13.910056)
			(end -7.975092 62.170056)
			(stroke
				(width 0.1524)
				(type default)
			)
			(layer "F.SilkS")
		)
		(fp_line
			(start 5.275072 62.170056)
			(end 5.275072 -13.910056)
			(stroke
				(width 0.1524)
				(type default)
			)
			(layer "F.SilkS")
		)
		(fp_line
			(start -7.975092 62.170056)
			(end 5.275072 62.170056)
			(stroke
				(width 0.1524)
				(type default)
			)
			(layer "F.SilkS")
		)
		(fp_line
			(start 5.275072 -13.910056)
			(end -7.975092 -13.910056)
			(stroke
				(width 0.1524)
				(type default)
			)
			(layer "B.SilkS")
		)
		(fp_line
			(start -7.975092 -13.910056)
			(end -7.975092 62.170056)
			(stroke
				(width 0.1524)
				(type default)
			)
			(layer "B.SilkS")
		)
		(fp_line
			(start 2.275078 -10.910062)
			(end 2.275078 59.170062)
			(stroke
				(width 0.1524)
				(type default)
			)
			(layer "B.SilkS")
		)
		(fp_line
			(start -4.975098 -10.910062)
			(end 2.275078 -10.910062)
			(stroke
				(width 0.1524)
				(type default)
			)
			(layer "B.SilkS")
		)
		(fp_line
			(start 2.275078 59.170062)
			(end -4.975098 59.170062)
			(stroke
				(width 0.1524)
				(type default)
			)
			(layer "B.SilkS")
		)
		(fp_line
			(start -4.975098 59.170062)
			(end -4.975098 -10.910062)
			(stroke
				(width 0.1524)
				(type default)
			)
			(layer "B.SilkS")
		)
		(fp_line
			(start 5.275072 62.170056)
			(end 5.275072 -13.910056)
			(stroke
				(width 0.1524)
				(type default)
			)
			(layer "B.SilkS")
		)
		(fp_line
			(start -7.975092 62.170056)
			(end 5.275072 62.170056)
			(stroke
				(width 0.1524)
				(type default)
			)
			(layer "B.SilkS")
		)
		(fp_poly
			(pts
				(xy 4.103878 -0.759206) (xy 4.103878 0.764794) (xy 2.579878 0.002794)
			)
			(stroke
				(width 0)
				(type default)
			)
			(fill yes)
			(layer "B.SilkS")
		)
		(fp_poly
			(pts
				(xy 2.275078 -10.910062) (xy 2.275078 59.170062) (xy -4.975098 59.170062) (xy -4.975098 -10.910062)
			)
			(stroke
				(width 0)
				(type default)
			)
			(fill no)
			(layer "B.CrtYd")
		)
		(fp_poly
			(pts
				(xy 1.1938 40.9702) (xy 1.1938 48.6156) (xy -3.9116 48.6156) (xy -3.9116 40.9702) (xy -3.9116 40.9448)
				(xy 1.1938 40.9448)
			)
			(stroke
				(width 0)
				(type default)
			)
			(fill no)
			(layer "F.CrtYd")
		)
		(fp_poly
			(pts
				(xy -3.3274 -0.6604) (xy 0.635 -0.6604) (xy 0.635 38.735) (xy 0.635 38.7604) (xy -3.3274 38.7604)
				(xy -3.3528 38.7604) (xy -3.3528 -0.6604)
			)
			(stroke
				(width 0)
				(type default)
			)
			(fill no)
			(layer "F.CrtYd")
		)
		(fp_poly
			(pts
				(arc
					(start -1.35001 -1.01219)
					(mid -1.35001 -4.06781)
					(end -1.35001 -1.01219)
				)
			)
			(stroke
				(width 0)
				(type default)
			)
			(fill no)
			(layer "F.CrtYd")
		)
		(fp_poly
			(pts
				(arc
					(start 0 52.33162)
					(mid 0 49.26838)
					(end 0 52.33162)
				)
			)
			(stroke
				(width 0)
				(type default)
			)
			(fill no)
			(layer "F.CrtYd")
		)
		(fp_line
			(start 2.275078 -10.910062)
			(end 2.275078 59.170062)
			(stroke
				(width 0.1)
				(type default)
			)
			(layer "B.Fab")
		)
		(fp_line
			(start -4.975098 -10.910062)
			(end 2.275078 -10.910062)
			(stroke
				(width 0.1)
				(type default)
			)
			(layer "B.Fab")
		)
		(fp_line
			(start 2.275078 59.170062)
			(end -4.975098 59.170062)
			(stroke
				(width 0.1)
				(type default)
			)
			(layer "B.Fab")
		)
		(fp_line
			(start -4.975098 59.170062)
			(end -4.975098 -10.910062)
			(stroke
				(width 0.1)
				(type default)
			)
			(layer "B.Fab")
		)
		(fp_poly
			(pts
				(xy 4.103878 -0.759206) (xy 4.103878 0.764794) (xy 2.579878 0.002794)
			)
			(stroke
				(width 0)
				(type default)
			)
			(fill yes)
			(layer "B.Fab")
		)
		(fp_line
			(start 5.275072 -13.910056)
			(end -7.975092 -13.910056)
			(stroke
				(width 0.1)
				(type default)
			)
			(layer "F.Fab")
		)
		(fp_line
			(start -7.975092 -13.910056)
			(end -7.975092 62.170056)
			(stroke
				(width 0.1)
				(type default)
			)
			(layer "F.Fab")
		)
		(fp_line
			(start 5.275072 62.170056)
			(end 5.275072 -13.910056)
			(stroke
				(width 0.1)
				(type default)
			)
			(layer "F.Fab")
		)
		(fp_line
			(start -7.975092 62.170056)
			(end 5.275072 62.170056)
			(stroke
				(width 0.1)
				(type default)
			)
			(layer "F.Fab")
		)
		(fp_text user "P32"
			(at -9.100312 -0.1651 0)
			(unlocked yes)
			(layer "F.SilkS")
			(effects
				(font
					(size 0.7874 0.5842)
					(thickness 0.1524)
				)
			)
		)
		(fp_text user "P1"
			(at 6.27253 -0.031496 0)
			(unlocked yes)
			(layer "F.SilkS")
			(effects
				(font
					(size 0.7874 0.5842)
					(thickness 0.1524)
				)
			)
		)
		(fp_text user "PRESS-FIT"
			(at -9.03351 9.860534 0)
			(unlocked yes)
			(layer "F.SilkS")
			(effects
				(font
					(size 0.7874 0.5842)
					(thickness 0.1524)
				)
				(justify left)
			)
		)
		(fp_text user "P17"
			(at -9.28243 37.648896 0)
			(unlocked yes)
			(layer "F.SilkS")
			(effects
				(font
					(size 0.7874 0.5842)
					(thickness 0.1524)
				)
			)
		)
		(fp_text user "P16"
			(at 7.168642 38.070282 0)
			(unlocked yes)
			(layer "F.SilkS")
			(effects
				(font
					(size 0.7874 0.5842)
					(thickness 0.1524)
				)
			)
		)
		(fp_text user "S12"
			(at -9.044178 40.92067 0)
			(unlocked yes)
			(layer "F.SilkS")
			(effects
				(font
					(size 0.7874 0.5842)
					(thickness 0.1524)
				)
			)
		)
		(fp_text user "S1"
			(at 7.168642 41.691814 0)
			(unlocked yes)
			(layer "F.SilkS")
			(effects
				(font
					(size 0.7874 0.5842)
					(thickness 0.1524)
				)
			)
		)
		(fp_text user "S6"
			(at 6.11251 47.855886 0)
			(unlocked yes)
			(layer "F.SilkS")
			(effects
				(font
					(size 0.7874 0.5842)
					(thickness 0.1524)
				)
			)
		)
		(fp_text user "S7"
			(at -8.957818 47.91075 0)
			(unlocked yes)
			(layer "F.SilkS")
			(effects
				(font
					(size 0.7874 0.5842)
					(thickness 0.1524)
				)
			)
		)
		(fp_text user "P1"
			(at 3.191764 -1.633982 0)
			(unlocked yes)
			(layer "B.SilkS")
			(effects
				(font
					(size 0.7874 0.5842)
					(thickness 0.1524)
				)
				(justify mirror)
			)
		)
		(fp_text user "P32"
			(at -5.830316 -0.19685 0)
			(unlocked yes)
			(layer "B.SilkS")
			(effects
				(font
					(size 0.7874 0.5842)
					(thickness 0.1524)
				)
				(justify mirror)
			)
		)
		(fp_text user "PRESS-FIT"
			(at -7.18947 29.8831 0)
			(unlocked yes)
			(layer "B.SilkS")
			(effects
				(font
					(size 0.7874 0.5842)
					(thickness 0.1524)
				)
				(justify left mirror)
			)
		)
		(fp_text user "P17"
			(at -5.822696 37.797994 0)
			(unlocked yes)
			(layer "B.SilkS")
			(effects
				(font
					(size 0.7874 0.5842)
					(thickness 0.1524)
				)
				(justify mirror)
			)
		)
		(fp_text user "P16"
			(at 3.175254 37.799518 0)
			(unlocked yes)
			(layer "B.SilkS")
			(effects
				(font
					(size 0.7874 0.5842)
					(thickness 0.1524)
				)
				(justify mirror)
			)
		)
		(fp_text user "S1"
			(at 3.136138 41.77665 0)
			(unlocked yes)
			(layer "B.SilkS")
			(effects
				(font
					(size 0.7874 0.5842)
					(thickness 0.1524)
				)
				(justify mirror)
			)
		)
		(fp_text user "S12"
			(at -5.818378 42.38498 0)
			(unlocked yes)
			(layer "B.SilkS")
			(effects
				(font
					(size 0.7874 0.5842)
					(thickness 0.1524)
				)
				(justify mirror)
			)
		)
		(fp_text user "S6"
			(at 3.268726 47.303182 0)
			(unlocked yes)
			(layer "B.SilkS")
			(effects
				(font
					(size 0.7874 0.5842)
					(thickness 0.1524)
				)
				(justify mirror)
			)
		)
		(fp_text user "S7"
			(at -5.830316 48.392842 0)
			(unlocked yes)
			(layer "B.SilkS")
			(effects
				(font
					(size 0.7874 0.5842)
					(thickness 0.1524)
				)
				(justify mirror)
			)
		)
		(fp_text user "P1"
			(at 3.108452 -1.27 180)
			(unlocked yes)
			(layer "B.Fab")
			(effects
				(font
					(size 0.7874 0.5842)
					(thickness 0.000001)
				)
				(justify mirror)
			)
		)
		(fp_text user "P32"
			(at -5.781548 -0.0508 180)
			(unlocked yes)
			(layer "B.Fab")
			(effects
				(font
					(size 0.7874 0.5842)
					(thickness 0.000001)
				)
				(justify mirror)
			)
		)
		(fp_text user "PRESS-FIT"
			(at -6.82371 29.8831 0)
			(unlocked yes)
			(layer "B.Fab")
			(effects
				(font
					(size 1.6002 1.1938)
					(thickness 0.000001)
				)
				(justify left mirror)
			)
		)
		(fp_text user "P17"
			(at -5.72135 38.0746 180)
			(unlocked yes)
			(layer "B.Fab")
			(effects
				(font
					(size 0.7874 0.5842)
					(thickness 0.000001)
				)
				(justify mirror)
			)
		)
		(fp_text user "P16"
			(at 3.159252 38.3794 180)
			(unlocked yes)
			(layer "B.Fab")
			(effects
				(font
					(size 0.7874 0.5842)
					(thickness 0.000001)
				)
				(justify mirror)
			)
		)
		(fp_text user "S12"
			(at -5.79374 41.42232 180)
			(unlocked yes)
			(layer "B.Fab")
			(effects
				(font
					(size 0.7874 0.5842)
					(thickness 0.000001)
				)
				(justify mirror)
			)
		)
		(fp_text user "S1"
			(at 3.09626 41.656 180)
			(unlocked yes)
			(layer "B.Fab")
			(effects
				(font
					(size 0.7874 0.5842)
					(thickness 0.000001)
				)
				(justify mirror)
			)
		)
		(fp_text user "S6"
			(at 3.133852 48.0822 180)
			(unlocked yes)
			(layer "B.Fab")
			(effects
				(font
					(size 0.7874 0.5842)
					(thickness 0.000001)
				)
				(justify mirror)
			)
		)
		(fp_text user "S7"
			(at -5.781548 48.0822 180)
			(unlocked yes)
			(layer "B.Fab")
			(effects
				(font
					(size 0.7874 0.5842)
					(thickness 0.000001)
				)
				(justify mirror)
			)
		)
		(fp_text user "P32"
			(at -4.071112 -0.0762 180)
			(unlocked yes)
			(layer "F.Fab")
			(effects
				(font
					(size 0.7874 0.5842)
					(thickness 0.000001)
				)
			)
		)
		(fp_text user "P1"
			(at 1.516888 0 180)
			(unlocked yes)
			(layer "F.Fab")
			(effects
				(font
					(size 0.7874 0.5842)
					(thickness 0.000001)
				)
			)
		)
		(fp_text user "PRESS-FIT"
			(at -6.762496 16.251428 0)
			(unlocked yes)
			(layer "F.Fab")
			(effects
				(font
					(size 1.6002 1.1938)
					(thickness 0.000001)
				)
				(justify left)
			)
		)
		(fp_text user "P17"
			(at -4.366768 38.227 180)
			(unlocked yes)
			(layer "F.Fab")
			(effects
				(font
					(size 0.7874 0.5842)
					(thickness 0.000001)
				)
			)
		)
		(fp_text user "P16"
			(at 2.228088 38.354 180)
			(unlocked yes)
			(layer "F.Fab")
			(effects
				(font
					(size 0.7874 0.5842)
					(thickness 0.000001)
				)
			)
		)
		(fp_text user "S12"
			(at -4.362958 41.09212 180)
			(unlocked yes)
			(layer "F.Fab")
			(effects
				(font
					(size 0.7874 0.5842)
					(thickness 0.000001)
				)
			)
		)
		(fp_text user "S1"
			(at 2.164842 41.6306 180)
			(unlocked yes)
			(layer "F.Fab")
			(effects
				(font
					(size 0.7874 0.5842)
					(thickness 0.000001)
				)
			)
		)
		(fp_text user "S6"
			(at 1.923288 48.133 180)
			(unlocked yes)
			(layer "F.Fab")
			(effects
				(font
					(size 0.7874 0.5842)
					(thickness 0.000001)
				)
			)
		)
		(fp_text user "S7"
			(at -4.426712 48.2346 180)
			(unlocked yes)
			(layer "F.Fab")
			(effects
				(font
					(size 0.7874 0.5842)
					(thickness 0.000001)
				)
			)
		)
		(pad "" np_thru_hole circle
			(at -1.35001 -2.54)
			(size 2.5146 2.5146)
			(drill 2.5146)
			(layers "*.Cu" "*.Mask")
			(clearance 0.381)
			(thermal_gap 0.381)
		)
		(pad "" np_thru_hole circle
			(at 0 50.8)
			(size 2.5146 2.5146)
			(drill 2.5146)
			(layers "*.Cu" "*.Mask")
			(clearance 0.381)
			(thermal_gap 0.381)
		)
		(pad "P1" thru_hole rect
			(at 0 0)
			(size 1.1684 1.1684)
			(drill 0.762)
			(layers "*.Cu" "*.Mask")
			(remove_unused_layers no)
			(net "GND")
			(clearance 0.0508)
			(padstack
				(mode front_inner_back)
				(layer "Inner"
					(shape circle)
					(size 1.1684 1.1684)
					(clearance 0.0508)
				)
				(layer "B.Cu"
					(shape rect)
					(size 1.1684 1.1684)
					(thermal_gap 0.0508)
					(clearance 0.0508)
				)
			)
		)
		(pad "P2" thru_hole circle
			(at 0 2.54)
			(size 1.1684 1.1684)
			(drill 0.762)
			(layers "*.Cu" "*.Mask")
			(remove_unused_layers no)
			(net "GND")
			(clearance 0.0508)
			(thermal_gap 0.0508)
		)
		(pad "P3" thru_hole circle
			(at 0 5.08)
			(size 1.1684 1.1684)
			(drill 0.762)
			(layers "*.Cu" "*.Mask")
			(remove_unused_layers no)
			(net "GND")
			(clearance 0.0508)
			(thermal_gap 0.0508)
		)
		(pad "P4" thru_hole circle
			(at 0 7.62)
			(size 1.1684 1.1684)
			(drill 0.762)
			(layers "*.Cu" "*.Mask")
			(remove_unused_layers no)
			(net "GND")
			(clearance 0.0508)
			(thermal_gap 0.0508)
		)
		(pad "P5" thru_hole circle
			(at 0 10.16)
			(size 1.1684 1.1684)
			(drill 0.762)
			(layers "*.Cu" "*.Mask")
			(remove_unused_layers no)
			(net "GND")
			(clearance 0.0508)
			(thermal_gap 0.0508)
		)
		(pad "P6" thru_hole circle
			(at 0 12.7)
			(size 1.1684 1.1684)
			(drill 0.762)
			(layers "*.Cu" "*.Mask")
			(remove_unused_layers no)
			(net "GND")
			(clearance 0.0508)
			(thermal_gap 0.0508)
		)
		(pad "P7" thru_hole circle
			(at 0 15.24)
			(size 1.1684 1.1684)
			(drill 0.762)
			(layers "*.Cu" "*.Mask")
			(remove_unused_layers no)
			(net "GND")
			(clearance 0.0508)
			(thermal_gap 0.0508)
		)
		(pad "P8" thru_hole circle
			(at 0 17.78)
			(size 1.1684 1.1684)
			(drill 0.762)
			(layers "*.Cu" "*.Mask")
			(remove_unused_layers no)
			(net "GND")
			(clearance 0.0508)
			(thermal_gap 0.0508)
		)
		(pad "P9" thru_hole circle
			(at 0 20.32)
			(size 1.1684 1.1684)
			(drill 0.762)
			(layers "*.Cu" "*.Mask")
			(remove_unused_layers no)
			(net "P12V")
			(clearance 0.0508)
			(thermal_gap 0.0508)
		)
		(pad "P10" thru_hole circle
			(at 0 22.86)
			(size 1.1684 1.1684)
			(drill 0.762)
			(layers "*.Cu" "*.Mask")
			(remove_unused_layers no)
			(net "P12V")
			(clearance 0.0508)
			(thermal_gap 0.0508)
		)
		(pad "P11" thru_hole circle
			(at 0 25.4)
			(size 1.1684 1.1684)
			(drill 0.762)
			(layers "*.Cu" "*.Mask")
			(remove_unused_layers no)
			(net "P12V")
			(clearance 0.0508)
			(thermal_gap 0.0508)
		)
		(pad "P12" thru_hole circle
			(at 0 27.94)
			(size 1.1684 1.1684)
			(drill 0.762)
			(layers "*.Cu" "*.Mask")
			(remove_unused_layers no)
			(net "P12V")
			(clearance 0.0508)
			(thermal_gap 0.0508)
		)
		(pad "P13" thru_hole circle
			(at 0 30.48)
			(size 1.1684 1.1684)
			(drill 0.762)
			(layers "*.Cu" "*.Mask")
			(remove_unused_layers no)
			(net "P12V")
			(clearance 0.0508)
			(thermal_gap 0.0508)
		)
		(pad "P14" thru_hole circle
			(at 0 33.02)
			(size 1.1684 1.1684)
			(drill 0.762)
			(layers "*.Cu" "*.Mask")
			(remove_unused_layers no)
			(net "P12V")
			(clearance 0.0508)
			(thermal_gap 0.0508)
		)
		(pad "P15" thru_hole circle
			(at 0 35.56)
			(size 1.1684 1.1684)
			(drill 0.762)
			(layers "*.Cu" "*.Mask")
			(remove_unused_layers no)
			(net "P12V")
			(clearance 0.0508)
			(thermal_gap 0.0508)
		)
		(pad "P16" thru_hole circle
			(at 0 38.1)
			(size 1.1684 1.1684)
			(drill 0.762)
			(layers "*.Cu" "*.Mask")
			(remove_unused_layers no)
			(net "P12V")
			(clearance 0.0508)
			(thermal_gap 0.0508)
		)
		(pad "P17" thru_hole circle
			(at -2.70002 38.1)
			(size 1.1684 1.1684)
			(drill 0.762)
			(layers "*.Cu" "*.Mask")
			(remove_unused_layers no)
			(net "P12V")
			(clearance 0.0508)
			(thermal_gap 0.0508)
		)
		(pad "P18" thru_hole circle
			(at -2.70002 35.56)
			(size 1.1684 1.1684)
			(drill 0.762)
			(layers "*.Cu" "*.Mask")
			(remove_unused_layers no)
			(net "P12V")
			(clearance 0.0508)
			(thermal_gap 0.0508)
		)
		(pad "P19" thru_hole circle
			(at -2.70002 33.02)
			(size 1.1684 1.1684)
			(drill 0.762)
			(layers "*.Cu" "*.Mask")
			(remove_unused_layers no)
			(net "P12V")
			(clearance 0.0508)
			(thermal_gap 0.0508)
		)
		(pad "P20" thru_hole circle
			(at -2.70002 30.48)
			(size 1.1684 1.1684)
			(drill 0.762)
			(layers "*.Cu" "*.Mask")
			(remove_unused_layers no)
			(net "P12V")
			(clearance 0.0508)
			(thermal_gap 0.0508)
		)
		(pad "P21" thru_hole circle
			(at -2.70002 27.94)
			(size 1.1684 1.1684)
			(drill 0.762)
			(layers "*.Cu" "*.Mask")
			(remove_unused_layers no)
			(net "P12V")
			(clearance 0.0508)
			(thermal_gap 0.0508)
		)
		(pad "P22" thru_hole circle
			(at -2.70002 25.4)
			(size 1.1684 1.1684)
			(drill 0.762)
			(layers "*.Cu" "*.Mask")
			(remove_unused_layers no)
			(net "P12V")
			(clearance 0.0508)
			(thermal_gap 0.0508)
		)
		(pad "P23" thru_hole circle
			(at -2.70002 22.86)
			(size 1.1684 1.1684)
			(drill 0.762)
			(layers "*.Cu" "*.Mask")
			(remove_unused_layers no)
			(net "P12V")
			(clearance 0.0508)
			(thermal_gap 0.0508)
		)
		(pad "P24" thru_hole circle
			(at -2.70002 20.32)
			(size 1.1684 1.1684)
			(drill 0.762)
			(layers "*.Cu" "*.Mask")
			(remove_unused_layers no)
			(net "P12V")
			(clearance 0.0508)
			(thermal_gap 0.0508)
		)
		(pad "P25" thru_hole circle
			(at -2.70002 17.78)
			(size 1.1684 1.1684)
			(drill 0.762)
			(layers "*.Cu" "*.Mask")
			(remove_unused_layers no)
			(net "GND")
			(clearance 0.0508)
			(thermal_gap 0.0508)
		)
		(pad "P26" thru_hole circle
			(at -2.70002 15.24)
			(size 1.1684 1.1684)
			(drill 0.762)
			(layers "*.Cu" "*.Mask")
			(remove_unused_layers no)
			(net "GND")
			(clearance 0.0508)
			(thermal_gap 0.0508)
		)
		(pad "P27" thru_hole circle
			(at -2.70002 12.7)
			(size 1.1684 1.1684)
			(drill 0.762)
			(layers "*.Cu" "*.Mask")
			(remove_unused_layers no)
			(net "GND")
			(clearance 0.0508)
			(thermal_gap 0.0508)
		)
		(pad "P28" thru_hole circle
			(at -2.70002 10.16)
			(size 1.1684 1.1684)
			(drill 0.762)
			(layers "*.Cu" "*.Mask")
			(remove_unused_layers no)
			(net "GND")
			(clearance 0.0508)
			(thermal_gap 0.0508)
		)
		(pad "P29" thru_hole circle
			(at -2.70002 7.62)
			(size 1.1684 1.1684)
			(drill 0.762)
			(layers "*.Cu" "*.Mask")
			(remove_unused_layers no)
			(net "GND")
			(clearance 0.0508)
			(thermal_gap 0.0508)
		)
		(pad "P30" thru_hole circle
			(at -2.70002 5.08)
			(size 1.1684 1.1684)
			(drill 0.762)
			(layers "*.Cu" "*.Mask")
			(remove_unused_layers no)
			(net "GND")
			(clearance 0.0508)
			(thermal_gap 0.0508)
		)
		(pad "P31" thru_hole circle
			(at -2.70002 2.54)
			(size 1.1684 1.1684)
			(drill 0.762)
			(layers "*.Cu" "*.Mask")
			(remove_unused_layers no)
			(net "GND")
			(clearance 0.0508)
			(thermal_gap 0.0508)
		)
		(pad "P32" thru_hole circle
			(at -2.70002 0)
			(size 1.1684 1.1684)
			(drill 0.762)
			(layers "*.Cu" "*.Mask")
			(remove_unused_layers no)
			(net "GND")
			(clearance 0.0508)
			(thermal_gap 0.0508)
		)
		(pad "S1" thru_hole circle
			(at 0.55499 41.60012)
			(size 1.1684 1.1684)
			(drill 0.762)
			(layers "*.Cu" "*.Mask")
			(remove_unused_layers no)
			(net "T8_BLAD1_TXD")
			(clearance 0.0508)
			(thermal_gap 0.0508)
		)
		(pad "S2" thru_hole circle
			(at -0.71501 42.87012)
			(size 1.1684 1.1684)
			(drill 0.762)
			(layers "*.Cu" "*.Mask")
			(remove_unused_layers no)
			(net "T8_BLAD1_RXD")
			(clearance 0.0508)
			(thermal_gap 0.0508)
		)
		(pad "S3" thru_hole circle
			(at 0.55499 44.14012)
			(size 1.1684 1.1684)
			(drill 0.762)
			(layers "*.Cu" "*.Mask")
			(remove_unused_layers no)
			(net "T8_BLAD1_EN")
			(clearance 0.0508)
			(thermal_gap 0.0508)
		)
		(pad "S4" thru_hole circle
			(at -0.71501 45.41012)
			(size 1.1684 1.1684)
			(drill 0.762)
			(layers "*.Cu" "*.Mask")
			(remove_unused_layers no)
			(net "T8_BLAD2_EN")
			(clearance 0.0508)
			(thermal_gap 0.0508)
		)
		(pad "S5" thru_hole circle
			(at 0.55499 46.68012)
			(size 1.1684 1.1684)
			(drill 0.762)
			(layers "*.Cu" "*.Mask")
			(remove_unused_layers no)
			(net "T8_BLAD2_TXD")
			(clearance 0.0508)
			(thermal_gap 0.0508)
		)
		(pad "S6" thru_hole circle
			(at -0.71501 47.95012)
			(size 1.1684 1.1684)
			(drill 0.762)
			(layers "*.Cu" "*.Mask")
			(remove_unused_layers no)
			(net "T8_BLAD2_RXD")
			(clearance 0.0508)
			(thermal_gap 0.0508)
		)
		(pad "S7" thru_hole circle
			(at -3.25501 47.95012)
			(size 1.1684 1.1684)
			(drill 0.762)
			(layers "*.Cu" "*.Mask")
			(remove_unused_layers no)
			(net "T8_BLAD4_RXD")
			(clearance 0.0508)
			(thermal_gap 0.0508)
		)
		(pad "S8" thru_hole circle
			(at -1.98501 46.68012)
			(size 1.1684 1.1684)
			(drill 0.762)
			(layers "*.Cu" "*.Mask")
			(remove_unused_layers no)
			(net "T8_BLAD4_TXD")
			(clearance 0.0508)
			(thermal_gap 0.0508)
		)
		(pad "S9" thru_hole circle
			(at -3.25501 45.41012)
			(size 1.1684 1.1684)
			(drill 0.762)
			(layers "*.Cu" "*.Mask")
			(remove_unused_layers no)
			(net "T8_BLAD4_EN")
			(clearance 0.0508)
			(thermal_gap 0.0508)
		)
		(pad "S10" thru_hole circle
			(at -1.98501 44.14012)
			(size 1.1684 1.1684)
			(drill 0.762)
			(layers "*.Cu" "*.Mask")
			(remove_unused_layers no)
			(net "T8_BLAD3_EN")
			(clearance 0.0508)
			(thermal_gap 0.0508)
		)
		(pad "S11" thru_hole circle
			(at -3.25501 42.87012)
			(size 1.1684 1.1684)
			(drill 0.762)
			(layers "*.Cu" "*.Mask")
			(remove_unused_layers no)
			(net "T8_BLAD3_RXD")
			(clearance 0.0508)
			(thermal_gap 0.0508)
		)
		(pad "S12" thru_hole circle
			(at -1.98501 41.60012)
			(size 1.1684 1.1684)
			(drill 0.762)
			(layers "*.Cu" "*.Mask")
			(remove_unused_layers no)
			(net "T8_BLAD3_TXD")
			(clearance 0.0508)
			(thermal_gap 0.0508)
		)
		(zone
			(layer "F.Cu")
			(hatch none 0.5)
			(connect_pads
				(clearance 0)
			)
			(min_thickness 0.25)
			(keepout
				(tracks allowed)
				(vias not_allowed)
				(pads allowed)
				(copperpour not_allowed)
				(footprints allowed)
			)
			(placement
				(enabled no)
				(sheetname "")
			)
			(fill
				(thermal_gap 0.5)
				(thermal_bridge_width 0.5)
				(island_removal_mode 0)
			)
			(polygon
				(pts
					(xy 85.00999 -320.60388) (xy 92.65539 -320.60388) (xy 92.65539 -315.49848) (xy 85.00999 -315.49848)
					(xy 84.98459 -315.49848) (xy 84.98459 -320.60388)
				)
			)
		)
		(zone
			(layer "F.Cu")
			(hatch none 0.5)
			(connect_pads
				(clearance 0)
			)
			(min_thickness 0.25)
			(keepout
				(tracks allowed)
				(vias not_allowed)
				(pads allowed)
				(copperpour not_allowed)
				(footprints allowed)
			)
			(placement
				(enabled no)
				(sheetname "")
			)
			(fill
				(thermal_gap 0.5)
				(thermal_bridge_width 0.5)
				(island_removal_mode 0)
			)
			(polygon
				(pts
					(xy 43.37939 -316.08268) (xy 43.37939 -320.04508) (xy 82.77479 -320.04508) (xy 82.80019 -320.04508)
					(xy 82.80019 -316.08268) (xy 82.80019 -316.05728) (xy 43.37939 -316.05728)
				)
			)
		)
		(zone
			(layers "F.Cu" "B.Cu" "In1.Cu" "In2.Cu" "In3.Cu" "In4.Cu" "In5.Cu" "In6.Cu")
			(hatch none 0.5)
			(connect_pads
				(clearance 0)
			)
			(min_thickness 0.25)
			(keepout
				(tracks not_allowed)
				(vias allowed)
				(pads allowed)
				(copperpour not_allowed)
				(footprints allowed)
			)
			(placement
				(enabled no)
				(sheetname "")
			)
			(fill
				(thermal_gap 0.5)
				(thermal_bridge_width 0.5)
				(island_removal_mode 0)
			)
			(polygon
				(pts
					(arc
						(start 43.18 -318.06007)
						(mid 39.81958 -318.06007)
						(end 43.18 -318.06007)
					)
				)
			)
		)
		(zone
			(layers "F.Cu" "B.Cu" "In1.Cu" "In2.Cu" "In3.Cu" "In4.Cu" "In5.Cu" "In6.Cu")
			(hatch none 0.5)
			(connect_pads
				(clearance 0)
			)
			(min_thickness 0.25)
			(keepout
				(tracks not_allowed)
				(vias allowed)
				(pads allowed)
				(copperpour not_allowed)
				(footprints allowed)
			)
			(placement
				(enabled no)
				(sheetname "")
			)
			(fill
				(thermal_gap 0.5)
				(thermal_bridge_width 0.5)
				(island_removal_mode 0)
			)
			(polygon
				(pts
					(arc
						(start 96.52381 -319.41008)
						(mid 93.15577 -319.41008)
						(end 96.52381 -319.41008)
					)
				)
			)
		)
	)
	(footprint ""
		(layer "B.Cu")
		(at 44.03979 -452.76008 90)
		(property "Reference" "J17"
			(at 6.342888 1.323848 0)
			(unlocked yes)
			(layer "B.SilkS")
			(effects
				(font
					(size 0.7874 0.5842)
					(thickness 0.1524)
				)
				(justify left mirror)
			)
		)
		(property "Value" ""
			(at 0 0 90)
			(layer "B.Fab")
			(effects
				(font
					(size 1.27 1.27)
				)
				(justify mirror)
			)
		)
		(duplicate_pad_numbers_are_jumpers no)
		(fp_line
			(start 5.275072 -13.910056)
			(end -7.975092 -13.910056)
			(stroke
				(width 0.1524)
				(type default)
			)
			(layer "F.SilkS")
		)
		(fp_line
			(start -7.975092 -13.910056)
			(end -7.975092 62.170056)
			(stroke
				(width 0.1524)
				(type default)
			)
			(layer "F.SilkS")
		)
		(fp_line
			(start 5.275072 62.170056)
			(end 5.275072 -13.910056)
			(stroke
				(width 0.1524)
				(type default)
			)
			(layer "F.SilkS")
		)
		(fp_line
			(start -7.975092 62.170056)
			(end 5.275072 62.170056)
			(stroke
				(width 0.1524)
				(type default)
			)
			(layer "F.SilkS")
		)
		(fp_line
			(start 5.275072 -13.910056)
			(end -7.975092 -13.910056)
			(stroke
				(width 0.1524)
				(type default)
			)
			(layer "B.SilkS")
		)
		(fp_line
			(start -7.975092 -13.910056)
			(end -7.975092 62.170056)
			(stroke
				(width 0.1524)
				(type default)
			)
			(layer "B.SilkS")
		)
		(fp_line
			(start 2.275078 -10.910062)
			(end 2.275078 59.170062)
			(stroke
				(width 0.1524)
				(type default)
			)
			(layer "B.SilkS")
		)
		(fp_line
			(start -4.975098 -10.910062)
			(end 2.275078 -10.910062)
			(stroke
				(width 0.1524)
				(type default)
			)
			(layer "B.SilkS")
		)
		(fp_line
			(start 2.275078 59.170062)
			(end -4.975098 59.170062)
			(stroke
				(width 0.1524)
				(type default)
			)
			(layer "B.SilkS")
		)
		(fp_line
			(start -4.975098 59.170062)
			(end -4.975098 -10.910062)
			(stroke
				(width 0.1524)
				(type default)
			)
			(layer "B.SilkS")
		)
		(fp_line
			(start 5.275072 62.170056)
			(end 5.275072 -13.910056)
			(stroke
				(width 0.1524)
				(type default)
			)
			(layer "B.SilkS")
		)
		(fp_line
			(start -7.975092 62.170056)
			(end 5.275072 62.170056)
			(stroke
				(width 0.1524)
				(type default)
			)
			(layer "B.SilkS")
		)
		(fp_poly
			(pts
				(xy 4.103878 -0.759206) (xy 4.103878 0.764794) (xy 2.579878 0.002794)
			)
			(stroke
				(width 0)
				(type default)
			)
			(fill yes)
			(layer "B.SilkS")
		)
		(fp_poly
			(pts
				(xy 2.275078 -10.910062) (xy 2.275078 59.170062) (xy -4.975098 59.170062) (xy -4.975098 -10.910062)
			)
			(stroke
				(width 0)
				(type default)
			)
			(fill no)
			(layer "B.CrtYd")
		)
		(fp_poly
			(pts
				(xy 1.1938 40.9702) (xy 1.1938 48.6156) (xy -3.9116 48.6156) (xy -3.9116 40.9702) (xy -3.9116 40.9448)
				(xy 1.1938 40.9448)
			)
			(stroke
				(width 0)
				(type default)
			)
			(fill no)
			(layer "F.CrtYd")
		)
		(fp_poly
			(pts
				(xy -3.3274 -0.6604) (xy 0.635 -0.6604) (xy 0.635 38.735) (xy 0.635 38.7604) (xy -3.3274 38.7604)
				(xy -3.3528 38.7604) (xy -3.3528 -0.6604)
			)
			(stroke
				(width 0)
				(type default)
			)
			(fill no)
			(layer "F.CrtYd")
		)
		(fp_poly
			(pts
				(arc
					(start -1.35001 -1.01219)
					(mid -1.35001 -4.06781)
					(end -1.35001 -1.01219)
				)
			)
			(stroke
				(width 0)
				(type default)
			)
			(fill no)
			(layer "F.CrtYd")
		)
		(fp_poly
			(pts
				(arc
					(start 0 52.33162)
					(mid 0 49.26838)
					(end 0 52.33162)
				)
			)
			(stroke
				(width 0)
				(type default)
			)
			(fill no)
			(layer "F.CrtYd")
		)
		(fp_line
			(start 2.275078 -10.910062)
			(end 2.275078 59.170062)
			(stroke
				(width 0.1)
				(type default)
			)
			(layer "B.Fab")
		)
		(fp_line
			(start -4.975098 -10.910062)
			(end 2.275078 -10.910062)
			(stroke
				(width 0.1)
				(type default)
			)
			(layer "B.Fab")
		)
		(fp_line
			(start 2.275078 59.170062)
			(end -4.975098 59.170062)
			(stroke
				(width 0.1)
				(type default)
			)
			(layer "B.Fab")
		)
		(fp_line
			(start -4.975098 59.170062)
			(end -4.975098 -10.910062)
			(stroke
				(width 0.1)
				(type default)
			)
			(layer "B.Fab")
		)
		(fp_poly
			(pts
				(xy 4.103878 -0.759206) (xy 4.103878 0.764794) (xy 2.579878 0.002794)
			)
			(stroke
				(width 0)
				(type default)
			)
			(fill yes)
			(layer "B.Fab")
		)
		(fp_line
			(start 5.275072 -13.910056)
			(end -7.975092 -13.910056)
			(stroke
				(width 0.1)
				(type default)
			)
			(layer "F.Fab")
		)
		(fp_line
			(start -7.975092 -13.910056)
			(end -7.975092 62.170056)
			(stroke
				(width 0.1)
				(type default)
			)
			(layer "F.Fab")
		)
		(fp_line
			(start 5.275072 62.170056)
			(end 5.275072 -13.910056)
			(stroke
				(width 0.1)
				(type default)
			)
			(layer "F.Fab")
		)
		(fp_line
			(start -7.975092 62.170056)
			(end 5.275072 62.170056)
			(stroke
				(width 0.1)
				(type default)
			)
			(layer "F.Fab")
		)
		(fp_text user "P32"
			(at -4.197096 -0.0254 0)
			(unlocked yes)
			(layer "F.SilkS")
			(effects
				(font
					(size 0.7874 0.5842)
					(thickness 0.1524)
				)
			)
		)
		(fp_text user "P1"
			(at 1.519936 0.06858 0)
			(unlocked yes)
			(layer "F.SilkS")
			(effects
				(font
					(size 0.7874 0.5842)
					(thickness 0.1524)
				)
			)
		)
		(fp_text user "PRESS-FIT"
			(at -9.413748 16.821912 0)
			(unlocked yes)
			(layer "F.SilkS")
			(effects
				(font
					(size 0.7874 0.5842)
					(thickness 0.1524)
				)
				(justify left)
			)
		)
		(fp_text user "P17"
			(at -9.424924 37.42436 0)
			(unlocked yes)
			(layer "F.SilkS")
			(effects
				(font
					(size 0.7874 0.5842)
					(thickness 0.1524)
				)
			)
		)
		(fp_text user "P16"
			(at 6.03758 39.340028 0)
			(unlocked yes)
			(layer "F.SilkS")
			(effects
				(font
					(size 0.7874 0.5842)
					(thickness 0.1524)
				)
			)
		)
		(fp_text user "S12"
			(at -9.360662 40.654224 0)
			(unlocked yes)
			(layer "F.SilkS")
			(effects
				(font
					(size 0.7874 0.5842)
					(thickness 0.1524)
				)
			)
		)
		(fp_text user "S1"
			(at 6.61162 42.942002 0)
			(unlocked yes)
			(layer "F.SilkS")
			(effects
				(font
					(size 0.7874 0.5842)
					(thickness 0.1524)
				)
			)
		)
		(fp_text user "S7"
			(at -9.467088 47.575216 0)
			(unlocked yes)
			(layer "F.SilkS")
			(effects
				(font
					(size 0.7874 0.5842)
					(thickness 0.1524)
				)
			)
		)
		(fp_text user "S6"
			(at 6.098286 48.259238 0)
			(unlocked yes)
			(layer "F.SilkS")
			(effects
				(font
					(size 0.7874 0.5842)
					(thickness 0.1524)
				)
			)
		)
		(fp_text user "P1"
			(at 3.034538 -1.521714 0)
			(unlocked yes)
			(layer "B.SilkS")
			(effects
				(font
					(size 0.7874 0.5842)
					(thickness 0.1524)
				)
				(justify mirror)
			)
		)
		(fp_text user "P32"
			(at -5.885688 0.255524 0)
			(unlocked yes)
			(layer "B.SilkS")
			(effects
				(font
					(size 0.7874 0.5842)
					(thickness 0.1524)
				)
				(justify mirror)
			)
		)
		(fp_text user "PRESS-FIT"
			(at -7.18947 29.8831 0)
			(unlocked yes)
			(layer "B.SilkS")
			(effects
				(font
					(size 0.7874 0.5842)
					(thickness 0.1524)
				)
				(justify left mirror)
			)
		)
		(fp_text user "P17"
			(at -5.813806 37.83203 0)
			(unlocked yes)
			(layer "B.SilkS")
			(effects
				(font
					(size 0.7874 0.5842)
					(thickness 0.1524)
				)
				(justify mirror)
			)
		)
		(fp_text user "P16"
			(at 3.187954 38.140132 0)
			(unlocked yes)
			(layer "B.SilkS")
			(effects
				(font
					(size 0.7874 0.5842)
					(thickness 0.1524)
				)
				(justify mirror)
			)
		)
		(fp_text user "S12"
			(at -5.741162 41.908222 0)
			(unlocked yes)
			(layer "B.SilkS")
			(effects
				(font
					(size 0.7874 0.5842)
					(thickness 0.1524)
				)
				(justify mirror)
			)
		)
		(fp_text user "S1"
			(at 3.080512 42.117264 0)
			(unlocked yes)
			(layer "B.SilkS")
			(effects
				(font
					(size 0.7874 0.5842)
					(thickness 0.1524)
				)
				(justify mirror)
			)
		)
		(fp_text user "S7"
			(at -5.855716 48.15459 0)
			(unlocked yes)
			(layer "B.SilkS")
			(effects
				(font
					(size 0.7874 0.5842)
					(thickness 0.1524)
				)
				(justify mirror)
			)
		)
		(fp_text user "S6"
			(at 2.941066 48.35906 0)
			(unlocked yes)
			(layer "B.SilkS")
			(effects
				(font
					(size 0.7874 0.5842)
					(thickness 0.1524)
				)
				(justify mirror)
			)
		)
		(fp_text user "P1"
			(at 3.108452 -1.27 180)
			(unlocked yes)
			(layer "B.Fab")
			(effects
				(font
					(size 0.7874 0.5842)
					(thickness 0.000001)
				)
				(justify mirror)
			)
		)
		(fp_text user "P32"
			(at -5.781548 -0.0508 180)
			(unlocked yes)
			(layer "B.Fab")
			(effects
				(font
					(size 0.7874 0.5842)
					(thickness 0.000001)
				)
				(justify mirror)
			)
		)
		(fp_text user "PRESS-FIT"
			(at -6.82371 29.8831 0)
			(unlocked yes)
			(layer "B.Fab")
			(effects
				(font
					(size 1.6002 1.1938)
					(thickness 0.000001)
				)
				(justify left mirror)
			)
		)
		(fp_text user "P17"
			(at -5.72135 38.0746 180)
			(unlocked yes)
			(layer "B.Fab")
			(effects
				(font
					(size 0.7874 0.5842)
					(thickness 0.000001)
				)
				(justify mirror)
			)
		)
		(fp_text user "P16"
			(at 3.159252 38.3794 180)
			(unlocked yes)
			(layer "B.Fab")
			(effects
				(font
					(size 0.7874 0.5842)
					(thickness 0.000001)
				)
				(justify mirror)
			)
		)
		(fp_text user "S12"
			(at -5.79374 41.42232 180)
			(unlocked yes)
			(layer "B.Fab")
			(effects
				(font
					(size 0.7874 0.5842)
					(thickness 0.000001)
				)
				(justify mirror)
			)
		)
		(fp_text user "S1"
			(at 3.09626 41.656 180)
			(unlocked yes)
			(layer "B.Fab")
			(effects
				(font
					(size 0.7874 0.5842)
					(thickness 0.000001)
				)
				(justify mirror)
			)
		)
		(fp_text user "S6"
			(at 3.133852 48.0822 180)
			(unlocked yes)
			(layer "B.Fab")
			(effects
				(font
					(size 0.7874 0.5842)
					(thickness 0.000001)
				)
				(justify mirror)
			)
		)
		(fp_text user "S7"
			(at -5.781548 48.0822 180)
			(unlocked yes)
			(layer "B.Fab")
			(effects
				(font
					(size 0.7874 0.5842)
					(thickness 0.000001)
				)
				(justify mirror)
			)
		)
		(fp_text user "P32"
			(at -4.071112 -0.0762 180)
			(unlocked yes)
			(layer "F.Fab")
			(effects
				(font
					(size 0.7874 0.5842)
					(thickness 0.000001)
				)
			)
		)
		(fp_text user "P1"
			(at 1.516888 0 180)
			(unlocked yes)
			(layer "F.Fab")
			(effects
				(font
					(size 0.7874 0.5842)
					(thickness 0.000001)
				)
			)
		)
		(fp_text user "PRESS-FIT"
			(at -6.762496 16.251428 0)
			(unlocked yes)
			(layer "F.Fab")
			(effects
				(font
					(size 1.6002 1.1938)
					(thickness 0.000001)
				)
				(justify left)
			)
		)
		(fp_text user "P17"
			(at -4.366768 38.227 180)
			(unlocked yes)
			(layer "F.Fab")
			(effects
				(font
					(size 0.7874 0.5842)
					(thickness 0.000001)
				)
			)
		)
		(fp_text user "P16"
			(at 2.228088 38.354 180)
			(unlocked yes)
			(layer "F.Fab")
			(effects
				(font
					(size 0.7874 0.5842)
					(thickness 0.000001)
				)
			)
		)
		(fp_text user "S12"
			(at -4.362958 41.09212 180)
			(unlocked yes)
			(layer "F.Fab")
			(effects
				(font
					(size 0.7874 0.5842)
					(thickness 0.000001)
				)
			)
		)
		(fp_text user "S1"
			(at 2.164842 41.6306 180)
			(unlocked yes)
			(layer "F.Fab")
			(effects
				(font
					(size 0.7874 0.5842)
					(thickness 0.000001)
				)
			)
		)
		(fp_text user "S6"
			(at 1.923288 48.133 180)
			(unlocked yes)
			(layer "F.Fab")
			(effects
				(font
					(size 0.7874 0.5842)
					(thickness 0.000001)
				)
			)
		)
		(fp_text user "S7"
			(at -4.426712 48.2346 180)
			(unlocked yes)
			(layer "F.Fab")
			(effects
				(font
					(size 0.7874 0.5842)
					(thickness 0.000001)
				)
			)
		)
		(pad "" np_thru_hole circle
			(at -1.35001 -2.54)
			(size 2.5146 2.5146)
			(drill 2.5146)
			(layers "*.Cu" "*.Mask")
			(clearance 0.381)
			(thermal_gap 0.381)
		)
		(pad "" np_thru_hole circle
			(at 0 50.8)
			(size 2.5146 2.5146)
			(drill 2.5146)
			(layers "*.Cu" "*.Mask")
			(clearance 0.381)
			(thermal_gap 0.381)
		)
		(pad "P1" thru_hole rect
			(at 0 0)
			(size 1.1684 1.1684)
			(drill 0.762)
			(layers "*.Cu" "*.Mask")
			(remove_unused_layers no)
			(net "GND")
			(clearance 0.0508)
			(padstack
				(mode front_inner_back)
				(layer "Inner"
					(shape circle)
					(size 1.1684 1.1684)
					(clearance 0.0508)
				)
				(layer "B.Cu"
					(shape rect)
					(size 1.1684 1.1684)
					(thermal_gap 0.0508)
					(clearance 0.0508)
				)
			)
		)
		(pad "P2" thru_hole circle
			(at 0 2.54)
			(size 1.1684 1.1684)
			(drill 0.762)
			(layers "*.Cu" "*.Mask")
			(remove_unused_layers no)
			(net "GND")
			(clearance 0.0508)
			(thermal_gap 0.0508)
		)
		(pad "P3" thru_hole circle
			(at 0 5.08)
			(size 1.1684 1.1684)
			(drill 0.762)
			(layers "*.Cu" "*.Mask")
			(remove_unused_layers no)
			(net "GND")
			(clearance 0.0508)
			(thermal_gap 0.0508)
		)
		(pad "P4" thru_hole circle
			(at 0 7.62)
			(size 1.1684 1.1684)
			(drill 0.762)
			(layers "*.Cu" "*.Mask")
			(remove_unused_layers no)
			(net "GND")
			(clearance 0.0508)
			(thermal_gap 0.0508)
		)
		(pad "P5" thru_hole circle
			(at 0 10.16)
			(size 1.1684 1.1684)
			(drill 0.762)
			(layers "*.Cu" "*.Mask")
			(remove_unused_layers no)
			(net "GND")
			(clearance 0.0508)
			(thermal_gap 0.0508)
		)
		(pad "P6" thru_hole circle
			(at 0 12.7)
			(size 1.1684 1.1684)
			(drill 0.762)
			(layers "*.Cu" "*.Mask")
			(remove_unused_layers no)
			(net "GND")
			(clearance 0.0508)
			(thermal_gap 0.0508)
		)
		(pad "P7" thru_hole circle
			(at 0 15.24)
			(size 1.1684 1.1684)
			(drill 0.762)
			(layers "*.Cu" "*.Mask")
			(remove_unused_layers no)
			(net "GND")
			(clearance 0.0508)
			(thermal_gap 0.0508)
		)
		(pad "P8" thru_hole circle
			(at 0 17.78)
			(size 1.1684 1.1684)
			(drill 0.762)
			(layers "*.Cu" "*.Mask")
			(remove_unused_layers no)
			(net "GND")
			(clearance 0.0508)
			(thermal_gap 0.0508)
		)
		(pad "P9" thru_hole circle
			(at 0 20.32)
			(size 1.1684 1.1684)
			(drill 0.762)
			(layers "*.Cu" "*.Mask")
			(remove_unused_layers no)
			(net "P12V")
			(clearance 0.0508)
			(thermal_gap 0.0508)
		)
		(pad "P10" thru_hole circle
			(at 0 22.86)
			(size 1.1684 1.1684)
			(drill 0.762)
			(layers "*.Cu" "*.Mask")
			(remove_unused_layers no)
			(net "P12V")
			(clearance 0.0508)
			(thermal_gap 0.0508)
		)
		(pad "P11" thru_hole circle
			(at 0 25.4)
			(size 1.1684 1.1684)
			(drill 0.762)
			(layers "*.Cu" "*.Mask")
			(remove_unused_layers no)
			(net "P12V")
			(clearance 0.0508)
			(thermal_gap 0.0508)
		)
		(pad "P12" thru_hole circle
			(at 0 27.94)
			(size 1.1684 1.1684)
			(drill 0.762)
			(layers "*.Cu" "*.Mask")
			(remove_unused_layers no)
			(net "P12V")
			(clearance 0.0508)
			(thermal_gap 0.0508)
		)
		(pad "P13" thru_hole circle
			(at 0 30.48)
			(size 1.1684 1.1684)
			(drill 0.762)
			(layers "*.Cu" "*.Mask")
			(remove_unused_layers no)
			(net "P12V")
			(clearance 0.0508)
			(thermal_gap 0.0508)
		)
		(pad "P14" thru_hole circle
			(at 0 33.02)
			(size 1.1684 1.1684)
			(drill 0.762)
			(layers "*.Cu" "*.Mask")
			(remove_unused_layers no)
			(net "P12V")
			(clearance 0.0508)
			(thermal_gap 0.0508)
		)
		(pad "P15" thru_hole circle
			(at 0 35.56)
			(size 1.1684 1.1684)
			(drill 0.762)
			(layers "*.Cu" "*.Mask")
			(remove_unused_layers no)
			(net "P12V")
			(clearance 0.0508)
			(thermal_gap 0.0508)
		)
		(pad "P16" thru_hole circle
			(at 0 38.1)
			(size 1.1684 1.1684)
			(drill 0.762)
			(layers "*.Cu" "*.Mask")
			(remove_unused_layers no)
			(net "P12V")
			(clearance 0.0508)
			(thermal_gap 0.0508)
		)
		(pad "P17" thru_hole circle
			(at -2.70002 38.1)
			(size 1.1684 1.1684)
			(drill 0.762)
			(layers "*.Cu" "*.Mask")
			(remove_unused_layers no)
			(net "P12V")
			(clearance 0.0508)
			(thermal_gap 0.0508)
		)
		(pad "P18" thru_hole circle
			(at -2.70002 35.56)
			(size 1.1684 1.1684)
			(drill 0.762)
			(layers "*.Cu" "*.Mask")
			(remove_unused_layers no)
			(net "P12V")
			(clearance 0.0508)
			(thermal_gap 0.0508)
		)
		(pad "P19" thru_hole circle
			(at -2.70002 33.02)
			(size 1.1684 1.1684)
			(drill 0.762)
			(layers "*.Cu" "*.Mask")
			(remove_unused_layers no)
			(net "P12V")
			(clearance 0.0508)
			(thermal_gap 0.0508)
		)
		(pad "P20" thru_hole circle
			(at -2.70002 30.48)
			(size 1.1684 1.1684)
			(drill 0.762)
			(layers "*.Cu" "*.Mask")
			(remove_unused_layers no)
			(net "P12V")
			(clearance 0.0508)
			(thermal_gap 0.0508)
		)
		(pad "P21" thru_hole circle
			(at -2.70002 27.94)
			(size 1.1684 1.1684)
			(drill 0.762)
			(layers "*.Cu" "*.Mask")
			(remove_unused_layers no)
			(net "P12V")
			(clearance 0.0508)
			(thermal_gap 0.0508)
		)
		(pad "P22" thru_hole circle
			(at -2.70002 25.4)
			(size 1.1684 1.1684)
			(drill 0.762)
			(layers "*.Cu" "*.Mask")
			(remove_unused_layers no)
			(net "P12V")
			(clearance 0.0508)
			(thermal_gap 0.0508)
		)
		(pad "P23" thru_hole circle
			(at -2.70002 22.86)
			(size 1.1684 1.1684)
			(drill 0.762)
			(layers "*.Cu" "*.Mask")
			(remove_unused_layers no)
			(net "P12V")
			(clearance 0.0508)
			(thermal_gap 0.0508)
		)
		(pad "P24" thru_hole circle
			(at -2.70002 20.32)
			(size 1.1684 1.1684)
			(drill 0.762)
			(layers "*.Cu" "*.Mask")
			(remove_unused_layers no)
			(net "P12V")
			(clearance 0.0508)
			(thermal_gap 0.0508)
		)
		(pad "P25" thru_hole circle
			(at -2.70002 17.78)
			(size 1.1684 1.1684)
			(drill 0.762)
			(layers "*.Cu" "*.Mask")
			(remove_unused_layers no)
			(net "GND")
			(clearance 0.0508)
			(thermal_gap 0.0508)
		)
		(pad "P26" thru_hole circle
			(at -2.70002 15.24)
			(size 1.1684 1.1684)
			(drill 0.762)
			(layers "*.Cu" "*.Mask")
			(remove_unused_layers no)
			(net "GND")
			(clearance 0.0508)
			(thermal_gap 0.0508)
		)
		(pad "P27" thru_hole circle
			(at -2.70002 12.7)
			(size 1.1684 1.1684)
			(drill 0.762)
			(layers "*.Cu" "*.Mask")
			(remove_unused_layers no)
			(net "GND")
			(clearance 0.0508)
			(thermal_gap 0.0508)
		)
		(pad "P28" thru_hole circle
			(at -2.70002 10.16)
			(size 1.1684 1.1684)
			(drill 0.762)
			(layers "*.Cu" "*.Mask")
			(remove_unused_layers no)
			(net "GND")
			(clearance 0.0508)
			(thermal_gap 0.0508)
		)
		(pad "P29" thru_hole circle
			(at -2.70002 7.62)
			(size 1.1684 1.1684)
			(drill 0.762)
			(layers "*.Cu" "*.Mask")
			(remove_unused_layers no)
			(net "GND")
			(clearance 0.0508)
			(thermal_gap 0.0508)
		)
		(pad "P30" thru_hole circle
			(at -2.70002 5.08)
			(size 1.1684 1.1684)
			(drill 0.762)
			(layers "*.Cu" "*.Mask")
			(remove_unused_layers no)
			(net "GND")
			(clearance 0.0508)
			(thermal_gap 0.0508)
		)
		(pad "P31" thru_hole circle
			(at -2.70002 2.54)
			(size 1.1684 1.1684)
			(drill 0.762)
			(layers "*.Cu" "*.Mask")
			(remove_unused_layers no)
			(net "GND")
			(clearance 0.0508)
			(thermal_gap 0.0508)
		)
		(pad "P32" thru_hole circle
			(at -2.70002 0)
			(size 1.1684 1.1684)
			(drill 0.762)
			(layers "*.Cu" "*.Mask")
			(remove_unused_layers no)
			(net "GND")
			(clearance 0.0508)
			(thermal_gap 0.0508)
		)
		(pad "S1" thru_hole circle
			(at 0.55499 41.60012)
			(size 1.1684 1.1684)
			(drill 0.762)
			(layers "*.Cu" "*.Mask")
			(remove_unused_layers no)
			(net "T11_BLAD1_TXD")
			(clearance 0.0508)
			(thermal_gap 0.0508)
		)
		(pad "S2" thru_hole circle
			(at -0.71501 42.87012)
			(size 1.1684 1.1684)
			(drill 0.762)
			(layers "*.Cu" "*.Mask")
			(remove_unused_layers no)
			(net "T11_BLAD1_RXD")
			(clearance 0.0508)
			(thermal_gap 0.0508)
		)
		(pad "S3" thru_hole circle
			(at 0.55499 44.14012)
			(size 1.1684 1.1684)
			(drill 0.762)
			(layers "*.Cu" "*.Mask")
			(remove_unused_layers no)
			(net "T11_BLAD1_EN")
			(clearance 0.0508)
			(thermal_gap 0.0508)
		)
		(pad "S4" thru_hole circle
			(at -0.71501 45.41012)
			(size 1.1684 1.1684)
			(drill 0.762)
			(layers "*.Cu" "*.Mask")
			(remove_unused_layers no)
			(net "T11_BLAD2_EN")
			(clearance 0.0508)
			(thermal_gap 0.0508)
		)
		(pad "S5" thru_hole circle
			(at 0.55499 46.68012)
			(size 1.1684 1.1684)
			(drill 0.762)
			(layers "*.Cu" "*.Mask")
			(remove_unused_layers no)
			(net "T11_BLAD2_TXD")
			(clearance 0.0508)
			(thermal_gap 0.0508)
		)
		(pad "S6" thru_hole circle
			(at -0.71501 47.95012)
			(size 1.1684 1.1684)
			(drill 0.762)
			(layers "*.Cu" "*.Mask")
			(remove_unused_layers no)
			(net "T11_BLAD2_RXD")
			(clearance 0.0508)
			(thermal_gap 0.0508)
		)
		(pad "S7" thru_hole circle
			(at -3.25501 47.95012)
			(size 1.1684 1.1684)
			(drill 0.762)
			(layers "*.Cu" "*.Mask")
			(remove_unused_layers no)
			(net "T11_BLAD4_RXD")
			(clearance 0.0508)
			(thermal_gap 0.0508)
		)
		(pad "S8" thru_hole circle
			(at -1.98501 46.68012)
			(size 1.1684 1.1684)
			(drill 0.762)
			(layers "*.Cu" "*.Mask")
			(remove_unused_layers no)
			(net "T11_BLAD4_TXD")
			(clearance 0.0508)
			(thermal_gap 0.0508)
		)
		(pad "S9" thru_hole circle
			(at -3.25501 45.41012)
			(size 1.1684 1.1684)
			(drill 0.762)
			(layers "*.Cu" "*.Mask")
			(remove_unused_layers no)
			(net "T11_BLAD4_EN")
			(clearance 0.0508)
			(thermal_gap 0.0508)
		)
		(pad "S10" thru_hole circle
			(at -1.98501 44.14012)
			(size 1.1684 1.1684)
			(drill 0.762)
			(layers "*.Cu" "*.Mask")
			(remove_unused_layers no)
			(net "T11_BLAD3_EN")
			(clearance 0.0508)
			(thermal_gap 0.0508)
		)
		(pad "S11" thru_hole circle
			(at -3.25501 42.87012)
			(size 1.1684 1.1684)
			(drill 0.762)
			(layers "*.Cu" "*.Mask")
			(remove_unused_layers no)
			(net "T11_BLAD3_RXD")
			(clearance 0.0508)
			(thermal_gap 0.0508)
		)
		(pad "S12" thru_hole circle
			(at -1.98501 41.60012)
			(size 1.1684 1.1684)
			(drill 0.762)
			(layers "*.Cu" "*.Mask")
			(remove_unused_layers no)
			(net "T11_BLAD3_TXD")
			(clearance 0.0508)
			(thermal_gap 0.0508)
		)
		(zone
			(layer "F.Cu")
			(hatch none 0.5)
			(connect_pads
				(clearance 0)
			)
			(min_thickness 0.25)
			(keepout
				(tracks allowed)
				(vias not_allowed)
				(pads allowed)
				(copperpour not_allowed)
				(footprints allowed)
			)
			(placement
				(enabled no)
				(sheetname "")
			)
			(fill
				(thermal_gap 0.5)
				(thermal_bridge_width 0.5)
				(island_removal_mode 0)
			)
			(polygon
				(pts
					(xy 85.00999 -453.95388) (xy 92.65539 -453.95388) (xy 92.65539 -448.84848) (xy 85.00999 -448.84848)
					(xy 84.98459 -448.84848) (xy 84.98459 -453.95388)
				)
			)
		)
		(zone
			(layer "F.Cu")
			(hatch none 0.5)
			(connect_pads
				(clearance 0)
			)
			(min_thickness 0.25)
			(keepout
				(tracks allowed)
				(vias not_allowed)
				(pads allowed)
				(copperpour not_allowed)
				(footprints allowed)
			)
			(placement
				(enabled no)
				(sheetname "")
			)
			(fill
				(thermal_gap 0.5)
				(thermal_bridge_width 0.5)
				(island_removal_mode 0)
			)
			(polygon
				(pts
					(xy 43.37939 -449.43268) (xy 43.37939 -453.39508) (xy 82.77479 -453.39508) (xy 82.80019 -453.39508)
					(xy 82.80019 -449.43268) (xy 82.80019 -449.40728) (xy 43.37939 -449.40728)
				)
			)
		)
		(zone
			(layers "F.Cu" "B.Cu" "In1.Cu" "In2.Cu" "In3.Cu" "In4.Cu" "In5.Cu" "In6.Cu")
			(hatch none 0.5)
			(connect_pads
				(clearance 0)
			)
			(min_thickness 0.25)
			(keepout
				(tracks not_allowed)
				(vias allowed)
				(pads allowed)
				(copperpour not_allowed)
				(footprints allowed)
			)
			(placement
				(enabled no)
				(sheetname "")
			)
			(fill
				(thermal_gap 0.5)
				(thermal_bridge_width 0.5)
				(island_removal_mode 0)
			)
			(polygon
				(pts
					(arc
						(start 43.18 -451.41007)
						(mid 39.81958 -451.41007)
						(end 43.18 -451.41007)
					)
				)
			)
		)
		(zone
			(layers "F.Cu" "B.Cu" "In1.Cu" "In2.Cu" "In3.Cu" "In4.Cu" "In5.Cu" "In6.Cu")
			(hatch none 0.5)
			(connect_pads
				(clearance 0)
			)
			(min_thickness 0.25)
			(keepout
				(tracks not_allowed)
				(vias allowed)
				(pads allowed)
				(copperpour not_allowed)
				(footprints allowed)
			)
			(placement
				(enabled no)
				(sheetname "")
			)
			(fill
				(thermal_gap 0.5)
				(thermal_bridge_width 0.5)
				(island_removal_mode 0)
			)
			(polygon
				(pts
					(arc
						(start 96.52381 -452.76008)
						(mid 93.15577 -452.76008)
						(end 96.52381 -452.76008)
					)
				)
			)
		)
	)
	(footprint ""
		(layer "B.Cu")
		(at 44.03979 -363.86008 90)
		(property "Reference" "J15"
			(at 6.521196 -4.437888 0)
			(unlocked yes)
			(layer "B.SilkS")
			(effects
				(font
					(size 0.7874 0.5842)
					(thickness 0.1524)
				)
				(justify left mirror)
			)
		)
		(property "Value" ""
			(at 0 0 90)
			(layer "B.Fab")
			(effects
				(font
					(size 1.27 1.27)
				)
				(justify mirror)
			)
		)
		(duplicate_pad_numbers_are_jumpers no)
		(fp_line
			(start 5.275072 -13.910056)
			(end -7.975092 -13.910056)
			(stroke
				(width 0.1524)
				(type default)
			)
			(layer "F.SilkS")
		)
		(fp_line
			(start -7.975092 -13.910056)
			(end -7.975092 62.170056)
			(stroke
				(width 0.1524)
				(type default)
			)
			(layer "F.SilkS")
		)
		(fp_line
			(start 5.275072 62.170056)
			(end 5.275072 -13.910056)
			(stroke
				(width 0.1524)
				(type default)
			)
			(layer "F.SilkS")
		)
		(fp_line
			(start -7.975092 62.170056)
			(end 5.275072 62.170056)
			(stroke
				(width 0.1524)
				(type default)
			)
			(layer "F.SilkS")
		)
		(fp_line
			(start 5.275072 -13.910056)
			(end -7.975092 -13.910056)
			(stroke
				(width 0.1524)
				(type default)
			)
			(layer "B.SilkS")
		)
		(fp_line
			(start -7.975092 -13.910056)
			(end -7.975092 62.170056)
			(stroke
				(width 0.1524)
				(type default)
			)
			(layer "B.SilkS")
		)
		(fp_line
			(start 2.275078 -10.910062)
			(end 2.275078 59.170062)
			(stroke
				(width 0.1524)
				(type default)
			)
			(layer "B.SilkS")
		)
		(fp_line
			(start -4.975098 -10.910062)
			(end 2.275078 -10.910062)
			(stroke
				(width 0.1524)
				(type default)
			)
			(layer "B.SilkS")
		)
		(fp_line
			(start 2.275078 59.170062)
			(end -4.975098 59.170062)
			(stroke
				(width 0.1524)
				(type default)
			)
			(layer "B.SilkS")
		)
		(fp_line
			(start -4.975098 59.170062)
			(end -4.975098 -10.910062)
			(stroke
				(width 0.1524)
				(type default)
			)
			(layer "B.SilkS")
		)
		(fp_line
			(start 5.275072 62.170056)
			(end 5.275072 -13.910056)
			(stroke
				(width 0.1524)
				(type default)
			)
			(layer "B.SilkS")
		)
		(fp_line
			(start -7.975092 62.170056)
			(end 5.275072 62.170056)
			(stroke
				(width 0.1524)
				(type default)
			)
			(layer "B.SilkS")
		)
		(fp_poly
			(pts
				(xy 4.103878 -0.759206) (xy 4.103878 0.764794) (xy 2.579878 0.002794)
			)
			(stroke
				(width 0)
				(type default)
			)
			(fill yes)
			(layer "B.SilkS")
		)
		(fp_poly
			(pts
				(xy 2.275078 -10.910062) (xy 2.275078 59.170062) (xy -4.975098 59.170062) (xy -4.975098 -10.910062)
			)
			(stroke
				(width 0)
				(type default)
			)
			(fill no)
			(layer "B.CrtYd")
		)
		(fp_poly
			(pts
				(xy 1.1938 40.9702) (xy 1.1938 48.6156) (xy -3.9116 48.6156) (xy -3.9116 40.9702) (xy -3.9116 40.9448)
				(xy 1.1938 40.9448)
			)
			(stroke
				(width 0)
				(type default)
			)
			(fill no)
			(layer "F.CrtYd")
		)
		(fp_poly
			(pts
				(xy -3.3274 -0.6604) (xy 0.635 -0.6604) (xy 0.635 38.735) (xy 0.635 38.7604) (xy -3.3274 38.7604)
				(xy -3.3528 38.7604) (xy -3.3528 -0.6604)
			)
			(stroke
				(width 0)
				(type default)
			)
			(fill no)
			(layer "F.CrtYd")
		)
		(fp_poly
			(pts
				(arc
					(start -1.35001 -1.01219)
					(mid -1.35001 -4.06781)
					(end -1.35001 -1.01219)
				)
			)
			(stroke
				(width 0)
				(type default)
			)
			(fill no)
			(layer "F.CrtYd")
		)
		(fp_poly
			(pts
				(arc
					(start 0 52.33162)
					(mid 0 49.26838)
					(end 0 52.33162)
				)
			)
			(stroke
				(width 0)
				(type default)
			)
			(fill no)
			(layer "F.CrtYd")
		)
		(fp_line
			(start 2.275078 -10.910062)
			(end 2.275078 59.170062)
			(stroke
				(width 0.1)
				(type default)
			)
			(layer "B.Fab")
		)
		(fp_line
			(start -4.975098 -10.910062)
			(end 2.275078 -10.910062)
			(stroke
				(width 0.1)
				(type default)
			)
			(layer "B.Fab")
		)
		(fp_line
			(start 2.275078 59.170062)
			(end -4.975098 59.170062)
			(stroke
				(width 0.1)
				(type default)
			)
			(layer "B.Fab")
		)
		(fp_line
			(start -4.975098 59.170062)
			(end -4.975098 -10.910062)
			(stroke
				(width 0.1)
				(type default)
			)
			(layer "B.Fab")
		)
		(fp_poly
			(pts
				(xy 4.103878 -0.759206) (xy 4.103878 0.764794) (xy 2.579878 0.002794)
			)
			(stroke
				(width 0)
				(type default)
			)
			(fill yes)
			(layer "B.Fab")
		)
		(fp_line
			(start 5.275072 -13.910056)
			(end -7.975092 -13.910056)
			(stroke
				(width 0.1)
				(type default)
			)
			(layer "F.Fab")
		)
		(fp_line
			(start -7.975092 -13.910056)
			(end -7.975092 62.170056)
			(stroke
				(width 0.1)
				(type default)
			)
			(layer "F.Fab")
		)
		(fp_line
			(start 5.275072 62.170056)
			(end 5.275072 -13.910056)
			(stroke
				(width 0.1)
				(type default)
			)
			(layer "F.Fab")
		)
		(fp_line
			(start -7.975092 62.170056)
			(end 5.275072 62.170056)
			(stroke
				(width 0.1)
				(type default)
			)
			(layer "F.Fab")
		)
		(fp_text user "P32"
			(at -9.0043 0.13589 0)
			(unlocked yes)
			(layer "F.SilkS")
			(effects
				(font
					(size 0.7874 0.5842)
					(thickness 0.1524)
				)
			)
		)
		(fp_text user "P1"
			(at 6.119622 1.773428 0)
			(unlocked yes)
			(layer "F.SilkS")
			(effects
				(font
					(size 0.7874 0.5842)
					(thickness 0.1524)
				)
			)
		)
		(fp_text user "PRESS-FIT"
			(at -9.510014 14.10081 0)
			(unlocked yes)
			(layer "F.SilkS")
			(effects
				(font
					(size 0.7874 0.5842)
					(thickness 0.1524)
				)
				(justify left)
			)
		)
		(fp_text user "P17"
			(at -9.337294 37.89553 0)
			(unlocked yes)
			(layer "F.SilkS")
			(effects
				(font
					(size 0.7874 0.5842)
					(thickness 0.1524)
				)
			)
		)
		(fp_text user "P16"
			(at 5.934202 38.194488 0)
			(unlocked yes)
			(layer "F.SilkS")
			(effects
				(font
					(size 0.7874 0.5842)
					(thickness 0.1524)
				)
			)
		)
		(fp_text user "S12"
			(at -9.223248 41.09339 0)
			(unlocked yes)
			(layer "F.SilkS")
			(effects
				(font
					(size 0.7874 0.5842)
					(thickness 0.1524)
				)
			)
		)
		(fp_text user "S1"
			(at 6.25602 41.568624 0)
			(unlocked yes)
			(layer "F.SilkS")
			(effects
				(font
					(size 0.7874 0.5842)
					(thickness 0.1524)
				)
			)
		)
		(fp_text user "S7"
			(at -9.309608 47.565564 0)
			(unlocked yes)
			(layer "F.SilkS")
			(effects
				(font
					(size 0.7874 0.5842)
					(thickness 0.1524)
				)
			)
		)
		(fp_text user "S6"
			(at 6.055106 47.903384 0)
			(unlocked yes)
			(layer "F.SilkS")
			(effects
				(font
					(size 0.7874 0.5842)
					(thickness 0.1524)
				)
			)
		)
		(fp_text user "P1"
			(at 2.937256 -1.453642 0)
			(unlocked yes)
			(layer "B.SilkS")
			(effects
				(font
					(size 0.7874 0.5842)
					(thickness 0.1524)
				)
				(justify mirror)
			)
		)
		(fp_text user "P32"
			(at -5.914644 -0.221234 0)
			(unlocked yes)
			(layer "B.SilkS")
			(effects
				(font
					(size 0.7874 0.5842)
					(thickness 0.1524)
				)
				(justify mirror)
			)
		)
		(fp_text user "PRESS-FIT"
			(at -7.18947 29.8831 0)
			(unlocked yes)
			(layer "B.SilkS")
			(effects
				(font
					(size 0.7874 0.5842)
					(thickness 0.1524)
				)
				(justify left mirror)
			)
		)
		(fp_text user "P16"
			(at 2.988564 37.7317 0)
			(unlocked yes)
			(layer "B.SilkS")
			(effects
				(font
					(size 0.7874 0.5842)
					(thickness 0.1524)
				)
				(justify mirror)
			)
		)
		(fp_text user "P17"
			(at -6.012688 37.821616 0)
			(unlocked yes)
			(layer "B.SilkS")
			(effects
				(font
					(size 0.7874 0.5842)
					(thickness 0.1524)
				)
				(justify mirror)
			)
		)
		(fp_text user "S1"
			(at 3.051556 41.674542 0)
			(unlocked yes)
			(layer "B.SilkS")
			(effects
				(font
					(size 0.7874 0.5842)
					(thickness 0.1524)
				)
				(justify mirror)
			)
		)
		(fp_text user "S12"
			(at -5.871972 42.408348 0)
			(unlocked yes)
			(layer "B.SilkS")
			(effects
				(font
					(size 0.7874 0.5842)
					(thickness 0.1524)
				)
				(justify mirror)
			)
		)
		(fp_text user "S6"
			(at 3.014218 47.541688 0)
			(unlocked yes)
			(layer "B.SilkS")
			(effects
				(font
					(size 0.7874 0.5842)
					(thickness 0.1524)
				)
				(justify mirror)
			)
		)
		(fp_text user "S7"
			(at -6.020562 47.973742 0)
			(unlocked yes)
			(layer "B.SilkS")
			(effects
				(font
					(size 0.7874 0.5842)
					(thickness 0.1524)
				)
				(justify mirror)
			)
		)
		(fp_text user "P1"
			(at 3.108452 -1.27 180)
			(unlocked yes)
			(layer "B.Fab")
			(effects
				(font
					(size 0.7874 0.5842)
					(thickness 0.000001)
				)
				(justify mirror)
			)
		)
		(fp_text user "P32"
			(at -5.781548 -0.0508 180)
			(unlocked yes)
			(layer "B.Fab")
			(effects
				(font
					(size 0.7874 0.5842)
					(thickness 0.000001)
				)
				(justify mirror)
			)
		)
		(fp_text user "PRESS-FIT"
			(at -6.82371 29.8831 0)
			(unlocked yes)
			(layer "B.Fab")
			(effects
				(font
					(size 1.6002 1.1938)
					(thickness 0.000001)
				)
				(justify left mirror)
			)
		)
		(fp_text user "P17"
			(at -5.72135 38.0746 180)
			(unlocked yes)
			(layer "B.Fab")
			(effects
				(font
					(size 0.7874 0.5842)
					(thickness 0.000001)
				)
				(justify mirror)
			)
		)
		(fp_text user "P16"
			(at 3.159252 38.3794 180)
			(unlocked yes)
			(layer "B.Fab")
			(effects
				(font
					(size 0.7874 0.5842)
					(thickness 0.000001)
				)
				(justify mirror)
			)
		)
		(fp_text user "S12"
			(at -5.79374 41.42232 180)
			(unlocked yes)
			(layer "B.Fab")
			(effects
				(font
					(size 0.7874 0.5842)
					(thickness 0.000001)
				)
				(justify mirror)
			)
		)
		(fp_text user "S1"
			(at 3.09626 41.656 180)
			(unlocked yes)
			(layer "B.Fab")
			(effects
				(font
					(size 0.7874 0.5842)
					(thickness 0.000001)
				)
				(justify mirror)
			)
		)
		(fp_text user "S6"
			(at 3.133852 48.0822 180)
			(unlocked yes)
			(layer "B.Fab")
			(effects
				(font
					(size 0.7874 0.5842)
					(thickness 0.000001)
				)
				(justify mirror)
			)
		)
		(fp_text user "S7"
			(at -5.781548 48.0822 180)
			(unlocked yes)
			(layer "B.Fab")
			(effects
				(font
					(size 0.7874 0.5842)
					(thickness 0.000001)
				)
				(justify mirror)
			)
		)
		(fp_text user "P32"
			(at -4.071112 -0.0762 180)
			(unlocked yes)
			(layer "F.Fab")
			(effects
				(font
					(size 0.7874 0.5842)
					(thickness 0.000001)
				)
			)
		)
		(fp_text user "P1"
			(at 1.516888 0 180)
			(unlocked yes)
			(layer "F.Fab")
			(effects
				(font
					(size 0.7874 0.5842)
					(thickness 0.000001)
				)
			)
		)
		(fp_text user "PRESS-FIT"
			(at -6.762496 16.251428 0)
			(unlocked yes)
			(layer "F.Fab")
			(effects
				(font
					(size 1.6002 1.1938)
					(thickness 0.000001)
				)
				(justify left)
			)
		)
		(fp_text user "P17"
			(at -4.366768 38.227 180)
			(unlocked yes)
			(layer "F.Fab")
			(effects
				(font
					(size 0.7874 0.5842)
					(thickness 0.000001)
				)
			)
		)
		(fp_text user "P16"
			(at 2.228088 38.354 180)
			(unlocked yes)
			(layer "F.Fab")
			(effects
				(font
					(size 0.7874 0.5842)
					(thickness 0.000001)
				)
			)
		)
		(fp_text user "S12"
			(at -4.362958 41.09212 180)
			(unlocked yes)
			(layer "F.Fab")
			(effects
				(font
					(size 0.7874 0.5842)
					(thickness 0.000001)
				)
			)
		)
		(fp_text user "S1"
			(at 2.164842 41.6306 180)
			(unlocked yes)
			(layer "F.Fab")
			(effects
				(font
					(size 0.7874 0.5842)
					(thickness 0.000001)
				)
			)
		)
		(fp_text user "S6"
			(at 1.923288 48.133 180)
			(unlocked yes)
			(layer "F.Fab")
			(effects
				(font
					(size 0.7874 0.5842)
					(thickness 0.000001)
				)
			)
		)
		(fp_text user "S7"
			(at -4.426712 48.2346 180)
			(unlocked yes)
			(layer "F.Fab")
			(effects
				(font
					(size 0.7874 0.5842)
					(thickness 0.000001)
				)
			)
		)
		(pad "" np_thru_hole circle
			(at -1.35001 -2.54)
			(size 2.5146 2.5146)
			(drill 2.5146)
			(layers "*.Cu" "*.Mask")
			(clearance 0.381)
			(thermal_gap 0.381)
		)
		(pad "" np_thru_hole circle
			(at 0 50.8)
			(size 2.5146 2.5146)
			(drill 2.5146)
			(layers "*.Cu" "*.Mask")
			(clearance 0.381)
			(thermal_gap 0.381)
		)
		(pad "P1" thru_hole rect
			(at 0 0)
			(size 1.1684 1.1684)
			(drill 0.762)
			(layers "*.Cu" "*.Mask")
			(remove_unused_layers no)
			(net "GND")
			(clearance 0.0508)
			(padstack
				(mode front_inner_back)
				(layer "Inner"
					(shape circle)
					(size 1.1684 1.1684)
					(clearance 0.0508)
				)
				(layer "B.Cu"
					(shape rect)
					(size 1.1684 1.1684)
					(thermal_gap 0.0508)
					(clearance 0.0508)
				)
			)
		)
		(pad "P2" thru_hole circle
			(at 0 2.54)
			(size 1.1684 1.1684)
			(drill 0.762)
			(layers "*.Cu" "*.Mask")
			(remove_unused_layers no)
			(net "GND")
			(clearance 0.0508)
			(thermal_gap 0.0508)
		)
		(pad "P3" thru_hole circle
			(at 0 5.08)
			(size 1.1684 1.1684)
			(drill 0.762)
			(layers "*.Cu" "*.Mask")
			(remove_unused_layers no)
			(net "GND")
			(clearance 0.0508)
			(thermal_gap 0.0508)
		)
		(pad "P4" thru_hole circle
			(at 0 7.62)
			(size 1.1684 1.1684)
			(drill 0.762)
			(layers "*.Cu" "*.Mask")
			(remove_unused_layers no)
			(net "GND")
			(clearance 0.0508)
			(thermal_gap 0.0508)
		)
		(pad "P5" thru_hole circle
			(at 0 10.16)
			(size 1.1684 1.1684)
			(drill 0.762)
			(layers "*.Cu" "*.Mask")
			(remove_unused_layers no)
			(net "GND")
			(clearance 0.0508)
			(thermal_gap 0.0508)
		)
		(pad "P6" thru_hole circle
			(at 0 12.7)
			(size 1.1684 1.1684)
			(drill 0.762)
			(layers "*.Cu" "*.Mask")
			(remove_unused_layers no)
			(net "GND")
			(clearance 0.0508)
			(thermal_gap 0.0508)
		)
		(pad "P7" thru_hole circle
			(at 0 15.24)
			(size 1.1684 1.1684)
			(drill 0.762)
			(layers "*.Cu" "*.Mask")
			(remove_unused_layers no)
			(net "GND")
			(clearance 0.0508)
			(thermal_gap 0.0508)
		)
		(pad "P8" thru_hole circle
			(at 0 17.78)
			(size 1.1684 1.1684)
			(drill 0.762)
			(layers "*.Cu" "*.Mask")
			(remove_unused_layers no)
			(net "GND")
			(clearance 0.0508)
			(thermal_gap 0.0508)
		)
		(pad "P9" thru_hole circle
			(at 0 20.32)
			(size 1.1684 1.1684)
			(drill 0.762)
			(layers "*.Cu" "*.Mask")
			(remove_unused_layers no)
			(net "P12V")
			(clearance 0.0508)
			(thermal_gap 0.0508)
		)
		(pad "P10" thru_hole circle
			(at 0 22.86)
			(size 1.1684 1.1684)
			(drill 0.762)
			(layers "*.Cu" "*.Mask")
			(remove_unused_layers no)
			(net "P12V")
			(clearance 0.0508)
			(thermal_gap 0.0508)
		)
		(pad "P11" thru_hole circle
			(at 0 25.4)
			(size 1.1684 1.1684)
			(drill 0.762)
			(layers "*.Cu" "*.Mask")
			(remove_unused_layers no)
			(net "P12V")
			(clearance 0.0508)
			(thermal_gap 0.0508)
		)
		(pad "P12" thru_hole circle
			(at 0 27.94)
			(size 1.1684 1.1684)
			(drill 0.762)
			(layers "*.Cu" "*.Mask")
			(remove_unused_layers no)
			(net "P12V")
			(clearance 0.0508)
			(thermal_gap 0.0508)
		)
		(pad "P13" thru_hole circle
			(at 0 30.48)
			(size 1.1684 1.1684)
			(drill 0.762)
			(layers "*.Cu" "*.Mask")
			(remove_unused_layers no)
			(net "P12V")
			(clearance 0.0508)
			(thermal_gap 0.0508)
		)
		(pad "P14" thru_hole circle
			(at 0 33.02)
			(size 1.1684 1.1684)
			(drill 0.762)
			(layers "*.Cu" "*.Mask")
			(remove_unused_layers no)
			(net "P12V")
			(clearance 0.0508)
			(thermal_gap 0.0508)
		)
		(pad "P15" thru_hole circle
			(at 0 35.56)
			(size 1.1684 1.1684)
			(drill 0.762)
			(layers "*.Cu" "*.Mask")
			(remove_unused_layers no)
			(net "P12V")
			(clearance 0.0508)
			(thermal_gap 0.0508)
		)
		(pad "P16" thru_hole circle
			(at 0 38.1)
			(size 1.1684 1.1684)
			(drill 0.762)
			(layers "*.Cu" "*.Mask")
			(remove_unused_layers no)
			(net "P12V")
			(clearance 0.0508)
			(thermal_gap 0.0508)
		)
		(pad "P17" thru_hole circle
			(at -2.70002 38.1)
			(size 1.1684 1.1684)
			(drill 0.762)
			(layers "*.Cu" "*.Mask")
			(remove_unused_layers no)
			(net "P12V")
			(clearance 0.0508)
			(thermal_gap 0.0508)
		)
		(pad "P18" thru_hole circle
			(at -2.70002 35.56)
			(size 1.1684 1.1684)
			(drill 0.762)
			(layers "*.Cu" "*.Mask")
			(remove_unused_layers no)
			(net "P12V")
			(clearance 0.0508)
			(thermal_gap 0.0508)
		)
		(pad "P19" thru_hole circle
			(at -2.70002 33.02)
			(size 1.1684 1.1684)
			(drill 0.762)
			(layers "*.Cu" "*.Mask")
			(remove_unused_layers no)
			(net "P12V")
			(clearance 0.0508)
			(thermal_gap 0.0508)
		)
		(pad "P20" thru_hole circle
			(at -2.70002 30.48)
			(size 1.1684 1.1684)
			(drill 0.762)
			(layers "*.Cu" "*.Mask")
			(remove_unused_layers no)
			(net "P12V")
			(clearance 0.0508)
			(thermal_gap 0.0508)
		)
		(pad "P21" thru_hole circle
			(at -2.70002 27.94)
			(size 1.1684 1.1684)
			(drill 0.762)
			(layers "*.Cu" "*.Mask")
			(remove_unused_layers no)
			(net "P12V")
			(clearance 0.0508)
			(thermal_gap 0.0508)
		)
		(pad "P22" thru_hole circle
			(at -2.70002 25.4)
			(size 1.1684 1.1684)
			(drill 0.762)
			(layers "*.Cu" "*.Mask")
			(remove_unused_layers no)
			(net "P12V")
			(clearance 0.0508)
			(thermal_gap 0.0508)
		)
		(pad "P23" thru_hole circle
			(at -2.70002 22.86)
			(size 1.1684 1.1684)
			(drill 0.762)
			(layers "*.Cu" "*.Mask")
			(remove_unused_layers no)
			(net "P12V")
			(clearance 0.0508)
			(thermal_gap 0.0508)
		)
		(pad "P24" thru_hole circle
			(at -2.70002 20.32)
			(size 1.1684 1.1684)
			(drill 0.762)
			(layers "*.Cu" "*.Mask")
			(remove_unused_layers no)
			(net "P12V")
			(clearance 0.0508)
			(thermal_gap 0.0508)
		)
		(pad "P25" thru_hole circle
			(at -2.70002 17.78)
			(size 1.1684 1.1684)
			(drill 0.762)
			(layers "*.Cu" "*.Mask")
			(remove_unused_layers no)
			(net "GND")
			(clearance 0.0508)
			(thermal_gap 0.0508)
		)
		(pad "P26" thru_hole circle
			(at -2.70002 15.24)
			(size 1.1684 1.1684)
			(drill 0.762)
			(layers "*.Cu" "*.Mask")
			(remove_unused_layers no)
			(net "GND")
			(clearance 0.0508)
			(thermal_gap 0.0508)
		)
		(pad "P27" thru_hole circle
			(at -2.70002 12.7)
			(size 1.1684 1.1684)
			(drill 0.762)
			(layers "*.Cu" "*.Mask")
			(remove_unused_layers no)
			(net "GND")
			(clearance 0.0508)
			(thermal_gap 0.0508)
		)
		(pad "P28" thru_hole circle
			(at -2.70002 10.16)
			(size 1.1684 1.1684)
			(drill 0.762)
			(layers "*.Cu" "*.Mask")
			(remove_unused_layers no)
			(net "GND")
			(clearance 0.0508)
			(thermal_gap 0.0508)
		)
		(pad "P29" thru_hole circle
			(at -2.70002 7.62)
			(size 1.1684 1.1684)
			(drill 0.762)
			(layers "*.Cu" "*.Mask")
			(remove_unused_layers no)
			(net "GND")
			(clearance 0.0508)
			(thermal_gap 0.0508)
		)
		(pad "P30" thru_hole circle
			(at -2.70002 5.08)
			(size 1.1684 1.1684)
			(drill 0.762)
			(layers "*.Cu" "*.Mask")
			(remove_unused_layers no)
			(net "GND")
			(clearance 0.0508)
			(thermal_gap 0.0508)
		)
		(pad "P31" thru_hole circle
			(at -2.70002 2.54)
			(size 1.1684 1.1684)
			(drill 0.762)
			(layers "*.Cu" "*.Mask")
			(remove_unused_layers no)
			(net "GND")
			(clearance 0.0508)
			(thermal_gap 0.0508)
		)
		(pad "P32" thru_hole circle
			(at -2.70002 0)
			(size 1.1684 1.1684)
			(drill 0.762)
			(layers "*.Cu" "*.Mask")
			(remove_unused_layers no)
			(net "GND")
			(clearance 0.0508)
			(thermal_gap 0.0508)
		)
		(pad "S1" thru_hole circle
			(at 0.55499 41.60012)
			(size 1.1684 1.1684)
			(drill 0.762)
			(layers "*.Cu" "*.Mask")
			(remove_unused_layers no)
			(net "T9_BLAD1_TXD")
			(clearance 0.0508)
			(thermal_gap 0.0508)
		)
		(pad "S2" thru_hole circle
			(at -0.71501 42.87012)
			(size 1.1684 1.1684)
			(drill 0.762)
			(layers "*.Cu" "*.Mask")
			(remove_unused_layers no)
			(net "T9_BLAD1_RXD")
			(clearance 0.0508)
			(thermal_gap 0.0508)
		)
		(pad "S3" thru_hole circle
			(at 0.55499 44.14012)
			(size 1.1684 1.1684)
			(drill 0.762)
			(layers "*.Cu" "*.Mask")
			(remove_unused_layers no)
			(net "T9_BLAD1_EN")
			(clearance 0.0508)
			(thermal_gap 0.0508)
		)
		(pad "S4" thru_hole circle
			(at -0.71501 45.41012)
			(size 1.1684 1.1684)
			(drill 0.762)
			(layers "*.Cu" "*.Mask")
			(remove_unused_layers no)
			(net "T9_BLAD2_EN")
			(clearance 0.0508)
			(thermal_gap 0.0508)
		)
		(pad "S5" thru_hole circle
			(at 0.55499 46.68012)
			(size 1.1684 1.1684)
			(drill 0.762)
			(layers "*.Cu" "*.Mask")
			(remove_unused_layers no)
			(net "T9_BLAD2_TXD")
			(clearance 0.0508)
			(thermal_gap 0.0508)
		)
		(pad "S6" thru_hole circle
			(at -0.71501 47.95012)
			(size 1.1684 1.1684)
			(drill 0.762)
			(layers "*.Cu" "*.Mask")
			(remove_unused_layers no)
			(net "T9_BLAD2_RXD")
			(clearance 0.0508)
			(thermal_gap 0.0508)
		)
		(pad "S7" thru_hole circle
			(at -3.25501 47.95012)
			(size 1.1684 1.1684)
			(drill 0.762)
			(layers "*.Cu" "*.Mask")
			(remove_unused_layers no)
			(net "T9_BLAD4_RXD")
			(clearance 0.0508)
			(thermal_gap 0.0508)
		)
		(pad "S8" thru_hole circle
			(at -1.98501 46.68012)
			(size 1.1684 1.1684)
			(drill 0.762)
			(layers "*.Cu" "*.Mask")
			(remove_unused_layers no)
			(net "T9_BLAD4_TXD")
			(clearance 0.0508)
			(thermal_gap 0.0508)
		)
		(pad "S9" thru_hole circle
			(at -3.25501 45.41012)
			(size 1.1684 1.1684)
			(drill 0.762)
			(layers "*.Cu" "*.Mask")
			(remove_unused_layers no)
			(net "T9_BLAD4_EN")
			(clearance 0.0508)
			(thermal_gap 0.0508)
		)
		(pad "S10" thru_hole circle
			(at -1.98501 44.14012)
			(size 1.1684 1.1684)
			(drill 0.762)
			(layers "*.Cu" "*.Mask")
			(remove_unused_layers no)
			(net "T9_BLAD3_EN")
			(clearance 0.0508)
			(thermal_gap 0.0508)
		)
		(pad "S11" thru_hole circle
			(at -3.25501 42.87012)
			(size 1.1684 1.1684)
			(drill 0.762)
			(layers "*.Cu" "*.Mask")
			(remove_unused_layers no)
			(net "T9_BLAD3_RXD")
			(clearance 0.0508)
			(thermal_gap 0.0508)
		)
		(pad "S12" thru_hole circle
			(at -1.98501 41.60012)
			(size 1.1684 1.1684)
			(drill 0.762)
			(layers "*.Cu" "*.Mask")
			(remove_unused_layers no)
			(net "T9_BLAD3_TXD")
			(clearance 0.0508)
			(thermal_gap 0.0508)
		)
		(zone
			(layer "F.Cu")
			(hatch none 0.5)
			(connect_pads
				(clearance 0)
			)
			(min_thickness 0.25)
			(keepout
				(tracks allowed)
				(vias not_allowed)
				(pads allowed)
				(copperpour not_allowed)
				(footprints allowed)
			)
			(placement
				(enabled no)
				(sheetname "")
			)
			(fill
				(thermal_gap 0.5)
				(thermal_bridge_width 0.5)
				(island_removal_mode 0)
			)
			(polygon
				(pts
					(xy 85.00999 -365.05388) (xy 92.65539 -365.05388) (xy 92.65539 -359.94848) (xy 85.00999 -359.94848)
					(xy 84.98459 -359.94848) (xy 84.98459 -365.05388)
				)
			)
		)
		(zone
			(layer "F.Cu")
			(hatch none 0.5)
			(connect_pads
				(clearance 0)
			)
			(min_thickness 0.25)
			(keepout
				(tracks allowed)
				(vias not_allowed)
				(pads allowed)
				(copperpour not_allowed)
				(footprints allowed)
			)
			(placement
				(enabled no)
				(sheetname "")
			)
			(fill
				(thermal_gap 0.5)
				(thermal_bridge_width 0.5)
				(island_removal_mode 0)
			)
			(polygon
				(pts
					(xy 43.37939 -360.53268) (xy 43.37939 -364.49508) (xy 82.77479 -364.49508) (xy 82.80019 -364.49508)
					(xy 82.80019 -360.53268) (xy 82.80019 -360.50728) (xy 43.37939 -360.50728)
				)
			)
		)
		(zone
			(layers "F.Cu" "B.Cu" "In1.Cu" "In2.Cu" "In3.Cu" "In4.Cu" "In5.Cu" "In6.Cu")
			(hatch none 0.5)
			(connect_pads
				(clearance 0)
			)
			(min_thickness 0.25)
			(keepout
				(tracks not_allowed)
				(vias allowed)
				(pads allowed)
				(copperpour not_allowed)
				(footprints allowed)
			)
			(placement
				(enabled no)
				(sheetname "")
			)
			(fill
				(thermal_gap 0.5)
				(thermal_bridge_width 0.5)
				(island_removal_mode 0)
			)
			(polygon
				(pts
					(arc
						(start 43.18 -362.51007)
						(mid 39.81958 -362.51007)
						(end 43.18 -362.51007)
					)
				)
			)
		)
		(zone
			(layers "F.Cu" "B.Cu" "In1.Cu" "In2.Cu" "In3.Cu" "In4.Cu" "In5.Cu" "In6.Cu")
			(hatch none 0.5)
			(connect_pads
				(clearance 0)
			)
			(min_thickness 0.25)
			(keepout
				(tracks not_allowed)
				(vias allowed)
				(pads allowed)
				(copperpour not_allowed)
				(footprints allowed)
			)
			(placement
				(enabled no)
				(sheetname "")
			)
			(fill
				(thermal_gap 0.5)
				(thermal_bridge_width 0.5)
				(island_removal_mode 0)
			)
			(polygon
				(pts
					(arc
						(start 96.52381 -363.86008)
						(mid 93.15577 -363.86008)
						(end 96.52381 -363.86008)
					)
				)
			)
		)
	)
	(footprint ""
		(layer "B.Cu")
		(at 44.03979 -274.96008 90)
		(property "Reference" "J13"
			(at 6.540246 -4.559808 0)
			(unlocked yes)
			(layer "B.SilkS")
			(effects
				(font
					(size 0.7874 0.5842)
					(thickness 0.1524)
				)
				(justify left mirror)
			)
		)
		(property "Value" ""
			(at 0 0 90)
			(layer "B.Fab")
			(effects
				(font
					(size 1.27 1.27)
				)
				(justify mirror)
			)
		)
		(duplicate_pad_numbers_are_jumpers no)
		(fp_line
			(start 5.275072 -13.910056)
			(end -7.975092 -13.910056)
			(stroke
				(width 0.1524)
				(type default)
			)
			(layer "F.SilkS")
		)
		(fp_line
			(start -7.975092 -13.910056)
			(end -7.975092 62.170056)
			(stroke
				(width 0.1524)
				(type default)
			)
			(layer "F.SilkS")
		)
		(fp_line
			(start 5.275072 62.170056)
			(end 5.275072 -13.910056)
			(stroke
				(width 0.1524)
				(type default)
			)
			(layer "F.SilkS")
		)
		(fp_line
			(start -7.975092 62.170056)
			(end 5.275072 62.170056)
			(stroke
				(width 0.1524)
				(type default)
			)
			(layer "F.SilkS")
		)
		(fp_line
			(start 5.275072 -13.910056)
			(end -7.975092 -13.910056)
			(stroke
				(width 0.1524)
				(type default)
			)
			(layer "B.SilkS")
		)
		(fp_line
			(start -7.975092 -13.910056)
			(end -7.975092 62.170056)
			(stroke
				(width 0.1524)
				(type default)
			)
			(layer "B.SilkS")
		)
		(fp_line
			(start 2.275078 -10.910062)
			(end 2.275078 59.170062)
			(stroke
				(width 0.1524)
				(type default)
			)
			(layer "B.SilkS")
		)
		(fp_line
			(start -4.975098 -10.910062)
			(end 2.275078 -10.910062)
			(stroke
				(width 0.1524)
				(type default)
			)
			(layer "B.SilkS")
		)
		(fp_line
			(start 2.275078 59.170062)
			(end -4.975098 59.170062)
			(stroke
				(width 0.1524)
				(type default)
			)
			(layer "B.SilkS")
		)
		(fp_line
			(start -4.975098 59.170062)
			(end -4.975098 -10.910062)
			(stroke
				(width 0.1524)
				(type default)
			)
			(layer "B.SilkS")
		)
		(fp_line
			(start 5.275072 62.170056)
			(end 5.275072 -13.910056)
			(stroke
				(width 0.1524)
				(type default)
			)
			(layer "B.SilkS")
		)
		(fp_line
			(start -7.975092 62.170056)
			(end 5.275072 62.170056)
			(stroke
				(width 0.1524)
				(type default)
			)
			(layer "B.SilkS")
		)
		(fp_poly
			(pts
				(xy 4.103878 -0.759206) (xy 4.103878 0.764794) (xy 2.579878 0.002794)
			)
			(stroke
				(width 0)
				(type default)
			)
			(fill yes)
			(layer "B.SilkS")
		)
		(fp_poly
			(pts
				(xy 2.275078 -10.910062) (xy 2.275078 59.170062) (xy -4.975098 59.170062) (xy -4.975098 -10.910062)
			)
			(stroke
				(width 0)
				(type default)
			)
			(fill no)
			(layer "B.CrtYd")
		)
		(fp_poly
			(pts
				(xy 1.1938 40.9702) (xy 1.1938 48.6156) (xy -3.9116 48.6156) (xy -3.9116 40.9702) (xy -3.9116 40.9448)
				(xy 1.1938 40.9448)
			)
			(stroke
				(width 0)
				(type default)
			)
			(fill no)
			(layer "F.CrtYd")
		)
		(fp_poly
			(pts
				(xy -3.3274 -0.6604) (xy 0.635 -0.6604) (xy 0.635 38.735) (xy 0.635 38.7604) (xy -3.3274 38.7604)
				(xy -3.3528 38.7604) (xy -3.3528 -0.6604)
			)
			(stroke
				(width 0)
				(type default)
			)
			(fill no)
			(layer "F.CrtYd")
		)
		(fp_poly
			(pts
				(arc
					(start -1.35001 -1.01219)
					(mid -1.35001 -4.06781)
					(end -1.35001 -1.01219)
				)
			)
			(stroke
				(width 0)
				(type default)
			)
			(fill no)
			(layer "F.CrtYd")
		)
		(fp_poly
			(pts
				(arc
					(start 0 52.33162)
					(mid 0 49.26838)
					(end 0 52.33162)
				)
			)
			(stroke
				(width 0)
				(type default)
			)
			(fill no)
			(layer "F.CrtYd")
		)
		(fp_line
			(start 2.275078 -10.910062)
			(end 2.275078 59.170062)
			(stroke
				(width 0.1)
				(type default)
			)
			(layer "B.Fab")
		)
		(fp_line
			(start -4.975098 -10.910062)
			(end 2.275078 -10.910062)
			(stroke
				(width 0.1)
				(type default)
			)
			(layer "B.Fab")
		)
		(fp_line
			(start 2.275078 59.170062)
			(end -4.975098 59.170062)
			(stroke
				(width 0.1)
				(type default)
			)
			(layer "B.Fab")
		)
		(fp_line
			(start -4.975098 59.170062)
			(end -4.975098 -10.910062)
			(stroke
				(width 0.1)
				(type default)
			)
			(layer "B.Fab")
		)
		(fp_poly
			(pts
				(xy 4.103878 -0.759206) (xy 4.103878 0.764794) (xy 2.579878 0.002794)
			)
			(stroke
				(width 0)
				(type default)
			)
			(fill yes)
			(layer "B.Fab")
		)
		(fp_line
			(start 5.275072 -13.910056)
			(end -7.975092 -13.910056)
			(stroke
				(width 0.1)
				(type default)
			)
			(layer "F.Fab")
		)
		(fp_line
			(start -7.975092 -13.910056)
			(end -7.975092 62.170056)
			(stroke
				(width 0.1)
				(type default)
			)
			(layer "F.Fab")
		)
		(fp_line
			(start 5.275072 62.170056)
			(end 5.275072 -13.910056)
			(stroke
				(width 0.1)
				(type default)
			)
			(layer "F.Fab")
		)
		(fp_line
			(start -7.975092 62.170056)
			(end 5.275072 62.170056)
			(stroke
				(width 0.1)
				(type default)
			)
			(layer "F.Fab")
		)
		(fp_text user "P32"
			(at -9.264904 -0.265684 0)
			(unlocked yes)
			(layer "F.SilkS")
			(effects
				(font
					(size 0.7874 0.5842)
					(thickness 0.1524)
				)
			)
		)
		(fp_text user "P1"
			(at 6.17474 1.605788 0)
			(unlocked yes)
			(layer "F.SilkS")
			(effects
				(font
					(size 0.7874 0.5842)
					(thickness 0.1524)
				)
			)
		)
		(fp_text user "PRESS-FIT"
			(at -9.065768 15.80388 0)
			(unlocked yes)
			(layer "F.SilkS")
			(effects
				(font
					(size 0.7874 0.5842)
					(thickness 0.1524)
				)
				(justify left)
			)
		)
		(fp_text user "P17"
			(at -8.998966 37.492686 0)
			(unlocked yes)
			(layer "F.SilkS")
			(effects
				(font
					(size 0.7874 0.5842)
					(thickness 0.1524)
				)
			)
		)
		(fp_text user "P16"
			(at 6.1341 38.192456 0)
			(unlocked yes)
			(layer "F.SilkS")
			(effects
				(font
					(size 0.7874 0.5842)
					(thickness 0.1524)
				)
			)
		)
		(fp_text user "S12"
			(at -9.2329 40.032432 0)
			(unlocked yes)
			(layer "F.SilkS")
			(effects
				(font
					(size 0.7874 0.5842)
					(thickness 0.1524)
				)
			)
		)
		(fp_text user "S1"
			(at 5.97281 41.268904 0)
			(unlocked yes)
			(layer "F.SilkS")
			(effects
				(font
					(size 0.7874 0.5842)
					(thickness 0.1524)
				)
			)
		)
		(fp_text user "S7"
			(at -9.019286 47.64278 0)
			(unlocked yes)
			(layer "F.SilkS")
			(effects
				(font
					(size 0.7874 0.5842)
					(thickness 0.1524)
				)
			)
		)
		(fp_text user "S6"
			(at 6.006338 47.919386 0)
			(unlocked yes)
			(layer "F.SilkS")
			(effects
				(font
					(size 0.7874 0.5842)
					(thickness 0.1524)
				)
			)
		)
		(fp_text user "P1"
			(at 3.075178 -1.464056 0)
			(unlocked yes)
			(layer "B.SilkS")
			(effects
				(font
					(size 0.7874 0.5842)
					(thickness 0.1524)
				)
				(justify mirror)
			)
		)
		(fp_text user "P32"
			(at -6.014974 -0.09525 0)
			(unlocked yes)
			(layer "B.SilkS")
			(effects
				(font
					(size 0.7874 0.5842)
					(thickness 0.1524)
				)
				(justify mirror)
			)
		)
		(fp_text user "PRESS-FIT"
			(at -7.155434 24.40051 0)
			(unlocked yes)
			(layer "B.SilkS")
			(effects
				(font
					(size 0.7874 0.5842)
					(thickness 0.1524)
				)
				(justify left mirror)
			)
		)
		(fp_text user "P16"
			(at 3.024124 37.789104 0)
			(unlocked yes)
			(layer "B.SilkS")
			(effects
				(font
					(size 0.7874 0.5842)
					(thickness 0.1524)
				)
				(justify mirror)
			)
		)
		(fp_text user "P17"
			(at -5.734558 37.889942 0)
			(unlocked yes)
			(layer "B.SilkS")
			(effects
				(font
					(size 0.7874 0.5842)
					(thickness 0.1524)
				)
				(justify mirror)
			)
		)
		(fp_text user "S1"
			(at 3.05308 41.69791 0)
			(unlocked yes)
			(layer "B.SilkS")
			(effects
				(font
					(size 0.7874 0.5842)
					(thickness 0.1524)
				)
				(justify mirror)
			)
		)
		(fp_text user "S12"
			(at -5.832602 42.374566 0)
			(unlocked yes)
			(layer "B.SilkS")
			(effects
				(font
					(size 0.7874 0.5842)
					(thickness 0.1524)
				)
				(justify mirror)
			)
		)
		(fp_text user "S6"
			(at 3.015488 47.565056 0)
			(unlocked yes)
			(layer "B.SilkS")
			(effects
				(font
					(size 0.7874 0.5842)
					(thickness 0.1524)
				)
				(justify mirror)
			)
		)
		(fp_text user "S7"
			(at -5.810758 47.56531 0)
			(unlocked yes)
			(layer "B.SilkS")
			(effects
				(font
					(size 0.7874 0.5842)
					(thickness 0.1524)
				)
				(justify mirror)
			)
		)
		(fp_text user "P1"
			(at 3.108452 -1.27 180)
			(unlocked yes)
			(layer "B.Fab")
			(effects
				(font
					(size 0.7874 0.5842)
					(thickness 0.000001)
				)
				(justify mirror)
			)
		)
		(fp_text user "P32"
			(at -5.781548 -0.0508 180)
			(unlocked yes)
			(layer "B.Fab")
			(effects
				(font
					(size 0.7874 0.5842)
					(thickness 0.000001)
				)
				(justify mirror)
			)
		)
		(fp_text user "PRESS-FIT"
			(at -6.82371 29.8831 0)
			(unlocked yes)
			(layer "B.Fab")
			(effects
				(font
					(size 1.6002 1.1938)
					(thickness 0.000001)
				)
				(justify left mirror)
			)
		)
		(fp_text user "P17"
			(at -5.72135 38.0746 180)
			(unlocked yes)
			(layer "B.Fab")
			(effects
				(font
					(size 0.7874 0.5842)
					(thickness 0.000001)
				)
				(justify mirror)
			)
		)
		(fp_text user "P16"
			(at 3.159252 38.3794 180)
			(unlocked yes)
			(layer "B.Fab")
			(effects
				(font
					(size 0.7874 0.5842)
					(thickness 0.000001)
				)
				(justify mirror)
			)
		)
		(fp_text user "S12"
			(at -5.79374 41.42232 180)
			(unlocked yes)
			(layer "B.Fab")
			(effects
				(font
					(size 0.7874 0.5842)
					(thickness 0.000001)
				)
				(justify mirror)
			)
		)
		(fp_text user "S1"
			(at 3.09626 41.656 180)
			(unlocked yes)
			(layer "B.Fab")
			(effects
				(font
					(size 0.7874 0.5842)
					(thickness 0.000001)
				)
				(justify mirror)
			)
		)
		(fp_text user "S6"
			(at 3.133852 48.0822 180)
			(unlocked yes)
			(layer "B.Fab")
			(effects
				(font
					(size 0.7874 0.5842)
					(thickness 0.000001)
				)
				(justify mirror)
			)
		)
		(fp_text user "S7"
			(at -5.781548 48.0822 180)
			(unlocked yes)
			(layer "B.Fab")
			(effects
				(font
					(size 0.7874 0.5842)
					(thickness 0.000001)
				)
				(justify mirror)
			)
		)
		(fp_text user "P32"
			(at -4.071112 -0.0762 180)
			(unlocked yes)
			(layer "F.Fab")
			(effects
				(font
					(size 0.7874 0.5842)
					(thickness 0.000001)
				)
			)
		)
		(fp_text user "P1"
			(at 1.516888 0 180)
			(unlocked yes)
			(layer "F.Fab")
			(effects
				(font
					(size 0.7874 0.5842)
					(thickness 0.000001)
				)
			)
		)
		(fp_text user "PRESS-FIT"
			(at -6.762496 16.251428 0)
			(unlocked yes)
			(layer "F.Fab")
			(effects
				(font
					(size 1.6002 1.1938)
					(thickness 0.000001)
				)
				(justify left)
			)
		)
		(fp_text user "P17"
			(at -4.366768 38.227 180)
			(unlocked yes)
			(layer "F.Fab")
			(effects
				(font
					(size 0.7874 0.5842)
					(thickness 0.000001)
				)
			)
		)
		(fp_text user "P16"
			(at 2.228088 38.354 180)
			(unlocked yes)
			(layer "F.Fab")
			(effects
				(font
					(size 0.7874 0.5842)
					(thickness 0.000001)
				)
			)
		)
		(fp_text user "S12"
			(at -4.362958 41.09212 180)
			(unlocked yes)
			(layer "F.Fab")
			(effects
				(font
					(size 0.7874 0.5842)
					(thickness 0.000001)
				)
			)
		)
		(fp_text user "S1"
			(at 2.164842 41.6306 180)
			(unlocked yes)
			(layer "F.Fab")
			(effects
				(font
					(size 0.7874 0.5842)
					(thickness 0.000001)
				)
			)
		)
		(fp_text user "S6"
			(at 1.923288 48.133 180)
			(unlocked yes)
			(layer "F.Fab")
			(effects
				(font
					(size 0.7874 0.5842)
					(thickness 0.000001)
				)
			)
		)
		(fp_text user "S7"
			(at -4.426712 48.2346 180)
			(unlocked yes)
			(layer "F.Fab")
			(effects
				(font
					(size 0.7874 0.5842)
					(thickness 0.000001)
				)
			)
		)
		(pad "" np_thru_hole circle
			(at -1.35001 -2.54)
			(size 2.5146 2.5146)
			(drill 2.5146)
			(layers "*.Cu" "*.Mask")
			(clearance 0.381)
			(thermal_gap 0.381)
		)
		(pad "" np_thru_hole circle
			(at 0 50.8)
			(size 2.5146 2.5146)
			(drill 2.5146)
			(layers "*.Cu" "*.Mask")
			(clearance 0.381)
			(thermal_gap 0.381)
		)
		(pad "P1" thru_hole rect
			(at 0 0)
			(size 1.1684 1.1684)
			(drill 0.762)
			(layers "*.Cu" "*.Mask")
			(remove_unused_layers no)
			(net "GND")
			(clearance 0.0508)
			(padstack
				(mode front_inner_back)
				(layer "Inner"
					(shape circle)
					(size 1.1684 1.1684)
					(clearance 0.0508)
				)
				(layer "B.Cu"
					(shape rect)
					(size 1.1684 1.1684)
					(thermal_gap 0.0508)
					(clearance 0.0508)
				)
			)
		)
		(pad "P2" thru_hole circle
			(at 0 2.54)
			(size 1.1684 1.1684)
			(drill 0.762)
			(layers "*.Cu" "*.Mask")
			(remove_unused_layers no)
			(net "GND")
			(clearance 0.0508)
			(thermal_gap 0.0508)
		)
		(pad "P3" thru_hole circle
			(at 0 5.08)
			(size 1.1684 1.1684)
			(drill 0.762)
			(layers "*.Cu" "*.Mask")
			(remove_unused_layers no)
			(net "GND")
			(clearance 0.0508)
			(thermal_gap 0.0508)
		)
		(pad "P4" thru_hole circle
			(at 0 7.62)
			(size 1.1684 1.1684)
			(drill 0.762)
			(layers "*.Cu" "*.Mask")
			(remove_unused_layers no)
			(net "GND")
			(clearance 0.0508)
			(thermal_gap 0.0508)
		)
		(pad "P5" thru_hole circle
			(at 0 10.16)
			(size 1.1684 1.1684)
			(drill 0.762)
			(layers "*.Cu" "*.Mask")
			(remove_unused_layers no)
			(net "GND")
			(clearance 0.0508)
			(thermal_gap 0.0508)
		)
		(pad "P6" thru_hole circle
			(at 0 12.7)
			(size 1.1684 1.1684)
			(drill 0.762)
			(layers "*.Cu" "*.Mask")
			(remove_unused_layers no)
			(net "GND")
			(clearance 0.0508)
			(thermal_gap 0.0508)
		)
		(pad "P7" thru_hole circle
			(at 0 15.24)
			(size 1.1684 1.1684)
			(drill 0.762)
			(layers "*.Cu" "*.Mask")
			(remove_unused_layers no)
			(net "GND")
			(clearance 0.0508)
			(thermal_gap 0.0508)
		)
		(pad "P8" thru_hole circle
			(at 0 17.78)
			(size 1.1684 1.1684)
			(drill 0.762)
			(layers "*.Cu" "*.Mask")
			(remove_unused_layers no)
			(net "GND")
			(clearance 0.0508)
			(thermal_gap 0.0508)
		)
		(pad "P9" thru_hole circle
			(at 0 20.32)
			(size 1.1684 1.1684)
			(drill 0.762)
			(layers "*.Cu" "*.Mask")
			(remove_unused_layers no)
			(net "P12V")
			(clearance 0.0508)
			(thermal_gap 0.0508)
		)
		(pad "P10" thru_hole circle
			(at 0 22.86)
			(size 1.1684 1.1684)
			(drill 0.762)
			(layers "*.Cu" "*.Mask")
			(remove_unused_layers no)
			(net "P12V")
			(clearance 0.0508)
			(thermal_gap 0.0508)
		)
		(pad "P11" thru_hole circle
			(at 0 25.4)
			(size 1.1684 1.1684)
			(drill 0.762)
			(layers "*.Cu" "*.Mask")
			(remove_unused_layers no)
			(net "P12V")
			(clearance 0.0508)
			(thermal_gap 0.0508)
		)
		(pad "P12" thru_hole circle
			(at 0 27.94)
			(size 1.1684 1.1684)
			(drill 0.762)
			(layers "*.Cu" "*.Mask")
			(remove_unused_layers no)
			(net "P12V")
			(clearance 0.0508)
			(thermal_gap 0.0508)
		)
		(pad "P13" thru_hole circle
			(at 0 30.48)
			(size 1.1684 1.1684)
			(drill 0.762)
			(layers "*.Cu" "*.Mask")
			(remove_unused_layers no)
			(net "P12V")
			(clearance 0.0508)
			(thermal_gap 0.0508)
		)
		(pad "P14" thru_hole circle
			(at 0 33.02)
			(size 1.1684 1.1684)
			(drill 0.762)
			(layers "*.Cu" "*.Mask")
			(remove_unused_layers no)
			(net "P12V")
			(clearance 0.0508)
			(thermal_gap 0.0508)
		)
		(pad "P15" thru_hole circle
			(at 0 35.56)
			(size 1.1684 1.1684)
			(drill 0.762)
			(layers "*.Cu" "*.Mask")
			(remove_unused_layers no)
			(net "P12V")
			(clearance 0.0508)
			(thermal_gap 0.0508)
		)
		(pad "P16" thru_hole circle
			(at 0 38.1)
			(size 1.1684 1.1684)
			(drill 0.762)
			(layers "*.Cu" "*.Mask")
			(remove_unused_layers no)
			(net "P12V")
			(clearance 0.0508)
			(thermal_gap 0.0508)
		)
		(pad "P17" thru_hole circle
			(at -2.70002 38.1)
			(size 1.1684 1.1684)
			(drill 0.762)
			(layers "*.Cu" "*.Mask")
			(remove_unused_layers no)
			(net "P12V")
			(clearance 0.0508)
			(thermal_gap 0.0508)
		)
		(pad "P18" thru_hole circle
			(at -2.70002 35.56)
			(size 1.1684 1.1684)
			(drill 0.762)
			(layers "*.Cu" "*.Mask")
			(remove_unused_layers no)
			(net "P12V")
			(clearance 0.0508)
			(thermal_gap 0.0508)
		)
		(pad "P19" thru_hole circle
			(at -2.70002 33.02)
			(size 1.1684 1.1684)
			(drill 0.762)
			(layers "*.Cu" "*.Mask")
			(remove_unused_layers no)
			(net "P12V")
			(clearance 0.0508)
			(thermal_gap 0.0508)
		)
		(pad "P20" thru_hole circle
			(at -2.70002 30.48)
			(size 1.1684 1.1684)
			(drill 0.762)
			(layers "*.Cu" "*.Mask")
			(remove_unused_layers no)
			(net "P12V")
			(clearance 0.0508)
			(thermal_gap 0.0508)
		)
		(pad "P21" thru_hole circle
			(at -2.70002 27.94)
			(size 1.1684 1.1684)
			(drill 0.762)
			(layers "*.Cu" "*.Mask")
			(remove_unused_layers no)
			(net "P12V")
			(clearance 0.0508)
			(thermal_gap 0.0508)
		)
		(pad "P22" thru_hole circle
			(at -2.70002 25.4)
			(size 1.1684 1.1684)
			(drill 0.762)
			(layers "*.Cu" "*.Mask")
			(remove_unused_layers no)
			(net "P12V")
			(clearance 0.0508)
			(thermal_gap 0.0508)
		)
		(pad "P23" thru_hole circle
			(at -2.70002 22.86)
			(size 1.1684 1.1684)
			(drill 0.762)
			(layers "*.Cu" "*.Mask")
			(remove_unused_layers no)
			(net "P12V")
			(clearance 0.0508)
			(thermal_gap 0.0508)
		)
		(pad "P24" thru_hole circle
			(at -2.70002 20.32)
			(size 1.1684 1.1684)
			(drill 0.762)
			(layers "*.Cu" "*.Mask")
			(remove_unused_layers no)
			(net "P12V")
			(clearance 0.0508)
			(thermal_gap 0.0508)
		)
		(pad "P25" thru_hole circle
			(at -2.70002 17.78)
			(size 1.1684 1.1684)
			(drill 0.762)
			(layers "*.Cu" "*.Mask")
			(remove_unused_layers no)
			(net "GND")
			(clearance 0.0508)
			(thermal_gap 0.0508)
		)
		(pad "P26" thru_hole circle
			(at -2.70002 15.24)
			(size 1.1684 1.1684)
			(drill 0.762)
			(layers "*.Cu" "*.Mask")
			(remove_unused_layers no)
			(net "GND")
			(clearance 0.0508)
			(thermal_gap 0.0508)
		)
		(pad "P27" thru_hole circle
			(at -2.70002 12.7)
			(size 1.1684 1.1684)
			(drill 0.762)
			(layers "*.Cu" "*.Mask")
			(remove_unused_layers no)
			(net "GND")
			(clearance 0.0508)
			(thermal_gap 0.0508)
		)
		(pad "P28" thru_hole circle
			(at -2.70002 10.16)
			(size 1.1684 1.1684)
			(drill 0.762)
			(layers "*.Cu" "*.Mask")
			(remove_unused_layers no)
			(net "GND")
			(clearance 0.0508)
			(thermal_gap 0.0508)
		)
		(pad "P29" thru_hole circle
			(at -2.70002 7.62)
			(size 1.1684 1.1684)
			(drill 0.762)
			(layers "*.Cu" "*.Mask")
			(remove_unused_layers no)
			(net "GND")
			(clearance 0.0508)
			(thermal_gap 0.0508)
		)
		(pad "P30" thru_hole circle
			(at -2.70002 5.08)
			(size 1.1684 1.1684)
			(drill 0.762)
			(layers "*.Cu" "*.Mask")
			(remove_unused_layers no)
			(net "GND")
			(clearance 0.0508)
			(thermal_gap 0.0508)
		)
		(pad "P31" thru_hole circle
			(at -2.70002 2.54)
			(size 1.1684 1.1684)
			(drill 0.762)
			(layers "*.Cu" "*.Mask")
			(remove_unused_layers no)
			(net "GND")
			(clearance 0.0508)
			(thermal_gap 0.0508)
		)
		(pad "P32" thru_hole circle
			(at -2.70002 0)
			(size 1.1684 1.1684)
			(drill 0.762)
			(layers "*.Cu" "*.Mask")
			(remove_unused_layers no)
			(net "GND")
			(clearance 0.0508)
			(thermal_gap 0.0508)
		)
		(pad "S1" thru_hole circle
			(at 0.55499 41.60012)
			(size 1.1684 1.1684)
			(drill 0.762)
			(layers "*.Cu" "*.Mask")
			(remove_unused_layers no)
			(net "T7_BLAD1_TXD")
			(clearance 0.0508)
			(thermal_gap 0.0508)
		)
		(pad "S2" thru_hole circle
			(at -0.71501 42.87012)
			(size 1.1684 1.1684)
			(drill 0.762)
			(layers "*.Cu" "*.Mask")
			(remove_unused_layers no)
			(net "T7_BLAD1_RXD")
			(clearance 0.0508)
			(thermal_gap 0.0508)
		)
		(pad "S3" thru_hole circle
			(at 0.55499 44.14012)
			(size 1.1684 1.1684)
			(drill 0.762)
			(layers "*.Cu" "*.Mask")
			(remove_unused_layers no)
			(net "T7_BLAD1_EN")
			(clearance 0.0508)
			(thermal_gap 0.0508)
		)
		(pad "S4" thru_hole circle
			(at -0.71501 45.41012)
			(size 1.1684 1.1684)
			(drill 0.762)
			(layers "*.Cu" "*.Mask")
			(remove_unused_layers no)
			(net "T7_BLAD2_EN")
			(clearance 0.0508)
			(thermal_gap 0.0508)
		)
		(pad "S5" thru_hole circle
			(at 0.55499 46.68012)
			(size 1.1684 1.1684)
			(drill 0.762)
			(layers "*.Cu" "*.Mask")
			(remove_unused_layers no)
			(net "T7_BLAD2_TXD")
			(clearance 0.0508)
			(thermal_gap 0.0508)
		)
		(pad "S6" thru_hole circle
			(at -0.71501 47.95012)
			(size 1.1684 1.1684)
			(drill 0.762)
			(layers "*.Cu" "*.Mask")
			(remove_unused_layers no)
			(net "T7_BLAD2_RXD")
			(clearance 0.0508)
			(thermal_gap 0.0508)
		)
		(pad "S7" thru_hole circle
			(at -3.25501 47.95012)
			(size 1.1684 1.1684)
			(drill 0.762)
			(layers "*.Cu" "*.Mask")
			(remove_unused_layers no)
			(net "T7_BLAD4_RXD")
			(clearance 0.0508)
			(thermal_gap 0.0508)
		)
		(pad "S8" thru_hole circle
			(at -1.98501 46.68012)
			(size 1.1684 1.1684)
			(drill 0.762)
			(layers "*.Cu" "*.Mask")
			(remove_unused_layers no)
			(net "T7_BLAD4_TXD")
			(clearance 0.0508)
			(thermal_gap 0.0508)
		)
		(pad "S9" thru_hole circle
			(at -3.25501 45.41012)
			(size 1.1684 1.1684)
			(drill 0.762)
			(layers "*.Cu" "*.Mask")
			(remove_unused_layers no)
			(net "T7_BLAD4_EN")
			(clearance 0.0508)
			(thermal_gap 0.0508)
		)
		(pad "S10" thru_hole circle
			(at -1.98501 44.14012)
			(size 1.1684 1.1684)
			(drill 0.762)
			(layers "*.Cu" "*.Mask")
			(remove_unused_layers no)
			(net "T7_BLAD3_EN")
			(clearance 0.0508)
			(thermal_gap 0.0508)
		)
		(pad "S11" thru_hole circle
			(at -3.25501 42.87012)
			(size 1.1684 1.1684)
			(drill 0.762)
			(layers "*.Cu" "*.Mask")
			(remove_unused_layers no)
			(net "T7_BLAD3_RXD")
			(clearance 0.0508)
			(thermal_gap 0.0508)
		)
		(pad "S12" thru_hole circle
			(at -1.98501 41.60012)
			(size 1.1684 1.1684)
			(drill 0.762)
			(layers "*.Cu" "*.Mask")
			(remove_unused_layers no)
			(net "T7_BLAD3_TXD")
			(clearance 0.0508)
			(thermal_gap 0.0508)
		)
		(zone
			(layer "F.Cu")
			(hatch none 0.5)
			(connect_pads
				(clearance 0)
			)
			(min_thickness 0.25)
			(keepout
				(tracks allowed)
				(vias not_allowed)
				(pads allowed)
				(copperpour not_allowed)
				(footprints allowed)
			)
			(placement
				(enabled no)
				(sheetname "")
			)
			(fill
				(thermal_gap 0.5)
				(thermal_bridge_width 0.5)
				(island_removal_mode 0)
			)
			(polygon
				(pts
					(xy 85.00999 -276.15388) (xy 92.65539 -276.15388) (xy 92.65539 -271.04848) (xy 85.00999 -271.04848)
					(xy 84.98459 -271.04848) (xy 84.98459 -276.15388)
				)
			)
		)
		(zone
			(layer "F.Cu")
			(hatch none 0.5)
			(connect_pads
				(clearance 0)
			)
			(min_thickness 0.25)
			(keepout
				(tracks allowed)
				(vias not_allowed)
				(pads allowed)
				(copperpour not_allowed)
				(footprints allowed)
			)
			(placement
				(enabled no)
				(sheetname "")
			)
			(fill
				(thermal_gap 0.5)
				(thermal_bridge_width 0.5)
				(island_removal_mode 0)
			)
			(polygon
				(pts
					(xy 43.37939 -271.63268) (xy 43.37939 -275.59508) (xy 82.77479 -275.59508) (xy 82.80019 -275.59508)
					(xy 82.80019 -271.63268) (xy 82.80019 -271.60728) (xy 43.37939 -271.60728)
				)
			)
		)
		(zone
			(layers "F.Cu" "B.Cu" "In1.Cu" "In2.Cu" "In3.Cu" "In4.Cu" "In5.Cu" "In6.Cu")
			(hatch none 0.5)
			(connect_pads
				(clearance 0)
			)
			(min_thickness 0.25)
			(keepout
				(tracks not_allowed)
				(vias allowed)
				(pads allowed)
				(copperpour not_allowed)
				(footprints allowed)
			)
			(placement
				(enabled no)
				(sheetname "")
			)
			(fill
				(thermal_gap 0.5)
				(thermal_bridge_width 0.5)
				(island_removal_mode 0)
			)
			(polygon
				(pts
					(arc
						(start 43.18 -273.61007)
						(mid 39.81958 -273.61007)
						(end 43.18 -273.61007)
					)
				)
			)
		)
		(zone
			(layers "F.Cu" "B.Cu" "In1.Cu" "In2.Cu" "In3.Cu" "In4.Cu" "In5.Cu" "In6.Cu")
			(hatch none 0.5)
			(connect_pads
				(clearance 0)
			)
			(min_thickness 0.25)
			(keepout
				(tracks not_allowed)
				(vias allowed)
				(pads allowed)
				(copperpour not_allowed)
				(footprints allowed)
			)
			(placement
				(enabled no)
				(sheetname "")
			)
			(fill
				(thermal_gap 0.5)
				(thermal_bridge_width 0.5)
				(island_removal_mode 0)
			)
			(polygon
				(pts
					(arc
						(start 96.52381 -274.96008)
						(mid 93.15577 -274.96008)
						(end 96.52381 -274.96008)
					)
				)
			)
		)
	)
	(footprint ""
		(layer "B.Cu")
		(at 44.03979 -52.71008 90)
		(property "Reference" "J8"
			(at 6.17982 -4.9149 0)
			(unlocked yes)
			(layer "B.SilkS")
			(effects
				(font
					(size 0.7874 0.5842)
					(thickness 0.1524)
				)
				(justify left mirror)
			)
		)
		(property "Value" ""
			(at 0 0 90)
			(layer "B.Fab")
			(effects
				(font
					(size 1.27 1.27)
				)
				(justify mirror)
			)
		)
		(duplicate_pad_numbers_are_jumpers no)
		(fp_line
			(start 5.275072 -13.910056)
			(end -7.975092 -13.910056)
			(stroke
				(width 0.1524)
				(type default)
			)
			(layer "F.SilkS")
		)
		(fp_line
			(start -7.975092 -13.910056)
			(end -7.975092 62.170056)
			(stroke
				(width 0.1524)
				(type default)
			)
			(layer "F.SilkS")
		)
		(fp_line
			(start 5.275072 62.170056)
			(end 5.275072 -13.910056)
			(stroke
				(width 0.1524)
				(type default)
			)
			(layer "F.SilkS")
		)
		(fp_line
			(start -7.975092 62.170056)
			(end 5.275072 62.170056)
			(stroke
				(width 0.1524)
				(type default)
			)
			(layer "F.SilkS")
		)
		(fp_line
			(start 5.275072 -13.910056)
			(end -7.975092 -13.910056)
			(stroke
				(width 0.1524)
				(type default)
			)
			(layer "B.SilkS")
		)
		(fp_line
			(start -7.975092 -13.910056)
			(end -7.975092 62.170056)
			(stroke
				(width 0.1524)
				(type default)
			)
			(layer "B.SilkS")
		)
		(fp_line
			(start 2.275078 -10.910062)
			(end 2.275078 59.170062)
			(stroke
				(width 0.1524)
				(type default)
			)
			(layer "B.SilkS")
		)
		(fp_line
			(start -4.975098 -10.910062)
			(end 2.275078 -10.910062)
			(stroke
				(width 0.1524)
				(type default)
			)
			(layer "B.SilkS")
		)
		(fp_line
			(start 2.275078 59.170062)
			(end -4.975098 59.170062)
			(stroke
				(width 0.1524)
				(type default)
			)
			(layer "B.SilkS")
		)
		(fp_line
			(start -4.975098 59.170062)
			(end -4.975098 -10.910062)
			(stroke
				(width 0.1524)
				(type default)
			)
			(layer "B.SilkS")
		)
		(fp_line
			(start 5.275072 62.170056)
			(end 5.275072 -13.910056)
			(stroke
				(width 0.1524)
				(type default)
			)
			(layer "B.SilkS")
		)
		(fp_line
			(start -7.975092 62.170056)
			(end 5.275072 62.170056)
			(stroke
				(width 0.1524)
				(type default)
			)
			(layer "B.SilkS")
		)
		(fp_poly
			(pts
				(xy 4.103878 -0.759206) (xy 4.103878 0.764794) (xy 2.579878 0.002794)
			)
			(stroke
				(width 0)
				(type default)
			)
			(fill yes)
			(layer "B.SilkS")
		)
		(fp_poly
			(pts
				(xy 2.275078 -10.910062) (xy 2.275078 59.170062) (xy -4.975098 59.170062) (xy -4.975098 -10.910062)
			)
			(stroke
				(width 0)
				(type default)
			)
			(fill no)
			(layer "B.CrtYd")
		)
		(fp_poly
			(pts
				(xy 1.1938 40.9702) (xy 1.1938 48.6156) (xy -3.9116 48.6156) (xy -3.9116 40.9702) (xy -3.9116 40.9448)
				(xy 1.1938 40.9448)
			)
			(stroke
				(width 0)
				(type default)
			)
			(fill no)
			(layer "F.CrtYd")
		)
		(fp_poly
			(pts
				(xy -3.3274 -0.6604) (xy 0.635 -0.6604) (xy 0.635 38.735) (xy 0.635 38.7604) (xy -3.3274 38.7604)
				(xy -3.3528 38.7604) (xy -3.3528 -0.6604)
			)
			(stroke
				(width 0)
				(type default)
			)
			(fill no)
			(layer "F.CrtYd")
		)
		(fp_poly
			(pts
				(arc
					(start -1.35001 -1.01219)
					(mid -1.35001 -4.06781)
					(end -1.35001 -1.01219)
				)
			)
			(stroke
				(width 0)
				(type default)
			)
			(fill no)
			(layer "F.CrtYd")
		)
		(fp_poly
			(pts
				(arc
					(start 0 52.33162)
					(mid 0 49.26838)
					(end 0 52.33162)
				)
			)
			(stroke
				(width 0)
				(type default)
			)
			(fill no)
			(layer "F.CrtYd")
		)
		(fp_line
			(start 2.275078 -10.910062)
			(end 2.275078 59.170062)
			(stroke
				(width 0.1)
				(type default)
			)
			(layer "B.Fab")
		)
		(fp_line
			(start -4.975098 -10.910062)
			(end 2.275078 -10.910062)
			(stroke
				(width 0.1)
				(type default)
			)
			(layer "B.Fab")
		)
		(fp_line
			(start 2.275078 59.170062)
			(end -4.975098 59.170062)
			(stroke
				(width 0.1)
				(type default)
			)
			(layer "B.Fab")
		)
		(fp_line
			(start -4.975098 59.170062)
			(end -4.975098 -10.910062)
			(stroke
				(width 0.1)
				(type default)
			)
			(layer "B.Fab")
		)
		(fp_poly
			(pts
				(xy 4.103878 -0.759206) (xy 4.103878 0.764794) (xy 2.579878 0.002794)
			)
			(stroke
				(width 0)
				(type default)
			)
			(fill yes)
			(layer "B.Fab")
		)
		(fp_line
			(start 5.275072 -13.910056)
			(end -7.975092 -13.910056)
			(stroke
				(width 0.1)
				(type default)
			)
			(layer "F.Fab")
		)
		(fp_line
			(start -7.975092 -13.910056)
			(end -7.975092 62.170056)
			(stroke
				(width 0.1)
				(type default)
			)
			(layer "F.Fab")
		)
		(fp_line
			(start 5.275072 62.170056)
			(end 5.275072 -13.910056)
			(stroke
				(width 0.1)
				(type default)
			)
			(layer "F.Fab")
		)
		(fp_line
			(start -7.975092 62.170056)
			(end 5.275072 62.170056)
			(stroke
				(width 0.1)
				(type default)
			)
			(layer "F.Fab")
		)
		(fp_text user "P32"
			(at -8.889746 -0.874522 0)
			(unlocked yes)
			(layer "F.SilkS")
			(effects
				(font
					(size 0.7874 0.5842)
					(thickness 0.1524)
				)
			)
		)
		(fp_text user "P1"
			(at 6.75513 0.202184 0)
			(unlocked yes)
			(layer "F.SilkS")
			(effects
				(font
					(size 0.7874 0.5842)
					(thickness 0.1524)
				)
			)
		)
		(fp_text user "PRESS-FIT"
			(at -9.12368 0.829564 0)
			(unlocked yes)
			(layer "F.SilkS")
			(effects
				(font
					(size 0.7874 0.5842)
					(thickness 0.1524)
				)
				(justify left)
			)
		)
		(fp_text user "P17"
			(at -8.8519 37.893752 0)
			(unlocked yes)
			(layer "F.SilkS")
			(effects
				(font
					(size 0.7874 0.5842)
					(thickness 0.1524)
				)
			)
		)
		(fp_text user "P16"
			(at 6.922008 38.79596 0)
			(unlocked yes)
			(layer "F.SilkS")
			(effects
				(font
					(size 0.7874 0.5842)
					(thickness 0.1524)
				)
			)
		)
		(fp_text user "S1"
			(at 6.321298 41.858184 0)
			(unlocked yes)
			(layer "F.SilkS")
			(effects
				(font
					(size 0.7874 0.5842)
					(thickness 0.1524)
				)
			)
		)
		(fp_text user "S12"
			(at -8.95223 42.004234 0)
			(unlocked yes)
			(layer "F.SilkS")
			(effects
				(font
					(size 0.7874 0.5842)
					(thickness 0.1524)
				)
			)
		)
		(fp_text user "S6"
			(at 5.94995 47.81931 0)
			(unlocked yes)
			(layer "F.SilkS")
			(effects
				(font
					(size 0.7874 0.5842)
					(thickness 0.1524)
				)
			)
		)
		(fp_text user "S7"
			(at -9.26084 48.429672 0)
			(unlocked yes)
			(layer "F.SilkS")
			(effects
				(font
					(size 0.7874 0.5842)
					(thickness 0.1524)
				)
			)
		)
		(fp_text user "P1"
			(at 3.209544 -1.55575 0)
			(unlocked yes)
			(layer "B.SilkS")
			(effects
				(font
					(size 0.7874 0.5842)
					(thickness 0.1524)
				)
				(justify mirror)
			)
		)
		(fp_text user "P32"
			(at -5.949188 -0.289052 0)
			(unlocked yes)
			(layer "B.SilkS")
			(effects
				(font
					(size 0.7874 0.5842)
					(thickness 0.1524)
				)
				(justify mirror)
			)
		)
		(fp_text user "PRESS-FIT"
			(at -7.18947 29.8831 0)
			(unlocked yes)
			(layer "B.SilkS")
			(effects
				(font
					(size 0.7874 0.5842)
					(thickness 0.1524)
				)
				(justify left mirror)
			)
		)
		(fp_text user "P17"
			(at -5.736336 37.729668 0)
			(unlocked yes)
			(layer "B.SilkS")
			(effects
				(font
					(size 0.7874 0.5842)
					(thickness 0.1524)
				)
				(justify mirror)
			)
		)
		(fp_text user "P16"
			(at 3.090926 38.106096 0)
			(unlocked yes)
			(layer "B.SilkS")
			(effects
				(font
					(size 0.7874 0.5842)
					(thickness 0.1524)
				)
				(justify mirror)
			)
		)
		(fp_text user "S12"
			(at -5.766054 41.499282 0)
			(unlocked yes)
			(layer "B.SilkS")
			(effects
				(font
					(size 0.7874 0.5842)
					(thickness 0.1524)
				)
				(justify mirror)
			)
		)
		(fp_text user "S1"
			(at 3.0861 41.980612 0)
			(unlocked yes)
			(layer "B.SilkS")
			(effects
				(font
					(size 0.7874 0.5842)
					(thickness 0.1524)
				)
				(justify mirror)
			)
		)
		(fp_text user "S7"
			(at -5.676138 44.170092 0)
			(unlocked yes)
			(layer "B.SilkS")
			(effects
				(font
					(size 0.7874 0.5842)
					(thickness 0.1524)
				)
				(justify mirror)
			)
		)
		(fp_text user "S6"
			(at 2.91211 48.052228 0)
			(unlocked yes)
			(layer "B.SilkS")
			(effects
				(font
					(size 0.7874 0.5842)
					(thickness 0.1524)
				)
				(justify mirror)
			)
		)
		(fp_text user "P1"
			(at 3.108452 -1.27 180)
			(unlocked yes)
			(layer "B.Fab")
			(effects
				(font
					(size 0.7874 0.5842)
					(thickness 0.000001)
				)
				(justify mirror)
			)
		)
		(fp_text user "P32"
			(at -5.781548 -0.0508 180)
			(unlocked yes)
			(layer "B.Fab")
			(effects
				(font
					(size 0.7874 0.5842)
					(thickness 0.000001)
				)
				(justify mirror)
			)
		)
		(fp_text user "PRESS-FIT"
			(at -6.82371 29.8831 0)
			(unlocked yes)
			(layer "B.Fab")
			(effects
				(font
					(size 1.6002 1.1938)
					(thickness 0.000001)
				)
				(justify left mirror)
			)
		)
		(fp_text user "P17"
			(at -5.72135 38.0746 180)
			(unlocked yes)
			(layer "B.Fab")
			(effects
				(font
					(size 0.7874 0.5842)
					(thickness 0.000001)
				)
				(justify mirror)
			)
		)
		(fp_text user "P16"
			(at 3.159252 38.3794 180)
			(unlocked yes)
			(layer "B.Fab")
			(effects
				(font
					(size 0.7874 0.5842)
					(thickness 0.000001)
				)
				(justify mirror)
			)
		)
		(fp_text user "S12"
			(at -5.79374 41.42232 180)
			(unlocked yes)
			(layer "B.Fab")
			(effects
				(font
					(size 0.7874 0.5842)
					(thickness 0.000001)
				)
				(justify mirror)
			)
		)
		(fp_text user "S1"
			(at 3.09626 41.656 180)
			(unlocked yes)
			(layer "B.Fab")
			(effects
				(font
					(size 0.7874 0.5842)
					(thickness 0.000001)
				)
				(justify mirror)
			)
		)
		(fp_text user "S6"
			(at 3.133852 48.0822 180)
			(unlocked yes)
			(layer "B.Fab")
			(effects
				(font
					(size 0.7874 0.5842)
					(thickness 0.000001)
				)
				(justify mirror)
			)
		)
		(fp_text user "S7"
			(at -5.781548 48.0822 180)
			(unlocked yes)
			(layer "B.Fab")
			(effects
				(font
					(size 0.7874 0.5842)
					(thickness 0.000001)
				)
				(justify mirror)
			)
		)
		(fp_text user "P32"
			(at -4.071112 -0.0762 180)
			(unlocked yes)
			(layer "F.Fab")
			(effects
				(font
					(size 0.7874 0.5842)
					(thickness 0.000001)
				)
			)
		)
		(fp_text user "P1"
			(at 1.516888 0 180)
			(unlocked yes)
			(layer "F.Fab")
			(effects
				(font
					(size 0.7874 0.5842)
					(thickness 0.000001)
				)
			)
		)
		(fp_text user "PRESS-FIT"
			(at -6.762496 16.251428 0)
			(unlocked yes)
			(layer "F.Fab")
			(effects
				(font
					(size 1.6002 1.1938)
					(thickness 0.000001)
				)
				(justify left)
			)
		)
		(fp_text user "P17"
			(at -4.366768 38.227 180)
			(unlocked yes)
			(layer "F.Fab")
			(effects
				(font
					(size 0.7874 0.5842)
					(thickness 0.000001)
				)
			)
		)
		(fp_text user "P16"
			(at 2.228088 38.354 180)
			(unlocked yes)
			(layer "F.Fab")
			(effects
				(font
					(size 0.7874 0.5842)
					(thickness 0.000001)
				)
			)
		)
		(fp_text user "S12"
			(at -4.362958 41.09212 180)
			(unlocked yes)
			(layer "F.Fab")
			(effects
				(font
					(size 0.7874 0.5842)
					(thickness 0.000001)
				)
			)
		)
		(fp_text user "S1"
			(at 2.164842 41.6306 180)
			(unlocked yes)
			(layer "F.Fab")
			(effects
				(font
					(size 0.7874 0.5842)
					(thickness 0.000001)
				)
			)
		)
		(fp_text user "S6"
			(at 1.923288 48.133 180)
			(unlocked yes)
			(layer "F.Fab")
			(effects
				(font
					(size 0.7874 0.5842)
					(thickness 0.000001)
				)
			)
		)
		(fp_text user "S7"
			(at -4.426712 48.2346 180)
			(unlocked yes)
			(layer "F.Fab")
			(effects
				(font
					(size 0.7874 0.5842)
					(thickness 0.000001)
				)
			)
		)
		(pad "" np_thru_hole circle
			(at -1.35001 -2.54)
			(size 2.5146 2.5146)
			(drill 2.5146)
			(layers "*.Cu" "*.Mask")
			(clearance 0.381)
			(thermal_gap 0.381)
		)
		(pad "" np_thru_hole circle
			(at 0 50.8)
			(size 2.5146 2.5146)
			(drill 2.5146)
			(layers "*.Cu" "*.Mask")
			(clearance 0.381)
			(thermal_gap 0.381)
		)
		(pad "P1" thru_hole rect
			(at 0 0)
			(size 1.1684 1.1684)
			(drill 0.762)
			(layers "*.Cu" "*.Mask")
			(remove_unused_layers no)
			(net "GND")
			(clearance 0.0508)
			(padstack
				(mode front_inner_back)
				(layer "Inner"
					(shape circle)
					(size 1.1684 1.1684)
					(clearance 0.0508)
				)
				(layer "B.Cu"
					(shape rect)
					(size 1.1684 1.1684)
					(thermal_gap 0.0508)
					(clearance 0.0508)
				)
			)
		)
		(pad "P2" thru_hole circle
			(at 0 2.54)
			(size 1.1684 1.1684)
			(drill 0.762)
			(layers "*.Cu" "*.Mask")
			(remove_unused_layers no)
			(net "GND")
			(clearance 0.0508)
			(thermal_gap 0.0508)
		)
		(pad "P3" thru_hole circle
			(at 0 5.08)
			(size 1.1684 1.1684)
			(drill 0.762)
			(layers "*.Cu" "*.Mask")
			(remove_unused_layers no)
			(net "GND")
			(clearance 0.0508)
			(thermal_gap 0.0508)
		)
		(pad "P4" thru_hole circle
			(at 0 7.62)
			(size 1.1684 1.1684)
			(drill 0.762)
			(layers "*.Cu" "*.Mask")
			(remove_unused_layers no)
			(net "GND")
			(clearance 0.0508)
			(thermal_gap 0.0508)
		)
		(pad "P5" thru_hole circle
			(at 0 10.16)
			(size 1.1684 1.1684)
			(drill 0.762)
			(layers "*.Cu" "*.Mask")
			(remove_unused_layers no)
			(net "GND")
			(clearance 0.0508)
			(thermal_gap 0.0508)
		)
		(pad "P6" thru_hole circle
			(at 0 12.7)
			(size 1.1684 1.1684)
			(drill 0.762)
			(layers "*.Cu" "*.Mask")
			(remove_unused_layers no)
			(net "GND")
			(clearance 0.0508)
			(thermal_gap 0.0508)
		)
		(pad "P7" thru_hole circle
			(at 0 15.24)
			(size 1.1684 1.1684)
			(drill 0.762)
			(layers "*.Cu" "*.Mask")
			(remove_unused_layers no)
			(net "GND")
			(clearance 0.0508)
			(thermal_gap 0.0508)
		)
		(pad "P8" thru_hole circle
			(at 0 17.78)
			(size 1.1684 1.1684)
			(drill 0.762)
			(layers "*.Cu" "*.Mask")
			(remove_unused_layers no)
			(net "GND")
			(clearance 0.0508)
			(thermal_gap 0.0508)
		)
		(pad "P9" thru_hole circle
			(at 0 20.32)
			(size 1.1684 1.1684)
			(drill 0.762)
			(layers "*.Cu" "*.Mask")
			(remove_unused_layers no)
			(net "P12V")
			(clearance 0.0508)
			(thermal_gap 0.0508)
		)
		(pad "P10" thru_hole circle
			(at 0 22.86)
			(size 1.1684 1.1684)
			(drill 0.762)
			(layers "*.Cu" "*.Mask")
			(remove_unused_layers no)
			(net "P12V")
			(clearance 0.0508)
			(thermal_gap 0.0508)
		)
		(pad "P11" thru_hole circle
			(at 0 25.4)
			(size 1.1684 1.1684)
			(drill 0.762)
			(layers "*.Cu" "*.Mask")
			(remove_unused_layers no)
			(net "P12V")
			(clearance 0.0508)
			(thermal_gap 0.0508)
		)
		(pad "P12" thru_hole circle
			(at 0 27.94)
			(size 1.1684 1.1684)
			(drill 0.762)
			(layers "*.Cu" "*.Mask")
			(remove_unused_layers no)
			(net "P12V")
			(clearance 0.0508)
			(thermal_gap 0.0508)
		)
		(pad "P13" thru_hole circle
			(at 0 30.48)
			(size 1.1684 1.1684)
			(drill 0.762)
			(layers "*.Cu" "*.Mask")
			(remove_unused_layers no)
			(net "P12V")
			(clearance 0.0508)
			(thermal_gap 0.0508)
		)
		(pad "P14" thru_hole circle
			(at 0 33.02)
			(size 1.1684 1.1684)
			(drill 0.762)
			(layers "*.Cu" "*.Mask")
			(remove_unused_layers no)
			(net "P12V")
			(clearance 0.0508)
			(thermal_gap 0.0508)
		)
		(pad "P15" thru_hole circle
			(at 0 35.56)
			(size 1.1684 1.1684)
			(drill 0.762)
			(layers "*.Cu" "*.Mask")
			(remove_unused_layers no)
			(net "P12V")
			(clearance 0.0508)
			(thermal_gap 0.0508)
		)
		(pad "P16" thru_hole circle
			(at 0 38.1)
			(size 1.1684 1.1684)
			(drill 0.762)
			(layers "*.Cu" "*.Mask")
			(remove_unused_layers no)
			(net "P12V")
			(clearance 0.0508)
			(thermal_gap 0.0508)
		)
		(pad "P17" thru_hole circle
			(at -2.70002 38.1)
			(size 1.1684 1.1684)
			(drill 0.762)
			(layers "*.Cu" "*.Mask")
			(remove_unused_layers no)
			(net "P12V")
			(clearance 0.0508)
			(thermal_gap 0.0508)
		)
		(pad "P18" thru_hole circle
			(at -2.70002 35.56)
			(size 1.1684 1.1684)
			(drill 0.762)
			(layers "*.Cu" "*.Mask")
			(remove_unused_layers no)
			(net "P12V")
			(clearance 0.0508)
			(thermal_gap 0.0508)
		)
		(pad "P19" thru_hole circle
			(at -2.70002 33.02)
			(size 1.1684 1.1684)
			(drill 0.762)
			(layers "*.Cu" "*.Mask")
			(remove_unused_layers no)
			(net "P12V")
			(clearance 0.0508)
			(thermal_gap 0.0508)
		)
		(pad "P20" thru_hole circle
			(at -2.70002 30.48)
			(size 1.1684 1.1684)
			(drill 0.762)
			(layers "*.Cu" "*.Mask")
			(remove_unused_layers no)
			(net "P12V")
			(clearance 0.0508)
			(thermal_gap 0.0508)
		)
		(pad "P21" thru_hole circle
			(at -2.70002 27.94)
			(size 1.1684 1.1684)
			(drill 0.762)
			(layers "*.Cu" "*.Mask")
			(remove_unused_layers no)
			(net "P12V")
			(clearance 0.0508)
			(thermal_gap 0.0508)
		)
		(pad "P22" thru_hole circle
			(at -2.70002 25.4)
			(size 1.1684 1.1684)
			(drill 0.762)
			(layers "*.Cu" "*.Mask")
			(remove_unused_layers no)
			(net "P12V")
			(clearance 0.0508)
			(thermal_gap 0.0508)
		)
		(pad "P23" thru_hole circle
			(at -2.70002 22.86)
			(size 1.1684 1.1684)
			(drill 0.762)
			(layers "*.Cu" "*.Mask")
			(remove_unused_layers no)
			(net "P12V")
			(clearance 0.0508)
			(thermal_gap 0.0508)
		)
		(pad "P24" thru_hole circle
			(at -2.70002 20.32)
			(size 1.1684 1.1684)
			(drill 0.762)
			(layers "*.Cu" "*.Mask")
			(remove_unused_layers no)
			(net "P12V")
			(clearance 0.0508)
			(thermal_gap 0.0508)
		)
		(pad "P25" thru_hole circle
			(at -2.70002 17.78)
			(size 1.1684 1.1684)
			(drill 0.762)
			(layers "*.Cu" "*.Mask")
			(remove_unused_layers no)
			(net "GND")
			(clearance 0.0508)
			(thermal_gap 0.0508)
		)
		(pad "P26" thru_hole circle
			(at -2.70002 15.24)
			(size 1.1684 1.1684)
			(drill 0.762)
			(layers "*.Cu" "*.Mask")
			(remove_unused_layers no)
			(net "GND")
			(clearance 0.0508)
			(thermal_gap 0.0508)
		)
		(pad "P27" thru_hole circle
			(at -2.70002 12.7)
			(size 1.1684 1.1684)
			(drill 0.762)
			(layers "*.Cu" "*.Mask")
			(remove_unused_layers no)
			(net "GND")
			(clearance 0.0508)
			(thermal_gap 0.0508)
		)
		(pad "P28" thru_hole circle
			(at -2.70002 10.16)
			(size 1.1684 1.1684)
			(drill 0.762)
			(layers "*.Cu" "*.Mask")
			(remove_unused_layers no)
			(net "GND")
			(clearance 0.0508)
			(thermal_gap 0.0508)
		)
		(pad "P29" thru_hole circle
			(at -2.70002 7.62)
			(size 1.1684 1.1684)
			(drill 0.762)
			(layers "*.Cu" "*.Mask")
			(remove_unused_layers no)
			(net "GND")
			(clearance 0.0508)
			(thermal_gap 0.0508)
		)
		(pad "P30" thru_hole circle
			(at -2.70002 5.08)
			(size 1.1684 1.1684)
			(drill 0.762)
			(layers "*.Cu" "*.Mask")
			(remove_unused_layers no)
			(net "GND")
			(clearance 0.0508)
			(thermal_gap 0.0508)
		)
		(pad "P31" thru_hole circle
			(at -2.70002 2.54)
			(size 1.1684 1.1684)
			(drill 0.762)
			(layers "*.Cu" "*.Mask")
			(remove_unused_layers no)
			(net "GND")
			(clearance 0.0508)
			(thermal_gap 0.0508)
		)
		(pad "P32" thru_hole circle
			(at -2.70002 0)
			(size 1.1684 1.1684)
			(drill 0.762)
			(layers "*.Cu" "*.Mask")
			(remove_unused_layers no)
			(net "GND")
			(clearance 0.0508)
			(thermal_gap 0.0508)
		)
		(pad "S1" thru_hole circle
			(at 0.55499 41.60012)
			(size 1.1684 1.1684)
			(drill 0.762)
			(layers "*.Cu" "*.Mask")
			(remove_unused_layers no)
			(net "T2_BLAD1_TXD")
			(clearance 0.0508)
			(thermal_gap 0.0508)
		)
		(pad "S2" thru_hole circle
			(at -0.71501 42.87012)
			(size 1.1684 1.1684)
			(drill 0.762)
			(layers "*.Cu" "*.Mask")
			(remove_unused_layers no)
			(net "T2_BLAD1_RXD")
			(clearance 0.0508)
			(thermal_gap 0.0508)
		)
		(pad "S3" thru_hole circle
			(at 0.55499 44.14012)
			(size 1.1684 1.1684)
			(drill 0.762)
			(layers "*.Cu" "*.Mask")
			(remove_unused_layers no)
			(net "T2_BLAD1_EN")
			(clearance 0.0508)
			(thermal_gap 0.0508)
		)
		(pad "S4" thru_hole circle
			(at -0.71501 45.41012)
			(size 1.1684 1.1684)
			(drill 0.762)
			(layers "*.Cu" "*.Mask")
			(remove_unused_layers no)
			(net "T2_BLAD2_EN")
			(clearance 0.0508)
			(thermal_gap 0.0508)
		)
		(pad "S5" thru_hole circle
			(at 0.55499 46.68012)
			(size 1.1684 1.1684)
			(drill 0.762)
			(layers "*.Cu" "*.Mask")
			(remove_unused_layers no)
			(net "T2_BLAD2_TXD")
			(clearance 0.0508)
			(thermal_gap 0.0508)
		)
		(pad "S6" thru_hole circle
			(at -0.71501 47.95012)
			(size 1.1684 1.1684)
			(drill 0.762)
			(layers "*.Cu" "*.Mask")
			(remove_unused_layers no)
			(net "T2_BLAD2_RXD")
			(clearance 0.0508)
			(thermal_gap 0.0508)
		)
		(pad "S7" thru_hole circle
			(at -3.25501 47.95012)
			(size 1.1684 1.1684)
			(drill 0.762)
			(layers "*.Cu" "*.Mask")
			(remove_unused_layers no)
			(net "T2_BLAD4_RXD")
			(clearance 0.0508)
			(thermal_gap 0.0508)
		)
		(pad "S8" thru_hole circle
			(at -1.98501 46.68012)
			(size 1.1684 1.1684)
			(drill 0.762)
			(layers "*.Cu" "*.Mask")
			(remove_unused_layers no)
			(net "T2_BLAD4_TXD")
			(clearance 0.0508)
			(thermal_gap 0.0508)
		)
		(pad "S9" thru_hole circle
			(at -3.25501 45.41012)
			(size 1.1684 1.1684)
			(drill 0.762)
			(layers "*.Cu" "*.Mask")
			(remove_unused_layers no)
			(net "T2_BLAD4_EN")
			(clearance 0.0508)
			(thermal_gap 0.0508)
		)
		(pad "S10" thru_hole circle
			(at -1.98501 44.14012)
			(size 1.1684 1.1684)
			(drill 0.762)
			(layers "*.Cu" "*.Mask")
			(remove_unused_layers no)
			(net "T2_BLAD3_EN")
			(clearance 0.0508)
			(thermal_gap 0.0508)
		)
		(pad "S11" thru_hole circle
			(at -3.25501 42.87012)
			(size 1.1684 1.1684)
			(drill 0.762)
			(layers "*.Cu" "*.Mask")
			(remove_unused_layers no)
			(net "T2_BLAD3_RXD")
			(clearance 0.0508)
			(thermal_gap 0.0508)
		)
		(pad "S12" thru_hole circle
			(at -1.98501 41.60012)
			(size 1.1684 1.1684)
			(drill 0.762)
			(layers "*.Cu" "*.Mask")
			(remove_unused_layers no)
			(net "T2_BLAD3_TXD")
			(clearance 0.0508)
			(thermal_gap 0.0508)
		)
		(zone
			(layer "F.Cu")
			(hatch none 0.5)
			(connect_pads
				(clearance 0)
			)
			(min_thickness 0.25)
			(keepout
				(tracks allowed)
				(vias not_allowed)
				(pads allowed)
				(copperpour not_allowed)
				(footprints allowed)
			)
			(placement
				(enabled no)
				(sheetname "")
			)
			(fill
				(thermal_gap 0.5)
				(thermal_bridge_width 0.5)
				(island_removal_mode 0)
			)
			(polygon
				(pts
					(xy 85.00999 -53.90388) (xy 92.65539 -53.90388) (xy 92.65539 -48.79848) (xy 85.00999 -48.79848)
					(xy 84.98459 -48.79848) (xy 84.98459 -53.90388)
				)
			)
		)
		(zone
			(layer "F.Cu")
			(hatch none 0.5)
			(connect_pads
				(clearance 0)
			)
			(min_thickness 0.25)
			(keepout
				(tracks allowed)
				(vias not_allowed)
				(pads allowed)
				(copperpour not_allowed)
				(footprints allowed)
			)
			(placement
				(enabled no)
				(sheetname "")
			)
			(fill
				(thermal_gap 0.5)
				(thermal_bridge_width 0.5)
				(island_removal_mode 0)
			)
			(polygon
				(pts
					(xy 43.37939 -49.38268) (xy 43.37939 -53.34508) (xy 82.77479 -53.34508) (xy 82.80019 -53.34508)
					(xy 82.80019 -49.38268) (xy 82.80019 -49.35728) (xy 43.37939 -49.35728)
				)
			)
		)
		(zone
			(layers "F.Cu" "B.Cu" "In1.Cu" "In2.Cu" "In3.Cu" "In4.Cu" "In5.Cu" "In6.Cu")
			(hatch none 0.5)
			(connect_pads
				(clearance 0)
			)
			(min_thickness 0.25)
			(keepout
				(tracks not_allowed)
				(vias allowed)
				(pads allowed)
				(copperpour not_allowed)
				(footprints allowed)
			)
			(placement
				(enabled no)
				(sheetname "")
			)
			(fill
				(thermal_gap 0.5)
				(thermal_bridge_width 0.5)
				(island_removal_mode 0)
			)
			(polygon
				(pts
					(arc
						(start 43.18 -51.36007)
						(mid 39.81958 -51.36007)
						(end 43.18 -51.36007)
					)
				)
			)
		)
		(zone
			(layers "F.Cu" "B.Cu" "In1.Cu" "In2.Cu" "In3.Cu" "In4.Cu" "In5.Cu" "In6.Cu")
			(hatch none 0.5)
			(connect_pads
				(clearance 0)
			)
			(min_thickness 0.25)
			(keepout
				(tracks not_allowed)
				(vias allowed)
				(pads allowed)
				(copperpour not_allowed)
				(footprints allowed)
			)
			(placement
				(enabled no)
				(sheetname "")
			)
			(fill
				(thermal_gap 0.5)
				(thermal_bridge_width 0.5)
				(island_removal_mode 0)
			)
			(polygon
				(pts
					(arc
						(start 96.52381 -52.71008)
						(mid 93.15577 -52.71008)
						(end 96.52381 -52.71008)
					)
				)
			)
		)
	)
	(footprint ""
		(layer "B.Cu")
		(at 44.040044 -141.61008 90)
		(property "Reference" "J10"
			(at 6.161024 -4.691126 0)
			(unlocked yes)
			(layer "B.SilkS")
			(effects
				(font
					(size 0.7874 0.5842)
					(thickness 0.1524)
				)
				(justify left mirror)
			)
		)
		(property "Value" ""
			(at 0 0 90)
			(layer "B.Fab")
			(effects
				(font
					(size 1.27 1.27)
				)
				(justify mirror)
			)
		)
		(duplicate_pad_numbers_are_jumpers no)
		(fp_line
			(start 5.275072 -13.910056)
			(end -7.975092 -13.910056)
			(stroke
				(width 0.1524)
				(type default)
			)
			(layer "F.SilkS")
		)
		(fp_line
			(start -7.975092 -13.910056)
			(end -7.975092 62.170056)
			(stroke
				(width 0.1524)
				(type default)
			)
			(layer "F.SilkS")
		)
		(fp_line
			(start 5.275072 62.170056)
			(end 5.275072 -13.910056)
			(stroke
				(width 0.1524)
				(type default)
			)
			(layer "F.SilkS")
		)
		(fp_line
			(start -7.975092 62.170056)
			(end 5.275072 62.170056)
			(stroke
				(width 0.1524)
				(type default)
			)
			(layer "F.SilkS")
		)
		(fp_line
			(start 5.275072 -13.910056)
			(end -7.975092 -13.910056)
			(stroke
				(width 0.1524)
				(type default)
			)
			(layer "B.SilkS")
		)
		(fp_line
			(start -7.975092 -13.910056)
			(end -7.975092 62.170056)
			(stroke
				(width 0.1524)
				(type default)
			)
			(layer "B.SilkS")
		)
		(fp_line
			(start 2.275078 -10.910062)
			(end 2.275078 59.170062)
			(stroke
				(width 0.1524)
				(type default)
			)
			(layer "B.SilkS")
		)
		(fp_line
			(start -4.975098 -10.910062)
			(end 2.275078 -10.910062)
			(stroke
				(width 0.1524)
				(type default)
			)
			(layer "B.SilkS")
		)
		(fp_line
			(start 2.275078 59.170062)
			(end -4.975098 59.170062)
			(stroke
				(width 0.1524)
				(type default)
			)
			(layer "B.SilkS")
		)
		(fp_line
			(start -4.975098 59.170062)
			(end -4.975098 -10.910062)
			(stroke
				(width 0.1524)
				(type default)
			)
			(layer "B.SilkS")
		)
		(fp_line
			(start 5.275072 62.170056)
			(end 5.275072 -13.910056)
			(stroke
				(width 0.1524)
				(type default)
			)
			(layer "B.SilkS")
		)
		(fp_line
			(start -7.975092 62.170056)
			(end 5.275072 62.170056)
			(stroke
				(width 0.1524)
				(type default)
			)
			(layer "B.SilkS")
		)
		(fp_poly
			(pts
				(xy 4.103878 -0.759206) (xy 4.103878 0.764794) (xy 2.579878 0.002794)
			)
			(stroke
				(width 0)
				(type default)
			)
			(fill yes)
			(layer "B.SilkS")
		)
		(fp_poly
			(pts
				(xy 2.275078 -10.910062) (xy 2.275078 59.170062) (xy -4.975098 59.170062) (xy -4.975098 -10.910062)
			)
			(stroke
				(width 0)
				(type default)
			)
			(fill no)
			(layer "B.CrtYd")
		)
		(fp_poly
			(pts
				(xy 1.1938 40.9702) (xy 1.1938 48.6156) (xy -3.9116 48.6156) (xy -3.9116 40.9702) (xy -3.9116 40.9448)
				(xy 1.1938 40.9448)
			)
			(stroke
				(width 0)
				(type default)
			)
			(fill no)
			(layer "F.CrtYd")
		)
		(fp_poly
			(pts
				(xy -3.3274 -0.6604) (xy 0.635 -0.6604) (xy 0.635 38.735) (xy 0.635 38.7604) (xy -3.3274 38.7604)
				(xy -3.3528 38.7604) (xy -3.3528 -0.6604)
			)
			(stroke
				(width 0)
				(type default)
			)
			(fill no)
			(layer "F.CrtYd")
		)
		(fp_poly
			(pts
				(arc
					(start -1.35001 -1.01219)
					(mid -1.35001 -4.06781)
					(end -1.35001 -1.01219)
				)
			)
			(stroke
				(width 0)
				(type default)
			)
			(fill no)
			(layer "F.CrtYd")
		)
		(fp_poly
			(pts
				(arc
					(start 0 52.33162)
					(mid 0 49.26838)
					(end 0 52.33162)
				)
			)
			(stroke
				(width 0)
				(type default)
			)
			(fill no)
			(layer "F.CrtYd")
		)
		(fp_line
			(start 2.275078 -10.910062)
			(end 2.275078 59.170062)
			(stroke
				(width 0.1)
				(type default)
			)
			(layer "B.Fab")
		)
		(fp_line
			(start -4.975098 -10.910062)
			(end 2.275078 -10.910062)
			(stroke
				(width 0.1)
				(type default)
			)
			(layer "B.Fab")
		)
		(fp_line
			(start 2.275078 59.170062)
			(end -4.975098 59.170062)
			(stroke
				(width 0.1)
				(type default)
			)
			(layer "B.Fab")
		)
		(fp_line
			(start -4.975098 59.170062)
			(end -4.975098 -10.910062)
			(stroke
				(width 0.1)
				(type default)
			)
			(layer "B.Fab")
		)
		(fp_poly
			(pts
				(xy 4.103878 -0.759206) (xy 4.103878 0.764794) (xy 2.579878 0.002794)
			)
			(stroke
				(width 0)
				(type default)
			)
			(fill yes)
			(layer "B.Fab")
		)
		(fp_line
			(start 5.275072 -13.910056)
			(end -7.975092 -13.910056)
			(stroke
				(width 0.1)
				(type default)
			)
			(layer "F.Fab")
		)
		(fp_line
			(start -7.975092 -13.910056)
			(end -7.975092 62.170056)
			(stroke
				(width 0.1)
				(type default)
			)
			(layer "F.Fab")
		)
		(fp_line
			(start 5.275072 62.170056)
			(end 5.275072 -13.910056)
			(stroke
				(width 0.1)
				(type default)
			)
			(layer "F.Fab")
		)
		(fp_line
			(start -7.975092 62.170056)
			(end 5.275072 62.170056)
			(stroke
				(width 0.1)
				(type default)
			)
			(layer "F.Fab")
		)
		(fp_text user "P1"
			(at 6.382004 -0.705612 0)
			(unlocked yes)
			(layer "F.SilkS")
			(effects
				(font
					(size 0.7874 0.5842)
					(thickness 0.1524)
				)
			)
		)
		(fp_text user "P32"
			(at -9.324848 -0.170942 0)
			(unlocked yes)
			(layer "F.SilkS")
			(effects
				(font
					(size 0.7874 0.5842)
					(thickness 0.1524)
				)
			)
		)
		(fp_text user "PRESS-FIT"
			(at -8.95731 8.785352 0)
			(unlocked yes)
			(layer "F.SilkS")
			(effects
				(font
					(size 0.7874 0.5842)
					(thickness 0.1524)
				)
				(justify left)
			)
		)
		(fp_text user "P16"
			(at 5.980684 37.793168 0)
			(unlocked yes)
			(layer "F.SilkS")
			(effects
				(font
					(size 0.7874 0.5842)
					(thickness 0.1524)
				)
			)
		)
		(fp_text user "P17"
			(at -9.525508 40.199564 0)
			(unlocked yes)
			(layer "F.SilkS")
			(effects
				(font
					(size 0.7874 0.5842)
					(thickness 0.1524)
				)
			)
		)
		(fp_text user "S1"
			(at 6.481318 41.559734 0)
			(unlocked yes)
			(layer "F.SilkS")
			(effects
				(font
					(size 0.7874 0.5842)
					(thickness 0.1524)
				)
			)
		)
		(fp_text user "S12"
			(at -9.024366 42.906442 0)
			(unlocked yes)
			(layer "F.SilkS")
			(effects
				(font
					(size 0.7874 0.5842)
					(thickness 0.1524)
				)
			)
		)
		(fp_text user "S6"
			(at 6.10997 47.690532 0)
			(unlocked yes)
			(layer "F.SilkS")
			(effects
				(font
					(size 0.7874 0.5842)
					(thickness 0.1524)
				)
			)
		)
		(fp_text user "S7"
			(at -9.49706 48.02759 0)
			(unlocked yes)
			(layer "F.SilkS")
			(effects
				(font
					(size 0.7874 0.5842)
					(thickness 0.1524)
				)
			)
		)
		(fp_text user "P1"
			(at 3.068828 -1.487932 0)
			(unlocked yes)
			(layer "B.SilkS")
			(effects
				(font
					(size 0.7874 0.5842)
					(thickness 0.1524)
				)
				(justify mirror)
			)
		)
		(fp_text user "P32"
			(at -5.817362 -0.221234 0)
			(unlocked yes)
			(layer "B.SilkS")
			(effects
				(font
					(size 0.7874 0.5842)
					(thickness 0.1524)
				)
				(justify mirror)
			)
		)
		(fp_text user "PRESS-FIT"
			(at -7.18947 29.8831 0)
			(unlocked yes)
			(layer "B.SilkS")
			(effects
				(font
					(size 0.7874 0.5842)
					(thickness 0.1524)
				)
				(justify left mirror)
			)
		)
		(fp_text user "P17"
			(at -5.913628 37.855652 0)
			(unlocked yes)
			(layer "B.SilkS")
			(effects
				(font
					(size 0.7874 0.5842)
					(thickness 0.1524)
				)
				(justify mirror)
			)
		)
		(fp_text user "P16"
			(at 3.018282 38.07206 0)
			(unlocked yes)
			(layer "B.SilkS")
			(effects
				(font
					(size 0.7874 0.5842)
					(thickness 0.1524)
				)
				(justify mirror)
			)
		)
		(fp_text user "S12"
			(at -5.807456 41.590976 0)
			(unlocked yes)
			(layer "B.SilkS")
			(effects
				(font
					(size 0.7874 0.5842)
					(thickness 0.1524)
				)
				(justify mirror)
			)
		)
		(fp_text user "S1"
			(at 3.081274 42.08272 0)
			(unlocked yes)
			(layer "B.SilkS")
			(effects
				(font
					(size 0.7874 0.5842)
					(thickness 0.1524)
				)
				(justify mirror)
			)
		)
		(fp_text user "S7"
			(at -5.615178 45.181266 0)
			(unlocked yes)
			(layer "B.SilkS")
			(effects
				(font
					(size 0.7874 0.5842)
					(thickness 0.1524)
				)
				(justify mirror)
			)
		)
		(fp_text user "S6"
			(at 2.97307 47.326804 0)
			(unlocked yes)
			(layer "B.SilkS")
			(effects
				(font
					(size 0.7874 0.5842)
					(thickness 0.1524)
				)
				(justify mirror)
			)
		)
		(fp_text user "P1"
			(at 3.108452 -1.27 180)
			(unlocked yes)
			(layer "B.Fab")
			(effects
				(font
					(size 0.7874 0.5842)
					(thickness 0.000001)
				)
				(justify mirror)
			)
		)
		(fp_text user "P32"
			(at -5.781548 -0.0508 180)
			(unlocked yes)
			(layer "B.Fab")
			(effects
				(font
					(size 0.7874 0.5842)
					(thickness 0.000001)
				)
				(justify mirror)
			)
		)
		(fp_text user "PRESS-FIT"
			(at -6.82371 29.8831 0)
			(unlocked yes)
			(layer "B.Fab")
			(effects
				(font
					(size 1.6002 1.1938)
					(thickness 0.000001)
				)
				(justify left mirror)
			)
		)
		(fp_text user "P17"
			(at -5.72135 38.0746 180)
			(unlocked yes)
			(layer "B.Fab")
			(effects
				(font
					(size 0.7874 0.5842)
					(thickness 0.000001)
				)
				(justify mirror)
			)
		)
		(fp_text user "P16"
			(at 3.159252 38.3794 180)
			(unlocked yes)
			(layer "B.Fab")
			(effects
				(font
					(size 0.7874 0.5842)
					(thickness 0.000001)
				)
				(justify mirror)
			)
		)
		(fp_text user "S12"
			(at -5.79374 41.42232 180)
			(unlocked yes)
			(layer "B.Fab")
			(effects
				(font
					(size 0.7874 0.5842)
					(thickness 0.000001)
				)
				(justify mirror)
			)
		)
		(fp_text user "S1"
			(at 3.09626 41.656 180)
			(unlocked yes)
			(layer "B.Fab")
			(effects
				(font
					(size 0.7874 0.5842)
					(thickness 0.000001)
				)
				(justify mirror)
			)
		)
		(fp_text user "S6"
			(at 3.133852 48.0822 180)
			(unlocked yes)
			(layer "B.Fab")
			(effects
				(font
					(size 0.7874 0.5842)
					(thickness 0.000001)
				)
				(justify mirror)
			)
		)
		(fp_text user "S7"
			(at -5.781548 48.0822 180)
			(unlocked yes)
			(layer "B.Fab")
			(effects
				(font
					(size 0.7874 0.5842)
					(thickness 0.000001)
				)
				(justify mirror)
			)
		)
		(fp_text user "P32"
			(at -4.071112 -0.0762 180)
			(unlocked yes)
			(layer "F.Fab")
			(effects
				(font
					(size 0.7874 0.5842)
					(thickness 0.000001)
				)
			)
		)
		(fp_text user "P1"
			(at 1.516888 0 180)
			(unlocked yes)
			(layer "F.Fab")
			(effects
				(font
					(size 0.7874 0.5842)
					(thickness 0.000001)
				)
			)
		)
		(fp_text user "PRESS-FIT"
			(at -6.762496 16.251428 0)
			(unlocked yes)
			(layer "F.Fab")
			(effects
				(font
					(size 1.6002 1.1938)
					(thickness 0.000001)
				)
				(justify left)
			)
		)
		(fp_text user "P17"
			(at -4.366768 38.227 180)
			(unlocked yes)
			(layer "F.Fab")
			(effects
				(font
					(size 0.7874 0.5842)
					(thickness 0.000001)
				)
			)
		)
		(fp_text user "P16"
			(at 2.228088 38.354 180)
			(unlocked yes)
			(layer "F.Fab")
			(effects
				(font
					(size 0.7874 0.5842)
					(thickness 0.000001)
				)
			)
		)
		(fp_text user "S12"
			(at -4.362958 41.09212 180)
			(unlocked yes)
			(layer "F.Fab")
			(effects
				(font
					(size 0.7874 0.5842)
					(thickness 0.000001)
				)
			)
		)
		(fp_text user "S1"
			(at 2.164842 41.6306 180)
			(unlocked yes)
			(layer "F.Fab")
			(effects
				(font
					(size 0.7874 0.5842)
					(thickness 0.000001)
				)
			)
		)
		(fp_text user "S6"
			(at 1.923288 48.133 180)
			(unlocked yes)
			(layer "F.Fab")
			(effects
				(font
					(size 0.7874 0.5842)
					(thickness 0.000001)
				)
			)
		)
		(fp_text user "S7"
			(at -4.426712 48.2346 180)
			(unlocked yes)
			(layer "F.Fab")
			(effects
				(font
					(size 0.7874 0.5842)
					(thickness 0.000001)
				)
			)
		)
		(pad "" np_thru_hole circle
			(at -1.35001 -2.54)
			(size 2.5146 2.5146)
			(drill 2.5146)
			(layers "*.Cu" "*.Mask")
			(clearance 0.381)
			(thermal_gap 0.381)
		)
		(pad "" np_thru_hole circle
			(at 0 50.8)
			(size 2.5146 2.5146)
			(drill 2.5146)
			(layers "*.Cu" "*.Mask")
			(clearance 0.381)
			(thermal_gap 0.381)
		)
		(pad "P1" thru_hole rect
			(at 0 0)
			(size 1.1684 1.1684)
			(drill 0.762)
			(layers "*.Cu" "*.Mask")
			(remove_unused_layers no)
			(net "GND")
			(clearance 0.0508)
			(padstack
				(mode front_inner_back)
				(layer "Inner"
					(shape circle)
					(size 1.1684 1.1684)
					(clearance 0.0508)
				)
				(layer "B.Cu"
					(shape rect)
					(size 1.1684 1.1684)
					(thermal_gap 0.0508)
					(clearance 0.0508)
				)
			)
		)
		(pad "P2" thru_hole circle
			(at 0 2.54)
			(size 1.1684 1.1684)
			(drill 0.762)
			(layers "*.Cu" "*.Mask")
			(remove_unused_layers no)
			(net "GND")
			(clearance 0.0508)
			(thermal_gap 0.0508)
		)
		(pad "P3" thru_hole circle
			(at 0 5.08)
			(size 1.1684 1.1684)
			(drill 0.762)
			(layers "*.Cu" "*.Mask")
			(remove_unused_layers no)
			(net "GND")
			(clearance 0.0508)
			(thermal_gap 0.0508)
		)
		(pad "P4" thru_hole circle
			(at 0 7.62)
			(size 1.1684 1.1684)
			(drill 0.762)
			(layers "*.Cu" "*.Mask")
			(remove_unused_layers no)
			(net "GND")
			(clearance 0.0508)
			(thermal_gap 0.0508)
		)
		(pad "P5" thru_hole circle
			(at 0 10.16)
			(size 1.1684 1.1684)
			(drill 0.762)
			(layers "*.Cu" "*.Mask")
			(remove_unused_layers no)
			(net "GND")
			(clearance 0.0508)
			(thermal_gap 0.0508)
		)
		(pad "P6" thru_hole circle
			(at 0 12.7)
			(size 1.1684 1.1684)
			(drill 0.762)
			(layers "*.Cu" "*.Mask")
			(remove_unused_layers no)
			(net "GND")
			(clearance 0.0508)
			(thermal_gap 0.0508)
		)
		(pad "P7" thru_hole circle
			(at 0 15.24)
			(size 1.1684 1.1684)
			(drill 0.762)
			(layers "*.Cu" "*.Mask")
			(remove_unused_layers no)
			(net "GND")
			(clearance 0.0508)
			(thermal_gap 0.0508)
		)
		(pad "P8" thru_hole circle
			(at 0 17.78)
			(size 1.1684 1.1684)
			(drill 0.762)
			(layers "*.Cu" "*.Mask")
			(remove_unused_layers no)
			(net "GND")
			(clearance 0.0508)
			(thermal_gap 0.0508)
		)
		(pad "P9" thru_hole circle
			(at 0 20.32)
			(size 1.1684 1.1684)
			(drill 0.762)
			(layers "*.Cu" "*.Mask")
			(remove_unused_layers no)
			(net "P12V")
			(clearance 0.0508)
			(thermal_gap 0.0508)
		)
		(pad "P10" thru_hole circle
			(at 0 22.86)
			(size 1.1684 1.1684)
			(drill 0.762)
			(layers "*.Cu" "*.Mask")
			(remove_unused_layers no)
			(net "P12V")
			(clearance 0.0508)
			(thermal_gap 0.0508)
		)
		(pad "P11" thru_hole circle
			(at 0 25.4)
			(size 1.1684 1.1684)
			(drill 0.762)
			(layers "*.Cu" "*.Mask")
			(remove_unused_layers no)
			(net "P12V")
			(clearance 0.0508)
			(thermal_gap 0.0508)
		)
		(pad "P12" thru_hole circle
			(at 0 27.94)
			(size 1.1684 1.1684)
			(drill 0.762)
			(layers "*.Cu" "*.Mask")
			(remove_unused_layers no)
			(net "P12V")
			(clearance 0.0508)
			(thermal_gap 0.0508)
		)
		(pad "P13" thru_hole circle
			(at 0 30.48)
			(size 1.1684 1.1684)
			(drill 0.762)
			(layers "*.Cu" "*.Mask")
			(remove_unused_layers no)
			(net "P12V")
			(clearance 0.0508)
			(thermal_gap 0.0508)
		)
		(pad "P14" thru_hole circle
			(at 0 33.02)
			(size 1.1684 1.1684)
			(drill 0.762)
			(layers "*.Cu" "*.Mask")
			(remove_unused_layers no)
			(net "P12V")
			(clearance 0.0508)
			(thermal_gap 0.0508)
		)
		(pad "P15" thru_hole circle
			(at 0 35.56)
			(size 1.1684 1.1684)
			(drill 0.762)
			(layers "*.Cu" "*.Mask")
			(remove_unused_layers no)
			(net "P12V")
			(clearance 0.0508)
			(thermal_gap 0.0508)
		)
		(pad "P16" thru_hole circle
			(at 0 38.1)
			(size 1.1684 1.1684)
			(drill 0.762)
			(layers "*.Cu" "*.Mask")
			(remove_unused_layers no)
			(net "P12V")
			(clearance 0.0508)
			(thermal_gap 0.0508)
		)
		(pad "P17" thru_hole circle
			(at -2.70002 38.1)
			(size 1.1684 1.1684)
			(drill 0.762)
			(layers "*.Cu" "*.Mask")
			(remove_unused_layers no)
			(net "P12V")
			(clearance 0.0508)
			(thermal_gap 0.0508)
		)
		(pad "P18" thru_hole circle
			(at -2.70002 35.56)
			(size 1.1684 1.1684)
			(drill 0.762)
			(layers "*.Cu" "*.Mask")
			(remove_unused_layers no)
			(net "P12V")
			(clearance 0.0508)
			(thermal_gap 0.0508)
		)
		(pad "P19" thru_hole circle
			(at -2.70002 33.02)
			(size 1.1684 1.1684)
			(drill 0.762)
			(layers "*.Cu" "*.Mask")
			(remove_unused_layers no)
			(net "P12V")
			(clearance 0.0508)
			(thermal_gap 0.0508)
		)
		(pad "P20" thru_hole circle
			(at -2.70002 30.48)
			(size 1.1684 1.1684)
			(drill 0.762)
			(layers "*.Cu" "*.Mask")
			(remove_unused_layers no)
			(net "P12V")
			(clearance 0.0508)
			(thermal_gap 0.0508)
		)
		(pad "P21" thru_hole circle
			(at -2.70002 27.94)
			(size 1.1684 1.1684)
			(drill 0.762)
			(layers "*.Cu" "*.Mask")
			(remove_unused_layers no)
			(net "P12V")
			(clearance 0.0508)
			(thermal_gap 0.0508)
		)
		(pad "P22" thru_hole circle
			(at -2.70002 25.4)
			(size 1.1684 1.1684)
			(drill 0.762)
			(layers "*.Cu" "*.Mask")
			(remove_unused_layers no)
			(net "P12V")
			(clearance 0.0508)
			(thermal_gap 0.0508)
		)
		(pad "P23" thru_hole circle
			(at -2.70002 22.86)
			(size 1.1684 1.1684)
			(drill 0.762)
			(layers "*.Cu" "*.Mask")
			(remove_unused_layers no)
			(net "P12V")
			(clearance 0.0508)
			(thermal_gap 0.0508)
		)
		(pad "P24" thru_hole circle
			(at -2.70002 20.32)
			(size 1.1684 1.1684)
			(drill 0.762)
			(layers "*.Cu" "*.Mask")
			(remove_unused_layers no)
			(net "P12V")
			(clearance 0.0508)
			(thermal_gap 0.0508)
		)
		(pad "P25" thru_hole circle
			(at -2.70002 17.78)
			(size 1.1684 1.1684)
			(drill 0.762)
			(layers "*.Cu" "*.Mask")
			(remove_unused_layers no)
			(net "GND")
			(clearance 0.0508)
			(thermal_gap 0.0508)
		)
		(pad "P26" thru_hole circle
			(at -2.70002 15.24)
			(size 1.1684 1.1684)
			(drill 0.762)
			(layers "*.Cu" "*.Mask")
			(remove_unused_layers no)
			(net "GND")
			(clearance 0.0508)
			(thermal_gap 0.0508)
		)
		(pad "P27" thru_hole circle
			(at -2.70002 12.7)
			(size 1.1684 1.1684)
			(drill 0.762)
			(layers "*.Cu" "*.Mask")
			(remove_unused_layers no)
			(net "GND")
			(clearance 0.0508)
			(thermal_gap 0.0508)
		)
		(pad "P28" thru_hole circle
			(at -2.70002 10.16)
			(size 1.1684 1.1684)
			(drill 0.762)
			(layers "*.Cu" "*.Mask")
			(remove_unused_layers no)
			(net "GND")
			(clearance 0.0508)
			(thermal_gap 0.0508)
		)
		(pad "P29" thru_hole circle
			(at -2.70002 7.62)
			(size 1.1684 1.1684)
			(drill 0.762)
			(layers "*.Cu" "*.Mask")
			(remove_unused_layers no)
			(net "GND")
			(clearance 0.0508)
			(thermal_gap 0.0508)
		)
		(pad "P30" thru_hole circle
			(at -2.70002 5.08)
			(size 1.1684 1.1684)
			(drill 0.762)
			(layers "*.Cu" "*.Mask")
			(remove_unused_layers no)
			(net "GND")
			(clearance 0.0508)
			(thermal_gap 0.0508)
		)
		(pad "P31" thru_hole circle
			(at -2.70002 2.54)
			(size 1.1684 1.1684)
			(drill 0.762)
			(layers "*.Cu" "*.Mask")
			(remove_unused_layers no)
			(net "GND")
			(clearance 0.0508)
			(thermal_gap 0.0508)
		)
		(pad "P32" thru_hole circle
			(at -2.70002 0)
			(size 1.1684 1.1684)
			(drill 0.762)
			(layers "*.Cu" "*.Mask")
			(remove_unused_layers no)
			(net "GND")
			(clearance 0.0508)
			(thermal_gap 0.0508)
		)
		(pad "S1" thru_hole circle
			(at 0.55499 41.60012)
			(size 1.1684 1.1684)
			(drill 0.762)
			(layers "*.Cu" "*.Mask")
			(remove_unused_layers no)
			(net "T4_BLAD1_TXD")
			(clearance 0.0508)
			(thermal_gap 0.0508)
		)
		(pad "S2" thru_hole circle
			(at -0.71501 42.87012)
			(size 1.1684 1.1684)
			(drill 0.762)
			(layers "*.Cu" "*.Mask")
			(remove_unused_layers no)
			(net "T4_BLAD1_RXD")
			(clearance 0.0508)
			(thermal_gap 0.0508)
		)
		(pad "S3" thru_hole circle
			(at 0.55499 44.14012)
			(size 1.1684 1.1684)
			(drill 0.762)
			(layers "*.Cu" "*.Mask")
			(remove_unused_layers no)
			(net "T4_BLAD1_EN")
			(clearance 0.0508)
			(thermal_gap 0.0508)
		)
		(pad "S4" thru_hole circle
			(at -0.71501 45.41012)
			(size 1.1684 1.1684)
			(drill 0.762)
			(layers "*.Cu" "*.Mask")
			(remove_unused_layers no)
			(net "T4_BLAD2_EN")
			(clearance 0.0508)
			(thermal_gap 0.0508)
		)
		(pad "S5" thru_hole circle
			(at 0.55499 46.68012)
			(size 1.1684 1.1684)
			(drill 0.762)
			(layers "*.Cu" "*.Mask")
			(remove_unused_layers no)
			(net "T4_BLAD2_TXD")
			(clearance 0.0508)
			(thermal_gap 0.0508)
		)
		(pad "S6" thru_hole circle
			(at -0.71501 47.95012)
			(size 1.1684 1.1684)
			(drill 0.762)
			(layers "*.Cu" "*.Mask")
			(remove_unused_layers no)
			(net "T4_BLAD2_RXD")
			(clearance 0.0508)
			(thermal_gap 0.0508)
		)
		(pad "S7" thru_hole circle
			(at -3.25501 47.95012)
			(size 1.1684 1.1684)
			(drill 0.762)
			(layers "*.Cu" "*.Mask")
			(remove_unused_layers no)
			(net "T4_BLAD4_RXD")
			(clearance 0.0508)
			(thermal_gap 0.0508)
		)
		(pad "S8" thru_hole circle
			(at -1.98501 46.68012)
			(size 1.1684 1.1684)
			(drill 0.762)
			(layers "*.Cu" "*.Mask")
			(remove_unused_layers no)
			(net "T4_BLAD4_TXD")
			(clearance 0.0508)
			(thermal_gap 0.0508)
		)
		(pad "S9" thru_hole circle
			(at -3.25501 45.41012)
			(size 1.1684 1.1684)
			(drill 0.762)
			(layers "*.Cu" "*.Mask")
			(remove_unused_layers no)
			(net "T4_BLAD4_EN")
			(clearance 0.0508)
			(thermal_gap 0.0508)
		)
		(pad "S10" thru_hole circle
			(at -1.98501 44.14012)
			(size 1.1684 1.1684)
			(drill 0.762)
			(layers "*.Cu" "*.Mask")
			(remove_unused_layers no)
			(net "T4_BLAD3_EN")
			(clearance 0.0508)
			(thermal_gap 0.0508)
		)
		(pad "S11" thru_hole circle
			(at -3.25501 42.87012)
			(size 1.1684 1.1684)
			(drill 0.762)
			(layers "*.Cu" "*.Mask")
			(remove_unused_layers no)
			(net "T4_BLAD3_RXD")
			(clearance 0.0508)
			(thermal_gap 0.0508)
		)
		(pad "S12" thru_hole circle
			(at -1.98501 41.60012)
			(size 1.1684 1.1684)
			(drill 0.762)
			(layers "*.Cu" "*.Mask")
			(remove_unused_layers no)
			(net "T4_BLAD3_TXD")
			(clearance 0.0508)
			(thermal_gap 0.0508)
		)
		(zone
			(layer "F.Cu")
			(hatch none 0.5)
			(connect_pads
				(clearance 0)
			)
			(min_thickness 0.25)
			(keepout
				(tracks allowed)
				(vias not_allowed)
				(pads allowed)
				(copperpour not_allowed)
				(footprints allowed)
			)
			(placement
				(enabled no)
				(sheetname "")
			)
			(fill
				(thermal_gap 0.5)
				(thermal_bridge_width 0.5)
				(island_removal_mode 0)
			)
			(polygon
				(pts
					(xy 85.010244 -142.80388) (xy 92.655644 -142.80388) (xy 92.655644 -137.69848) (xy 85.010244 -137.69848)
					(xy 84.984844 -137.69848) (xy 84.984844 -142.80388)
				)
			)
		)
		(zone
			(layer "F.Cu")
			(hatch none 0.5)
			(connect_pads
				(clearance 0)
			)
			(min_thickness 0.25)
			(keepout
				(tracks allowed)
				(vias not_allowed)
				(pads allowed)
				(copperpour not_allowed)
				(footprints allowed)
			)
			(placement
				(enabled no)
				(sheetname "")
			)
			(fill
				(thermal_gap 0.5)
				(thermal_bridge_width 0.5)
				(island_removal_mode 0)
			)
			(polygon
				(pts
					(xy 43.379644 -138.28268) (xy 43.379644 -142.24508) (xy 82.775044 -142.24508) (xy 82.800444 -142.24508)
					(xy 82.800444 -138.28268) (xy 82.800444 -138.25728) (xy 43.379644 -138.25728)
				)
			)
		)
		(zone
			(layers "F.Cu" "B.Cu" "In1.Cu" "In2.Cu" "In3.Cu" "In4.Cu" "In5.Cu" "In6.Cu")
			(hatch none 0.5)
			(connect_pads
				(clearance 0)
			)
			(min_thickness 0.25)
			(keepout
				(tracks not_allowed)
				(vias allowed)
				(pads allowed)
				(copperpour not_allowed)
				(footprints allowed)
			)
			(placement
				(enabled no)
				(sheetname "")
			)
			(fill
				(thermal_gap 0.5)
				(thermal_bridge_width 0.5)
				(island_removal_mode 0)
			)
			(polygon
				(pts
					(arc
						(start 43.180254 -140.26007)
						(mid 39.819834 -140.26007)
						(end 43.180254 -140.26007)
					)
				)
			)
		)
		(zone
			(layers "F.Cu" "B.Cu" "In1.Cu" "In2.Cu" "In3.Cu" "In4.Cu" "In5.Cu" "In6.Cu")
			(hatch none 0.5)
			(connect_pads
				(clearance 0)
			)
			(min_thickness 0.25)
			(keepout
				(tracks not_allowed)
				(vias allowed)
				(pads allowed)
				(copperpour not_allowed)
				(footprints allowed)
			)
			(placement
				(enabled no)
				(sheetname "")
			)
			(fill
				(thermal_gap 0.5)
				(thermal_bridge_width 0.5)
				(island_removal_mode 0)
			)
			(polygon
				(pts
					(arc
						(start 96.524064 -141.61008)
						(mid 93.156024 -141.61008)
						(end 96.524064 -141.61008)
					)
				)
			)
		)
	)
	(footprint ""
		(layer "B.Cu")
		(at 44.03979 -408.31008 90)
		(property "Reference" "J16"
			(at 6.272784 -4.326636 0)
			(unlocked yes)
			(layer "B.SilkS")
			(effects
				(font
					(size 0.7874 0.5842)
					(thickness 0.1524)
				)
				(justify left mirror)
			)
		)
		(property "Value" ""
			(at 0 0 90)
			(layer "B.Fab")
			(effects
				(font
					(size 1.27 1.27)
				)
				(justify mirror)
			)
		)
		(duplicate_pad_numbers_are_jumpers no)
		(fp_line
			(start 5.275072 -13.910056)
			(end -7.975092 -13.910056)
			(stroke
				(width 0.1524)
				(type default)
			)
			(layer "F.SilkS")
		)
		(fp_line
			(start -7.975092 -13.910056)
			(end -7.975092 62.170056)
			(stroke
				(width 0.1524)
				(type default)
			)
			(layer "F.SilkS")
		)
		(fp_line
			(start 5.275072 62.170056)
			(end 5.275072 -13.910056)
			(stroke
				(width 0.1524)
				(type default)
			)
			(layer "F.SilkS")
		)
		(fp_line
			(start -7.975092 62.170056)
			(end 5.275072 62.170056)
			(stroke
				(width 0.1524)
				(type default)
			)
			(layer "F.SilkS")
		)
		(fp_line
			(start 5.275072 -13.910056)
			(end -7.975092 -13.910056)
			(stroke
				(width 0.1524)
				(type default)
			)
			(layer "B.SilkS")
		)
		(fp_line
			(start -7.975092 -13.910056)
			(end -7.975092 62.170056)
			(stroke
				(width 0.1524)
				(type default)
			)
			(layer "B.SilkS")
		)
		(fp_line
			(start 2.275078 -10.910062)
			(end 2.275078 59.170062)
			(stroke
				(width 0.1524)
				(type default)
			)
			(layer "B.SilkS")
		)
		(fp_line
			(start -4.975098 -10.910062)
			(end 2.275078 -10.910062)
			(stroke
				(width 0.1524)
				(type default)
			)
			(layer "B.SilkS")
		)
		(fp_line
			(start 2.275078 59.170062)
			(end -4.975098 59.170062)
			(stroke
				(width 0.1524)
				(type default)
			)
			(layer "B.SilkS")
		)
		(fp_line
			(start -4.975098 59.170062)
			(end -4.975098 -10.910062)
			(stroke
				(width 0.1524)
				(type default)
			)
			(layer "B.SilkS")
		)
		(fp_line
			(start 5.275072 62.170056)
			(end 5.275072 -13.910056)
			(stroke
				(width 0.1524)
				(type default)
			)
			(layer "B.SilkS")
		)
		(fp_line
			(start -7.975092 62.170056)
			(end 5.275072 62.170056)
			(stroke
				(width 0.1524)
				(type default)
			)
			(layer "B.SilkS")
		)
		(fp_poly
			(pts
				(xy 4.103878 -0.759206) (xy 4.103878 0.764794) (xy 2.579878 0.002794)
			)
			(stroke
				(width 0)
				(type default)
			)
			(fill yes)
			(layer "B.SilkS")
		)
		(fp_poly
			(pts
				(xy 2.275078 -10.910062) (xy 2.275078 59.170062) (xy -4.975098 59.170062) (xy -4.975098 -10.910062)
			)
			(stroke
				(width 0)
				(type default)
			)
			(fill no)
			(layer "B.CrtYd")
		)
		(fp_poly
			(pts
				(xy 1.1938 40.9702) (xy 1.1938 48.6156) (xy -3.9116 48.6156) (xy -3.9116 40.9702) (xy -3.9116 40.9448)
				(xy 1.1938 40.9448)
			)
			(stroke
				(width 0)
				(type default)
			)
			(fill no)
			(layer "F.CrtYd")
		)
		(fp_poly
			(pts
				(xy -3.3274 -0.6604) (xy 0.635 -0.6604) (xy 0.635 38.735) (xy 0.635 38.7604) (xy -3.3274 38.7604)
				(xy -3.3528 38.7604) (xy -3.3528 -0.6604)
			)
			(stroke
				(width 0)
				(type default)
			)
			(fill no)
			(layer "F.CrtYd")
		)
		(fp_poly
			(pts
				(arc
					(start -1.35001 -1.01219)
					(mid -1.35001 -4.06781)
					(end -1.35001 -1.01219)
				)
			)
			(stroke
				(width 0)
				(type default)
			)
			(fill no)
			(layer "F.CrtYd")
		)
		(fp_poly
			(pts
				(arc
					(start 0 52.33162)
					(mid 0 49.26838)
					(end 0 52.33162)
				)
			)
			(stroke
				(width 0)
				(type default)
			)
			(fill no)
			(layer "F.CrtYd")
		)
		(fp_line
			(start 2.275078 -10.910062)
			(end 2.275078 59.170062)
			(stroke
				(width 0.1)
				(type default)
			)
			(layer "B.Fab")
		)
		(fp_line
			(start -4.975098 -10.910062)
			(end 2.275078 -10.910062)
			(stroke
				(width 0.1)
				(type default)
			)
			(layer "B.Fab")
		)
		(fp_line
			(start 2.275078 59.170062)
			(end -4.975098 59.170062)
			(stroke
				(width 0.1)
				(type default)
			)
			(layer "B.Fab")
		)
		(fp_line
			(start -4.975098 59.170062)
			(end -4.975098 -10.910062)
			(stroke
				(width 0.1)
				(type default)
			)
			(layer "B.Fab")
		)
		(fp_poly
			(pts
				(xy 4.103878 -0.759206) (xy 4.103878 0.764794) (xy 2.579878 0.002794)
			)
			(stroke
				(width 0)
				(type default)
			)
			(fill yes)
			(layer "B.Fab")
		)
		(fp_line
			(start 5.275072 -13.910056)
			(end -7.975092 -13.910056)
			(stroke
				(width 0.1)
				(type default)
			)
			(layer "F.Fab")
		)
		(fp_line
			(start -7.975092 -13.910056)
			(end -7.975092 62.170056)
			(stroke
				(width 0.1)
				(type default)
			)
			(layer "F.Fab")
		)
		(fp_line
			(start 5.275072 62.170056)
			(end 5.275072 -13.910056)
			(stroke
				(width 0.1)
				(type default)
			)
			(layer "F.Fab")
		)
		(fp_line
			(start -7.975092 62.170056)
			(end 5.275072 62.170056)
			(stroke
				(width 0.1)
				(type default)
			)
			(layer "F.Fab")
		)
		(fp_text user "P32"
			(at -8.804656 0.001778 0)
			(unlocked yes)
			(layer "F.SilkS")
			(effects
				(font
					(size 0.7874 0.5842)
					(thickness 0.1524)
				)
			)
		)
		(fp_text user "P1"
			(at 6.234176 0.469646 0)
			(unlocked yes)
			(layer "F.SilkS")
			(effects
				(font
					(size 0.7874 0.5842)
					(thickness 0.1524)
				)
			)
		)
		(fp_text user "PRESS-FIT"
			(at -9.339326 15.441422 0)
			(unlocked yes)
			(layer "F.SilkS")
			(effects
				(font
					(size 0.7874 0.5842)
					(thickness 0.1524)
				)
				(justify left)
			)
		)
		(fp_text user "P16"
			(at 5.963666 37.724842 0)
			(unlocked yes)
			(layer "F.SilkS")
			(effects
				(font
					(size 0.7874 0.5842)
					(thickness 0.1524)
				)
			)
		)
		(fp_text user "P17"
			(at -11.678158 38.451536 0)
			(unlocked yes)
			(layer "F.SilkS")
			(effects
				(font
					(size 0.7874 0.5842)
					(thickness 0.1524)
				)
			)
		)
		(fp_text user "S1"
			(at 6.265164 41.224454 0)
			(unlocked yes)
			(layer "F.SilkS")
			(effects
				(font
					(size 0.7874 0.5842)
					(thickness 0.1524)
				)
			)
		)
		(fp_text user "S12"
			(at -11.443462 41.784016 0)
			(unlocked yes)
			(layer "F.SilkS")
			(effects
				(font
					(size 0.7874 0.5842)
					(thickness 0.1524)
				)
			)
		)
		(fp_text user "S6"
			(at 6.030214 47.525686 0)
			(unlocked yes)
			(layer "F.SilkS")
			(effects
				(font
					(size 0.7874 0.5842)
					(thickness 0.1524)
				)
			)
		)
		(fp_text user "S7"
			(at -11.651996 48.364394 0)
			(unlocked yes)
			(layer "F.SilkS")
			(effects
				(font
					(size 0.7874 0.5842)
					(thickness 0.1524)
				)
			)
		)
		(fp_text user "P1"
			(at 2.951988 -1.351788 0)
			(unlocked yes)
			(layer "B.SilkS")
			(effects
				(font
					(size 0.7874 0.5842)
					(thickness 0.1524)
				)
				(justify mirror)
			)
		)
		(fp_text user "P32"
			(at -5.865876 0.085344 0)
			(unlocked yes)
			(layer "B.SilkS")
			(effects
				(font
					(size 0.7874 0.5842)
					(thickness 0.1524)
				)
				(justify mirror)
			)
		)
		(fp_text user "PRESS-FIT"
			(at -7.18947 29.8831 0)
			(unlocked yes)
			(layer "B.SilkS")
			(effects
				(font
					(size 0.7874 0.5842)
					(thickness 0.1524)
				)
				(justify left mirror)
			)
		)
		(fp_text user "P17"
			(at -5.858002 37.627814 0)
			(unlocked yes)
			(layer "B.SilkS")
			(effects
				(font
					(size 0.7874 0.5842)
					(thickness 0.1524)
				)
				(justify mirror)
			)
		)
		(fp_text user "P16"
			(at 3.071622 37.902134 0)
			(unlocked yes)
			(layer "B.SilkS")
			(effects
				(font
					(size 0.7874 0.5842)
					(thickness 0.1524)
				)
				(justify mirror)
			)
		)
		(fp_text user "S1"
			(at 3.066542 41.60647 0)
			(unlocked yes)
			(layer "B.SilkS")
			(effects
				(font
					(size 0.7874 0.5842)
					(thickness 0.1524)
				)
				(justify mirror)
			)
		)
		(fp_text user "S12"
			(at -5.725668 42.13733 180)
			(unlocked yes)
			(layer "B.SilkS")
			(effects
				(font
					(size 0.7874 0.5842)
					(thickness 0.1524)
				)
				(justify mirror)
			)
		)
		(fp_text user "S6"
			(at 3.02895 47.780194 0)
			(unlocked yes)
			(layer "B.SilkS")
			(effects
				(font
					(size 0.7874 0.5842)
					(thickness 0.1524)
				)
				(justify mirror)
			)
		)
		(fp_text user "S7"
			(at -5.899658 48.120808 0)
			(unlocked yes)
			(layer "B.SilkS")
			(effects
				(font
					(size 0.7874 0.5842)
					(thickness 0.1524)
				)
				(justify mirror)
			)
		)
		(fp_text user "P1"
			(at 3.108452 -1.27 180)
			(unlocked yes)
			(layer "B.Fab")
			(effects
				(font
					(size 0.7874 0.5842)
					(thickness 0.000001)
				)
				(justify mirror)
			)
		)
		(fp_text user "P32"
			(at -5.781548 -0.0508 180)
			(unlocked yes)
			(layer "B.Fab")
			(effects
				(font
					(size 0.7874 0.5842)
					(thickness 0.000001)
				)
				(justify mirror)
			)
		)
		(fp_text user "PRESS-FIT"
			(at -6.82371 29.8831 0)
			(unlocked yes)
			(layer "B.Fab")
			(effects
				(font
					(size 1.6002 1.1938)
					(thickness 0.000001)
				)
				(justify left mirror)
			)
		)
		(fp_text user "P17"
			(at -5.72135 38.0746 180)
			(unlocked yes)
			(layer "B.Fab")
			(effects
				(font
					(size 0.7874 0.5842)
					(thickness 0.000001)
				)
				(justify mirror)
			)
		)
		(fp_text user "P16"
			(at 3.159252 38.3794 180)
			(unlocked yes)
			(layer "B.Fab")
			(effects
				(font
					(size 0.7874 0.5842)
					(thickness 0.000001)
				)
				(justify mirror)
			)
		)
		(fp_text user "S12"
			(at -5.79374 41.42232 180)
			(unlocked yes)
			(layer "B.Fab")
			(effects
				(font
					(size 0.7874 0.5842)
					(thickness 0.000001)
				)
				(justify mirror)
			)
		)
		(fp_text user "S1"
			(at 3.09626 41.656 180)
			(unlocked yes)
			(layer "B.Fab")
			(effects
				(font
					(size 0.7874 0.5842)
					(thickness 0.000001)
				)
				(justify mirror)
			)
		)
		(fp_text user "S6"
			(at 3.133852 48.0822 180)
			(unlocked yes)
			(layer "B.Fab")
			(effects
				(font
					(size 0.7874 0.5842)
					(thickness 0.000001)
				)
				(justify mirror)
			)
		)
		(fp_text user "S7"
			(at -5.781548 48.0822 180)
			(unlocked yes)
			(layer "B.Fab")
			(effects
				(font
					(size 0.7874 0.5842)
					(thickness 0.000001)
				)
				(justify mirror)
			)
		)
		(fp_text user "P32"
			(at -4.071112 -0.0762 180)
			(unlocked yes)
			(layer "F.Fab")
			(effects
				(font
					(size 0.7874 0.5842)
					(thickness 0.000001)
				)
			)
		)
		(fp_text user "P1"
			(at 1.516888 0 180)
			(unlocked yes)
			(layer "F.Fab")
			(effects
				(font
					(size 0.7874 0.5842)
					(thickness 0.000001)
				)
			)
		)
		(fp_text user "PRESS-FIT"
			(at -6.762496 16.251428 0)
			(unlocked yes)
			(layer "F.Fab")
			(effects
				(font
					(size 1.6002 1.1938)
					(thickness 0.000001)
				)
				(justify left)
			)
		)
		(fp_text user "P17"
			(at -4.366768 38.227 180)
			(unlocked yes)
			(layer "F.Fab")
			(effects
				(font
					(size 0.7874 0.5842)
					(thickness 0.000001)
				)
			)
		)
		(fp_text user "P16"
			(at 2.228088 38.354 180)
			(unlocked yes)
			(layer "F.Fab")
			(effects
				(font
					(size 0.7874 0.5842)
					(thickness 0.000001)
				)
			)
		)
		(fp_text user "S12"
			(at -4.362958 41.09212 180)
			(unlocked yes)
			(layer "F.Fab")
			(effects
				(font
					(size 0.7874 0.5842)
					(thickness 0.000001)
				)
			)
		)
		(fp_text user "S1"
			(at 2.164842 41.6306 180)
			(unlocked yes)
			(layer "F.Fab")
			(effects
				(font
					(size 0.7874 0.5842)
					(thickness 0.000001)
				)
			)
		)
		(fp_text user "S6"
			(at 1.923288 48.133 180)
			(unlocked yes)
			(layer "F.Fab")
			(effects
				(font
					(size 0.7874 0.5842)
					(thickness 0.000001)
				)
			)
		)
		(fp_text user "S7"
			(at -4.426712 48.2346 180)
			(unlocked yes)
			(layer "F.Fab")
			(effects
				(font
					(size 0.7874 0.5842)
					(thickness 0.000001)
				)
			)
		)
		(pad "" np_thru_hole circle
			(at -1.35001 -2.54)
			(size 2.5146 2.5146)
			(drill 2.5146)
			(layers "*.Cu" "*.Mask")
			(clearance 0.381)
			(thermal_gap 0.381)
		)
		(pad "" np_thru_hole circle
			(at 0 50.8)
			(size 2.5146 2.5146)
			(drill 2.5146)
			(layers "*.Cu" "*.Mask")
			(clearance 0.381)
			(thermal_gap 0.381)
		)
		(pad "P1" thru_hole rect
			(at 0 0)
			(size 1.1684 1.1684)
			(drill 0.762)
			(layers "*.Cu" "*.Mask")
			(remove_unused_layers no)
			(net "GND")
			(clearance 0.0508)
			(padstack
				(mode front_inner_back)
				(layer "Inner"
					(shape circle)
					(size 1.1684 1.1684)
					(clearance 0.0508)
				)
				(layer "B.Cu"
					(shape rect)
					(size 1.1684 1.1684)
					(thermal_gap 0.0508)
					(clearance 0.0508)
				)
			)
		)
		(pad "P2" thru_hole circle
			(at 0 2.54)
			(size 1.1684 1.1684)
			(drill 0.762)
			(layers "*.Cu" "*.Mask")
			(remove_unused_layers no)
			(net "GND")
			(clearance 0.0508)
			(thermal_gap 0.0508)
		)
		(pad "P3" thru_hole circle
			(at 0 5.08)
			(size 1.1684 1.1684)
			(drill 0.762)
			(layers "*.Cu" "*.Mask")
			(remove_unused_layers no)
			(net "GND")
			(clearance 0.0508)
			(thermal_gap 0.0508)
		)
		(pad "P4" thru_hole circle
			(at 0 7.62)
			(size 1.1684 1.1684)
			(drill 0.762)
			(layers "*.Cu" "*.Mask")
			(remove_unused_layers no)
			(net "GND")
			(clearance 0.0508)
			(thermal_gap 0.0508)
		)
		(pad "P5" thru_hole circle
			(at 0 10.16)
			(size 1.1684 1.1684)
			(drill 0.762)
			(layers "*.Cu" "*.Mask")
			(remove_unused_layers no)
			(net "GND")
			(clearance 0.0508)
			(thermal_gap 0.0508)
		)
		(pad "P6" thru_hole circle
			(at 0 12.7)
			(size 1.1684 1.1684)
			(drill 0.762)
			(layers "*.Cu" "*.Mask")
			(remove_unused_layers no)
			(net "GND")
			(clearance 0.0508)
			(thermal_gap 0.0508)
		)
		(pad "P7" thru_hole circle
			(at 0 15.24)
			(size 1.1684 1.1684)
			(drill 0.762)
			(layers "*.Cu" "*.Mask")
			(remove_unused_layers no)
			(net "GND")
			(clearance 0.0508)
			(thermal_gap 0.0508)
		)
		(pad "P8" thru_hole circle
			(at 0 17.78)
			(size 1.1684 1.1684)
			(drill 0.762)
			(layers "*.Cu" "*.Mask")
			(remove_unused_layers no)
			(net "GND")
			(clearance 0.0508)
			(thermal_gap 0.0508)
		)
		(pad "P9" thru_hole circle
			(at 0 20.32)
			(size 1.1684 1.1684)
			(drill 0.762)
			(layers "*.Cu" "*.Mask")
			(remove_unused_layers no)
			(net "P12V")
			(clearance 0.0508)
			(thermal_gap 0.0508)
		)
		(pad "P10" thru_hole circle
			(at 0 22.86)
			(size 1.1684 1.1684)
			(drill 0.762)
			(layers "*.Cu" "*.Mask")
			(remove_unused_layers no)
			(net "P12V")
			(clearance 0.0508)
			(thermal_gap 0.0508)
		)
		(pad "P11" thru_hole circle
			(at 0 25.4)
			(size 1.1684 1.1684)
			(drill 0.762)
			(layers "*.Cu" "*.Mask")
			(remove_unused_layers no)
			(net "P12V")
			(clearance 0.0508)
			(thermal_gap 0.0508)
		)
		(pad "P12" thru_hole circle
			(at 0 27.94)
			(size 1.1684 1.1684)
			(drill 0.762)
			(layers "*.Cu" "*.Mask")
			(remove_unused_layers no)
			(net "P12V")
			(clearance 0.0508)
			(thermal_gap 0.0508)
		)
		(pad "P13" thru_hole circle
			(at 0 30.48)
			(size 1.1684 1.1684)
			(drill 0.762)
			(layers "*.Cu" "*.Mask")
			(remove_unused_layers no)
			(net "P12V")
			(clearance 0.0508)
			(thermal_gap 0.0508)
		)
		(pad "P14" thru_hole circle
			(at 0 33.02)
			(size 1.1684 1.1684)
			(drill 0.762)
			(layers "*.Cu" "*.Mask")
			(remove_unused_layers no)
			(net "P12V")
			(clearance 0.0508)
			(thermal_gap 0.0508)
		)
		(pad "P15" thru_hole circle
			(at 0 35.56)
			(size 1.1684 1.1684)
			(drill 0.762)
			(layers "*.Cu" "*.Mask")
			(remove_unused_layers no)
			(net "P12V")
			(clearance 0.0508)
			(thermal_gap 0.0508)
		)
		(pad "P16" thru_hole circle
			(at 0 38.1)
			(size 1.1684 1.1684)
			(drill 0.762)
			(layers "*.Cu" "*.Mask")
			(remove_unused_layers no)
			(net "P12V")
			(clearance 0.0508)
			(thermal_gap 0.0508)
		)
		(pad "P17" thru_hole circle
			(at -2.70002 38.1)
			(size 1.1684 1.1684)
			(drill 0.762)
			(layers "*.Cu" "*.Mask")
			(remove_unused_layers no)
			(net "P12V")
			(clearance 0.0508)
			(thermal_gap 0.0508)
		)
		(pad "P18" thru_hole circle
			(at -2.70002 35.56)
			(size 1.1684 1.1684)
			(drill 0.762)
			(layers "*.Cu" "*.Mask")
			(remove_unused_layers no)
			(net "P12V")
			(clearance 0.0508)
			(thermal_gap 0.0508)
		)
		(pad "P19" thru_hole circle
			(at -2.70002 33.02)
			(size 1.1684 1.1684)
			(drill 0.762)
			(layers "*.Cu" "*.Mask")
			(remove_unused_layers no)
			(net "P12V")
			(clearance 0.0508)
			(thermal_gap 0.0508)
		)
		(pad "P20" thru_hole circle
			(at -2.70002 30.48)
			(size 1.1684 1.1684)
			(drill 0.762)
			(layers "*.Cu" "*.Mask")
			(remove_unused_layers no)
			(net "P12V")
			(clearance 0.0508)
			(thermal_gap 0.0508)
		)
		(pad "P21" thru_hole circle
			(at -2.70002 27.94)
			(size 1.1684 1.1684)
			(drill 0.762)
			(layers "*.Cu" "*.Mask")
			(remove_unused_layers no)
			(net "P12V")
			(clearance 0.0508)
			(thermal_gap 0.0508)
		)
		(pad "P22" thru_hole circle
			(at -2.70002 25.4)
			(size 1.1684 1.1684)
			(drill 0.762)
			(layers "*.Cu" "*.Mask")
			(remove_unused_layers no)
			(net "P12V")
			(clearance 0.0508)
			(thermal_gap 0.0508)
		)
		(pad "P23" thru_hole circle
			(at -2.70002 22.86)
			(size 1.1684 1.1684)
			(drill 0.762)
			(layers "*.Cu" "*.Mask")
			(remove_unused_layers no)
			(net "P12V")
			(clearance 0.0508)
			(thermal_gap 0.0508)
		)
		(pad "P24" thru_hole circle
			(at -2.70002 20.32)
			(size 1.1684 1.1684)
			(drill 0.762)
			(layers "*.Cu" "*.Mask")
			(remove_unused_layers no)
			(net "P12V")
			(clearance 0.0508)
			(thermal_gap 0.0508)
		)
		(pad "P25" thru_hole circle
			(at -2.70002 17.78)
			(size 1.1684 1.1684)
			(drill 0.762)
			(layers "*.Cu" "*.Mask")
			(remove_unused_layers no)
			(net "GND")
			(clearance 0.0508)
			(thermal_gap 0.0508)
		)
		(pad "P26" thru_hole circle
			(at -2.70002 15.24)
			(size 1.1684 1.1684)
			(drill 0.762)
			(layers "*.Cu" "*.Mask")
			(remove_unused_layers no)
			(net "GND")
			(clearance 0.0508)
			(thermal_gap 0.0508)
		)
		(pad "P27" thru_hole circle
			(at -2.70002 12.7)
			(size 1.1684 1.1684)
			(drill 0.762)
			(layers "*.Cu" "*.Mask")
			(remove_unused_layers no)
			(net "GND")
			(clearance 0.0508)
			(thermal_gap 0.0508)
		)
		(pad "P28" thru_hole circle
			(at -2.70002 10.16)
			(size 1.1684 1.1684)
			(drill 0.762)
			(layers "*.Cu" "*.Mask")
			(remove_unused_layers no)
			(net "GND")
			(clearance 0.0508)
			(thermal_gap 0.0508)
		)
		(pad "P29" thru_hole circle
			(at -2.70002 7.62)
			(size 1.1684 1.1684)
			(drill 0.762)
			(layers "*.Cu" "*.Mask")
			(remove_unused_layers no)
			(net "GND")
			(clearance 0.0508)
			(thermal_gap 0.0508)
		)
		(pad "P30" thru_hole circle
			(at -2.70002 5.08)
			(size 1.1684 1.1684)
			(drill 0.762)
			(layers "*.Cu" "*.Mask")
			(remove_unused_layers no)
			(net "GND")
			(clearance 0.0508)
			(thermal_gap 0.0508)
		)
		(pad "P31" thru_hole circle
			(at -2.70002 2.54)
			(size 1.1684 1.1684)
			(drill 0.762)
			(layers "*.Cu" "*.Mask")
			(remove_unused_layers no)
			(net "GND")
			(clearance 0.0508)
			(thermal_gap 0.0508)
		)
		(pad "P32" thru_hole circle
			(at -2.70002 0)
			(size 1.1684 1.1684)
			(drill 0.762)
			(layers "*.Cu" "*.Mask")
			(remove_unused_layers no)
			(net "GND")
			(clearance 0.0508)
			(thermal_gap 0.0508)
		)
		(pad "S1" thru_hole circle
			(at 0.55499 41.60012)
			(size 1.1684 1.1684)
			(drill 0.762)
			(layers "*.Cu" "*.Mask")
			(remove_unused_layers no)
			(net "T10_BLAD1_TXD")
			(clearance 0.0508)
			(thermal_gap 0.0508)
		)
		(pad "S2" thru_hole circle
			(at -0.71501 42.87012)
			(size 1.1684 1.1684)
			(drill 0.762)
			(layers "*.Cu" "*.Mask")
			(remove_unused_layers no)
			(net "T10_BLAD1_RXD")
			(clearance 0.0508)
			(thermal_gap 0.0508)
		)
		(pad "S3" thru_hole circle
			(at 0.55499 44.14012)
			(size 1.1684 1.1684)
			(drill 0.762)
			(layers "*.Cu" "*.Mask")
			(remove_unused_layers no)
			(net "T10_BLAD1_EN")
			(clearance 0.0508)
			(thermal_gap 0.0508)
		)
		(pad "S4" thru_hole circle
			(at -0.71501 45.41012)
			(size 1.1684 1.1684)
			(drill 0.762)
			(layers "*.Cu" "*.Mask")
			(remove_unused_layers no)
			(net "T10_BLAD2_EN")
			(clearance 0.0508)
			(thermal_gap 0.0508)
		)
		(pad "S5" thru_hole circle
			(at 0.55499 46.68012)
			(size 1.1684 1.1684)
			(drill 0.762)
			(layers "*.Cu" "*.Mask")
			(remove_unused_layers no)
			(net "T10_BLAD2_TXD")
			(clearance 0.0508)
			(thermal_gap 0.0508)
		)
		(pad "S6" thru_hole circle
			(at -0.71501 47.95012)
			(size 1.1684 1.1684)
			(drill 0.762)
			(layers "*.Cu" "*.Mask")
			(remove_unused_layers no)
			(net "T10_BLAD2_RXD")
			(clearance 0.0508)
			(thermal_gap 0.0508)
		)
		(pad "S7" thru_hole circle
			(at -3.25501 47.95012)
			(size 1.1684 1.1684)
			(drill 0.762)
			(layers "*.Cu" "*.Mask")
			(remove_unused_layers no)
			(net "T10_BLAD4_RXD")
			(clearance 0.0508)
			(thermal_gap 0.0508)
		)
		(pad "S8" thru_hole circle
			(at -1.98501 46.68012)
			(size 1.1684 1.1684)
			(drill 0.762)
			(layers "*.Cu" "*.Mask")
			(remove_unused_layers no)
			(net "T10_BLAD4_TXD")
			(clearance 0.0508)
			(thermal_gap 0.0508)
		)
		(pad "S9" thru_hole circle
			(at -3.25501 45.41012)
			(size 1.1684 1.1684)
			(drill 0.762)
			(layers "*.Cu" "*.Mask")
			(remove_unused_layers no)
			(net "T10_BLAD4_EN")
			(clearance 0.0508)
			(thermal_gap 0.0508)
		)
		(pad "S10" thru_hole circle
			(at -1.98501 44.14012)
			(size 1.1684 1.1684)
			(drill 0.762)
			(layers "*.Cu" "*.Mask")
			(remove_unused_layers no)
			(net "T10_BLAD3_EN")
			(clearance 0.0508)
			(thermal_gap 0.0508)
		)
		(pad "S11" thru_hole circle
			(at -3.25501 42.87012)
			(size 1.1684 1.1684)
			(drill 0.762)
			(layers "*.Cu" "*.Mask")
			(remove_unused_layers no)
			(net "T10_BLAD3_RXD")
			(clearance 0.0508)
			(thermal_gap 0.0508)
		)
		(pad "S12" thru_hole circle
			(at -1.98501 41.60012)
			(size 1.1684 1.1684)
			(drill 0.762)
			(layers "*.Cu" "*.Mask")
			(remove_unused_layers no)
			(net "T10_BLAD3_TXD")
			(clearance 0.0508)
			(thermal_gap 0.0508)
		)
		(zone
			(layer "F.Cu")
			(hatch none 0.5)
			(connect_pads
				(clearance 0)
			)
			(min_thickness 0.25)
			(keepout
				(tracks allowed)
				(vias not_allowed)
				(pads allowed)
				(copperpour not_allowed)
				(footprints allowed)
			)
			(placement
				(enabled no)
				(sheetname "")
			)
			(fill
				(thermal_gap 0.5)
				(thermal_bridge_width 0.5)
				(island_removal_mode 0)
			)
			(polygon
				(pts
					(xy 85.00999 -409.50388) (xy 92.65539 -409.50388) (xy 92.65539 -404.39848) (xy 85.00999 -404.39848)
					(xy 84.98459 -404.39848) (xy 84.98459 -409.50388)
				)
			)
		)
		(zone
			(layer "F.Cu")
			(hatch none 0.5)
			(connect_pads
				(clearance 0)
			)
			(min_thickness 0.25)
			(keepout
				(tracks allowed)
				(vias not_allowed)
				(pads allowed)
				(copperpour not_allowed)
				(footprints allowed)
			)
			(placement
				(enabled no)
				(sheetname "")
			)
			(fill
				(thermal_gap 0.5)
				(thermal_bridge_width 0.5)
				(island_removal_mode 0)
			)
			(polygon
				(pts
					(xy 43.37939 -404.98268) (xy 43.37939 -408.94508) (xy 82.77479 -408.94508) (xy 82.80019 -408.94508)
					(xy 82.80019 -404.98268) (xy 82.80019 -404.95728) (xy 43.37939 -404.95728)
				)
			)
		)
		(zone
			(layers "F.Cu" "B.Cu" "In1.Cu" "In2.Cu" "In3.Cu" "In4.Cu" "In5.Cu" "In6.Cu")
			(hatch none 0.5)
			(connect_pads
				(clearance 0)
			)
			(min_thickness 0.25)
			(keepout
				(tracks not_allowed)
				(vias allowed)
				(pads allowed)
				(copperpour not_allowed)
				(footprints allowed)
			)
			(placement
				(enabled no)
				(sheetname "")
			)
			(fill
				(thermal_gap 0.5)
				(thermal_bridge_width 0.5)
				(island_removal_mode 0)
			)
			(polygon
				(pts
					(arc
						(start 43.18 -406.96007)
						(mid 39.81958 -406.96007)
						(end 43.18 -406.96007)
					)
				)
			)
		)
		(zone
			(layers "F.Cu" "B.Cu" "In1.Cu" "In2.Cu" "In3.Cu" "In4.Cu" "In5.Cu" "In6.Cu")
			(hatch none 0.5)
			(connect_pads
				(clearance 0)
			)
			(min_thickness 0.25)
			(keepout
				(tracks not_allowed)
				(vias allowed)
				(pads allowed)
				(copperpour not_allowed)
				(footprints allowed)
			)
			(placement
				(enabled no)
				(sheetname "")
			)
			(fill
				(thermal_gap 0.5)
				(thermal_bridge_width 0.5)
				(island_removal_mode 0)
			)
			(polygon
				(pts
					(arc
						(start 96.52381 -408.31008)
						(mid 93.15577 -408.31008)
						(end 96.52381 -408.31008)
					)
				)
			)
		)
	)
	(footprint ""
		(layer "B.Cu")
		(at 98.951288 -16.810228)
		(property "Reference" ""
			(at 0 0 0)
			(layer "B.SilkS")
			(hide yes)
			(effects
				(font
					(size 1.27 1.27)
				)
				(justify mirror)
			)
		)
		(property "Value" ""
			(at 0 0 0)
			(layer "B.Fab")
			(effects
				(font
					(size 1.27 1.27)
				)
				(justify mirror)
			)
		)
		(duplicate_pad_numbers_are_jumpers no)
		(fp_poly
			(pts
				(arc
					(start 1.4986 0)
					(mid -1.4986 0)
					(end 1.4986 0)
				)
			)
			(stroke
				(width 0)
				(type default)
			)
			(fill no)
			(layer "B.CrtYd")
		)
		(pad "1" smd circle
			(at 0 0 180)
			(size 0.9906 0.9906)
			(layers "B.Cu" "B.Mask" "B.Paste")
			(net "Net_1")
		)
		(zone
			(layer "B.Cu")
			(hatch none 0.5)
			(connect_pads
				(clearance 0)
			)
			(min_thickness 0.25)
			(keepout
				(tracks not_allowed)
				(vias allowed)
				(pads allowed)
				(copperpour not_allowed)
				(footprints allowed)
			)
			(placement
				(enabled no)
				(sheetname "")
			)
			(fill
				(thermal_gap 0.5)
				(thermal_bridge_width 0.5)
				(island_removal_mode 0)
			)
			(polygon
				(pts
					(arc
						(start 100.576888 -16.810228)
						(mid 97.325688 -16.810228)
						(end 100.576888 -16.810228)
					)
				)
			)
		)
	)
	(footprint ""
		(layer "B.Cu")
		(at 87.585804 -516.95858)
		(property "Reference" ""
			(at 0 0 0)
			(layer "B.SilkS")
			(hide yes)
			(effects
				(font
					(size 1.27 1.27)
				)
				(justify mirror)
			)
		)
		(property "Value" ""
			(at 0 0 0)
			(layer "B.Fab")
			(effects
				(font
					(size 1.27 1.27)
				)
				(justify mirror)
			)
		)
		(duplicate_pad_numbers_are_jumpers no)
		(fp_poly
			(pts
				(arc
					(start 1.4986 0)
					(mid -1.4986 0)
					(end 1.4986 0)
				)
			)
			(stroke
				(width 0)
				(type default)
			)
			(fill no)
			(layer "B.CrtYd")
		)
		(pad "1" smd circle
			(at 0 0 180)
			(size 0.9906 0.9906)
			(layers "B.Cu" "B.Mask" "B.Paste")
			(net "Net_2")
		)
		(zone
			(layer "B.Cu")
			(hatch none 0.5)
			(connect_pads
				(clearance 0)
			)
			(min_thickness 0.25)
			(keepout
				(tracks not_allowed)
				(vias allowed)
				(pads allowed)
				(copperpour not_allowed)
				(footprints allowed)
			)
			(placement
				(enabled no)
				(sheetname "")
			)
			(fill
				(thermal_gap 0.5)
				(thermal_bridge_width 0.5)
				(island_removal_mode 0)
			)
			(polygon
				(pts
					(arc
						(start 89.211404 -516.95858)
						(mid 85.960204 -516.95858)
						(end 89.211404 -516.95858)
					)
				)
			)
		)
	)
	(footprint ""
		(layer "B.Cu")
		(at 44.03979 -8.26008 90)
		(property "Reference" "J7"
			(at 6.1214 -5.060442 0)
			(unlocked yes)
			(layer "B.SilkS")
			(effects
				(font
					(size 0.7874 0.5842)
					(thickness 0.1524)
				)
				(justify left mirror)
			)
		)
		(property "Value" ""
			(at 0 0 90)
			(layer "B.Fab")
			(effects
				(font
					(size 1.27 1.27)
				)
				(justify mirror)
			)
		)
		(duplicate_pad_numbers_are_jumpers no)
		(fp_line
			(start 5.275072 -13.910056)
			(end -7.975092 -13.910056)
			(stroke
				(width 0.1524)
				(type default)
			)
			(layer "F.SilkS")
		)
		(fp_line
			(start -7.975092 -13.910056)
			(end -7.975092 62.170056)
			(stroke
				(width 0.1524)
				(type default)
			)
			(layer "F.SilkS")
		)
		(fp_line
			(start 5.275072 62.170056)
			(end 5.275072 -13.910056)
			(stroke
				(width 0.1524)
				(type default)
			)
			(layer "F.SilkS")
		)
		(fp_line
			(start -7.975092 62.170056)
			(end 5.275072 62.170056)
			(stroke
				(width 0.1524)
				(type default)
			)
			(layer "F.SilkS")
		)
		(fp_line
			(start 5.275072 -13.910056)
			(end -7.975092 -13.910056)
			(stroke
				(width 0.1524)
				(type default)
			)
			(layer "B.SilkS")
		)
		(fp_line
			(start -7.975092 -13.910056)
			(end -7.975092 62.170056)
			(stroke
				(width 0.1524)
				(type default)
			)
			(layer "B.SilkS")
		)
		(fp_line
			(start 2.275078 -10.910062)
			(end 2.275078 59.170062)
			(stroke
				(width 0.1524)
				(type default)
			)
			(layer "B.SilkS")
		)
		(fp_line
			(start -4.975098 -10.910062)
			(end 2.275078 -10.910062)
			(stroke
				(width 0.1524)
				(type default)
			)
			(layer "B.SilkS")
		)
		(fp_line
			(start 2.275078 59.170062)
			(end -4.975098 59.170062)
			(stroke
				(width 0.1524)
				(type default)
			)
			(layer "B.SilkS")
		)
		(fp_line
			(start -4.975098 59.170062)
			(end -4.975098 -10.910062)
			(stroke
				(width 0.1524)
				(type default)
			)
			(layer "B.SilkS")
		)
		(fp_line
			(start 5.275072 62.170056)
			(end 5.275072 -13.910056)
			(stroke
				(width 0.1524)
				(type default)
			)
			(layer "B.SilkS")
		)
		(fp_line
			(start -7.975092 62.170056)
			(end 5.275072 62.170056)
			(stroke
				(width 0.1524)
				(type default)
			)
			(layer "B.SilkS")
		)
		(fp_poly
			(pts
				(xy 4.103878 -0.759206) (xy 4.103878 0.764794) (xy 2.579878 0.002794)
			)
			(stroke
				(width 0)
				(type default)
			)
			(fill yes)
			(layer "B.SilkS")
		)
		(fp_poly
			(pts
				(xy 2.275078 -10.910062) (xy 2.275078 59.170062) (xy -4.975098 59.170062) (xy -4.975098 -10.910062)
			)
			(stroke
				(width 0)
				(type default)
			)
			(fill no)
			(layer "B.CrtYd")
		)
		(fp_poly
			(pts
				(xy 1.1938 40.9702) (xy 1.1938 48.6156) (xy -3.9116 48.6156) (xy -3.9116 40.9702) (xy -3.9116 40.9448)
				(xy 1.1938 40.9448)
			)
			(stroke
				(width 0)
				(type default)
			)
			(fill no)
			(layer "F.CrtYd")
		)
		(fp_poly
			(pts
				(xy -3.3274 -0.6604) (xy 0.635 -0.6604) (xy 0.635 38.735) (xy 0.635 38.7604) (xy -3.3274 38.7604)
				(xy -3.3528 38.7604) (xy -3.3528 -0.6604)
			)
			(stroke
				(width 0)
				(type default)
			)
			(fill no)
			(layer "F.CrtYd")
		)
		(fp_poly
			(pts
				(arc
					(start -1.35001 -1.01219)
					(mid -1.35001 -4.06781)
					(end -1.35001 -1.01219)
				)
			)
			(stroke
				(width 0)
				(type default)
			)
			(fill no)
			(layer "F.CrtYd")
		)
		(fp_poly
			(pts
				(arc
					(start 0 52.33162)
					(mid 0 49.26838)
					(end 0 52.33162)
				)
			)
			(stroke
				(width 0)
				(type default)
			)
			(fill no)
			(layer "F.CrtYd")
		)
		(fp_line
			(start 2.275078 -10.910062)
			(end 2.275078 59.170062)
			(stroke
				(width 0.1)
				(type default)
			)
			(layer "B.Fab")
		)
		(fp_line
			(start -4.975098 -10.910062)
			(end 2.275078 -10.910062)
			(stroke
				(width 0.1)
				(type default)
			)
			(layer "B.Fab")
		)
		(fp_line
			(start 2.275078 59.170062)
			(end -4.975098 59.170062)
			(stroke
				(width 0.1)
				(type default)
			)
			(layer "B.Fab")
		)
		(fp_line
			(start -4.975098 59.170062)
			(end -4.975098 -10.910062)
			(stroke
				(width 0.1)
				(type default)
			)
			(layer "B.Fab")
		)
		(fp_poly
			(pts
				(xy 4.103878 -0.759206) (xy 4.103878 0.764794) (xy 2.579878 0.002794)
			)
			(stroke
				(width 0)
				(type default)
			)
			(fill yes)
			(layer "B.Fab")
		)
		(fp_line
			(start 5.275072 -13.910056)
			(end -7.975092 -13.910056)
			(stroke
				(width 0.1)
				(type default)
			)
			(layer "F.Fab")
		)
		(fp_line
			(start -7.975092 -13.910056)
			(end -7.975092 62.170056)
			(stroke
				(width 0.1)
				(type default)
			)
			(layer "F.Fab")
		)
		(fp_line
			(start 5.275072 62.170056)
			(end 5.275072 -13.910056)
			(stroke
				(width 0.1)
				(type default)
			)
			(layer "F.Fab")
		)
		(fp_line
			(start -7.975092 62.170056)
			(end 5.275072 62.170056)
			(stroke
				(width 0.1)
				(type default)
			)
			(layer "F.Fab")
		)
		(fp_text user "P32"
			(at -4.37134 0.049784 0)
			(unlocked yes)
			(layer "F.SilkS")
			(effects
				(font
					(size 0.7874 0.5842)
					(thickness 0.1524)
				)
			)
		)
		(fp_text user "P1"
			(at 6.256782 0.402844 0)
			(unlocked yes)
			(layer "F.SilkS")
			(effects
				(font
					(size 0.7874 0.5842)
					(thickness 0.1524)
				)
			)
		)
		(fp_text user "PRESS-FIT"
			(at 6.390386 8.707882 0)
			(unlocked yes)
			(layer "F.SilkS")
			(effects
				(font
					(size 0.7874 0.5842)
					(thickness 0.1524)
				)
				(justify left)
			)
		)
		(fp_text user "P17"
			(at -4.280408 37.907468 0)
			(unlocked yes)
			(layer "F.SilkS")
			(effects
				(font
					(size 0.7874 0.5842)
					(thickness 0.1524)
				)
			)
		)
		(fp_text user "P16"
			(at 1.418082 37.950648 0)
			(unlocked yes)
			(layer "F.SilkS")
			(effects
				(font
					(size 0.7874 0.5842)
					(thickness 0.1524)
				)
			)
		)
		(fp_text user "S12"
			(at -4.454652 41.239948 0)
			(unlocked yes)
			(layer "F.SilkS")
			(effects
				(font
					(size 0.7874 0.5842)
					(thickness 0.1524)
				)
			)
		)
		(fp_text user "S1"
			(at 2.060448 41.620948 0)
			(unlocked yes)
			(layer "F.SilkS")
			(effects
				(font
					(size 0.7874 0.5842)
					(thickness 0.1524)
				)
			)
		)
		(fp_text user "S6"
			(at 1.65481 47.888652 0)
			(unlocked yes)
			(layer "F.SilkS")
			(effects
				(font
					(size 0.7874 0.5842)
					(thickness 0.1524)
				)
			)
		)
		(fp_text user "S7"
			(at -4.79933 47.88916 0)
			(unlocked yes)
			(layer "F.SilkS")
			(effects
				(font
					(size 0.7874 0.5842)
					(thickness 0.1524)
				)
			)
		)
		(fp_text user "P1"
			(at 2.955798 -1.463548 0)
			(unlocked yes)
			(layer "B.SilkS")
			(effects
				(font
					(size 0.7874 0.5842)
					(thickness 0.1524)
				)
				(justify mirror)
			)
		)
		(fp_text user "P32"
			(at -5.896356 -0.299212 0)
			(unlocked yes)
			(layer "B.SilkS")
			(effects
				(font
					(size 0.7874 0.5842)
					(thickness 0.1524)
				)
				(justify mirror)
			)
		)
		(fp_text user "PRESS-FIT"
			(at -6.81482 32.505396 0)
			(unlocked yes)
			(layer "B.SilkS")
			(effects
				(font
					(size 0.7874 0.5842)
					(thickness 0.1524)
				)
				(justify left mirror)
			)
		)
		(fp_text user "P17"
			(at -5.854192 38.026086 0)
			(unlocked yes)
			(layer "B.SilkS")
			(effects
				(font
					(size 0.7874 0.5842)
					(thickness 0.1524)
				)
				(justify mirror)
			)
		)
		(fp_text user "P16"
			(at 2.939034 38.436296 0)
			(unlocked yes)
			(layer "B.SilkS")
			(effects
				(font
					(size 0.7874 0.5842)
					(thickness 0.1524)
				)
				(justify mirror)
			)
		)
		(fp_text user "S1"
			(at 2.933954 41.936416 0)
			(unlocked yes)
			(layer "B.SilkS")
			(effects
				(font
					(size 0.7874 0.5842)
					(thickness 0.1524)
				)
				(justify mirror)
			)
		)
		(fp_text user "S12"
			(at -5.84962 42.442892 0)
			(unlocked yes)
			(layer "B.SilkS")
			(effects
				(font
					(size 0.7874 0.5842)
					(thickness 0.1524)
				)
				(justify mirror)
			)
		)
		(fp_text user "S6"
			(at 2.930398 47.701708 0)
			(unlocked yes)
			(layer "B.SilkS")
			(effects
				(font
					(size 0.7874 0.5842)
					(thickness 0.1524)
				)
				(justify mirror)
			)
		)
		(fp_text user "S7"
			(at -5.930392 48.382682 0)
			(unlocked yes)
			(layer "B.SilkS")
			(effects
				(font
					(size 0.7874 0.5842)
					(thickness 0.1524)
				)
				(justify mirror)
			)
		)
		(fp_text user "P1"
			(at 3.108452 -1.27 180)
			(unlocked yes)
			(layer "B.Fab")
			(effects
				(font
					(size 0.7874 0.5842)
					(thickness 0.000001)
				)
				(justify mirror)
			)
		)
		(fp_text user "P32"
			(at -5.781548 -0.0508 180)
			(unlocked yes)
			(layer "B.Fab")
			(effects
				(font
					(size 0.7874 0.5842)
					(thickness 0.000001)
				)
				(justify mirror)
			)
		)
		(fp_text user "PRESS-FIT"
			(at -6.82371 29.8831 0)
			(unlocked yes)
			(layer "B.Fab")
			(effects
				(font
					(size 1.6002 1.1938)
					(thickness 0.000001)
				)
				(justify left mirror)
			)
		)
		(fp_text user "P17"
			(at -5.72135 38.0746 180)
			(unlocked yes)
			(layer "B.Fab")
			(effects
				(font
					(size 0.7874 0.5842)
					(thickness 0.000001)
				)
				(justify mirror)
			)
		)
		(fp_text user "P16"
			(at 3.159252 38.3794 180)
			(unlocked yes)
			(layer "B.Fab")
			(effects
				(font
					(size 0.7874 0.5842)
					(thickness 0.000001)
				)
				(justify mirror)
			)
		)
		(fp_text user "S12"
			(at -5.79374 41.42232 180)
			(unlocked yes)
			(layer "B.Fab")
			(effects
				(font
					(size 0.7874 0.5842)
					(thickness 0.000001)
				)
				(justify mirror)
			)
		)
		(fp_text user "S1"
			(at 3.09626 41.656 180)
			(unlocked yes)
			(layer "B.Fab")
			(effects
				(font
					(size 0.7874 0.5842)
					(thickness 0.000001)
				)
				(justify mirror)
			)
		)
		(fp_text user "S6"
			(at 3.133852 48.0822 180)
			(unlocked yes)
			(layer "B.Fab")
			(effects
				(font
					(size 0.7874 0.5842)
					(thickness 0.000001)
				)
				(justify mirror)
			)
		)
		(fp_text user "S7"
			(at -5.781548 48.0822 180)
			(unlocked yes)
			(layer "B.Fab")
			(effects
				(font
					(size 0.7874 0.5842)
					(thickness 0.000001)
				)
				(justify mirror)
			)
		)
		(fp_text user "P32"
			(at -4.071112 -0.0762 180)
			(unlocked yes)
			(layer "F.Fab")
			(effects
				(font
					(size 0.7874 0.5842)
					(thickness 0.000001)
				)
			)
		)
		(fp_text user "P1"
			(at 1.516888 0 180)
			(unlocked yes)
			(layer "F.Fab")
			(effects
				(font
					(size 0.7874 0.5842)
					(thickness 0.000001)
				)
			)
		)
		(fp_text user "PRESS-FIT"
			(at -6.762496 16.251428 0)
			(unlocked yes)
			(layer "F.Fab")
			(effects
				(font
					(size 1.6002 1.1938)
					(thickness 0.000001)
				)
				(justify left)
			)
		)
		(fp_text user "P17"
			(at -4.366768 38.227 180)
			(unlocked yes)
			(layer "F.Fab")
			(effects
				(font
					(size 0.7874 0.5842)
					(thickness 0.000001)
				)
			)
		)
		(fp_text user "P16"
			(at 2.228088 38.354 180)
			(unlocked yes)
			(layer "F.Fab")
			(effects
				(font
					(size 0.7874 0.5842)
					(thickness 0.000001)
				)
			)
		)
		(fp_text user "S12"
			(at -4.362958 41.09212 180)
			(unlocked yes)
			(layer "F.Fab")
			(effects
				(font
					(size 0.7874 0.5842)
					(thickness 0.000001)
				)
			)
		)
		(fp_text user "S1"
			(at 2.164842 41.6306 180)
			(unlocked yes)
			(layer "F.Fab")
			(effects
				(font
					(size 0.7874 0.5842)
					(thickness 0.000001)
				)
			)
		)
		(fp_text user "S6"
			(at 1.923288 48.133 180)
			(unlocked yes)
			(layer "F.Fab")
			(effects
				(font
					(size 0.7874 0.5842)
					(thickness 0.000001)
				)
			)
		)
		(fp_text user "S7"
			(at -4.426712 48.2346 180)
			(unlocked yes)
			(layer "F.Fab")
			(effects
				(font
					(size 0.7874 0.5842)
					(thickness 0.000001)
				)
			)
		)
		(pad "" np_thru_hole circle
			(at -1.35001 -2.54)
			(size 2.5146 2.5146)
			(drill 2.5146)
			(layers "*.Cu" "*.Mask")
			(clearance 0.381)
			(thermal_gap 0.381)
		)
		(pad "" np_thru_hole circle
			(at 0 50.8)
			(size 2.5146 2.5146)
			(drill 2.5146)
			(layers "*.Cu" "*.Mask")
			(clearance 0.381)
			(thermal_gap 0.381)
		)
		(pad "P1" thru_hole rect
			(at 0 0)
			(size 1.1684 1.1684)
			(drill 0.762)
			(layers "*.Cu" "*.Mask")
			(remove_unused_layers no)
			(net "GND")
			(clearance 0.0508)
			(padstack
				(mode front_inner_back)
				(layer "Inner"
					(shape circle)
					(size 1.1684 1.1684)
					(clearance 0.0508)
				)
				(layer "B.Cu"
					(shape rect)
					(size 1.1684 1.1684)
					(thermal_gap 0.0508)
					(clearance 0.0508)
				)
			)
		)
		(pad "P2" thru_hole circle
			(at 0 2.54)
			(size 1.1684 1.1684)
			(drill 0.762)
			(layers "*.Cu" "*.Mask")
			(remove_unused_layers no)
			(net "GND")
			(clearance 0.0508)
			(thermal_gap 0.0508)
		)
		(pad "P3" thru_hole circle
			(at 0 5.08)
			(size 1.1684 1.1684)
			(drill 0.762)
			(layers "*.Cu" "*.Mask")
			(remove_unused_layers no)
			(net "GND")
			(clearance 0.0508)
			(thermal_gap 0.0508)
		)
		(pad "P4" thru_hole circle
			(at 0 7.62)
			(size 1.1684 1.1684)
			(drill 0.762)
			(layers "*.Cu" "*.Mask")
			(remove_unused_layers no)
			(net "GND")
			(clearance 0.0508)
			(thermal_gap 0.0508)
		)
		(pad "P5" thru_hole circle
			(at 0 10.16)
			(size 1.1684 1.1684)
			(drill 0.762)
			(layers "*.Cu" "*.Mask")
			(remove_unused_layers no)
			(net "GND")
			(clearance 0.0508)
			(thermal_gap 0.0508)
		)
		(pad "P6" thru_hole circle
			(at 0 12.7)
			(size 1.1684 1.1684)
			(drill 0.762)
			(layers "*.Cu" "*.Mask")
			(remove_unused_layers no)
			(net "GND")
			(clearance 0.0508)
			(thermal_gap 0.0508)
		)
		(pad "P7" thru_hole circle
			(at 0 15.24)
			(size 1.1684 1.1684)
			(drill 0.762)
			(layers "*.Cu" "*.Mask")
			(remove_unused_layers no)
			(net "GND")
			(clearance 0.0508)
			(thermal_gap 0.0508)
		)
		(pad "P8" thru_hole circle
			(at 0 17.78)
			(size 1.1684 1.1684)
			(drill 0.762)
			(layers "*.Cu" "*.Mask")
			(remove_unused_layers no)
			(net "GND")
			(clearance 0.0508)
			(thermal_gap 0.0508)
		)
		(pad "P9" thru_hole circle
			(at 0 20.32)
			(size 1.1684 1.1684)
			(drill 0.762)
			(layers "*.Cu" "*.Mask")
			(remove_unused_layers no)
			(net "P12V")
			(clearance 0.0508)
			(thermal_gap 0.0508)
		)
		(pad "P10" thru_hole circle
			(at 0 22.86)
			(size 1.1684 1.1684)
			(drill 0.762)
			(layers "*.Cu" "*.Mask")
			(remove_unused_layers no)
			(net "P12V")
			(clearance 0.0508)
			(thermal_gap 0.0508)
		)
		(pad "P11" thru_hole circle
			(at 0 25.4)
			(size 1.1684 1.1684)
			(drill 0.762)
			(layers "*.Cu" "*.Mask")
			(remove_unused_layers no)
			(net "P12V")
			(clearance 0.0508)
			(thermal_gap 0.0508)
		)
		(pad "P12" thru_hole circle
			(at 0 27.94)
			(size 1.1684 1.1684)
			(drill 0.762)
			(layers "*.Cu" "*.Mask")
			(remove_unused_layers no)
			(net "P12V")
			(clearance 0.0508)
			(thermal_gap 0.0508)
		)
		(pad "P13" thru_hole circle
			(at 0 30.48)
			(size 1.1684 1.1684)
			(drill 0.762)
			(layers "*.Cu" "*.Mask")
			(remove_unused_layers no)
			(net "P12V")
			(clearance 0.0508)
			(thermal_gap 0.0508)
		)
		(pad "P14" thru_hole circle
			(at 0 33.02)
			(size 1.1684 1.1684)
			(drill 0.762)
			(layers "*.Cu" "*.Mask")
			(remove_unused_layers no)
			(net "P12V")
			(clearance 0.0508)
			(thermal_gap 0.0508)
		)
		(pad "P15" thru_hole circle
			(at 0 35.56)
			(size 1.1684 1.1684)
			(drill 0.762)
			(layers "*.Cu" "*.Mask")
			(remove_unused_layers no)
			(net "P12V")
			(clearance 0.0508)
			(thermal_gap 0.0508)
		)
		(pad "P16" thru_hole circle
			(at 0 38.1)
			(size 1.1684 1.1684)
			(drill 0.762)
			(layers "*.Cu" "*.Mask")
			(remove_unused_layers no)
			(net "P12V")
			(clearance 0.0508)
			(thermal_gap 0.0508)
		)
		(pad "P17" thru_hole circle
			(at -2.70002 38.1)
			(size 1.1684 1.1684)
			(drill 0.762)
			(layers "*.Cu" "*.Mask")
			(remove_unused_layers no)
			(net "P12V")
			(clearance 0.0508)
			(thermal_gap 0.0508)
		)
		(pad "P18" thru_hole circle
			(at -2.70002 35.56)
			(size 1.1684 1.1684)
			(drill 0.762)
			(layers "*.Cu" "*.Mask")
			(remove_unused_layers no)
			(net "P12V")
			(clearance 0.0508)
			(thermal_gap 0.0508)
		)
		(pad "P19" thru_hole circle
			(at -2.70002 33.02)
			(size 1.1684 1.1684)
			(drill 0.762)
			(layers "*.Cu" "*.Mask")
			(remove_unused_layers no)
			(net "P12V")
			(clearance 0.0508)
			(thermal_gap 0.0508)
		)
		(pad "P20" thru_hole circle
			(at -2.70002 30.48)
			(size 1.1684 1.1684)
			(drill 0.762)
			(layers "*.Cu" "*.Mask")
			(remove_unused_layers no)
			(net "P12V")
			(clearance 0.0508)
			(thermal_gap 0.0508)
		)
		(pad "P21" thru_hole circle
			(at -2.70002 27.94)
			(size 1.1684 1.1684)
			(drill 0.762)
			(layers "*.Cu" "*.Mask")
			(remove_unused_layers no)
			(net "P12V")
			(clearance 0.0508)
			(thermal_gap 0.0508)
		)
		(pad "P22" thru_hole circle
			(at -2.70002 25.4)
			(size 1.1684 1.1684)
			(drill 0.762)
			(layers "*.Cu" "*.Mask")
			(remove_unused_layers no)
			(net "P12V")
			(clearance 0.0508)
			(thermal_gap 0.0508)
		)
		(pad "P23" thru_hole circle
			(at -2.70002 22.86)
			(size 1.1684 1.1684)
			(drill 0.762)
			(layers "*.Cu" "*.Mask")
			(remove_unused_layers no)
			(net "P12V")
			(clearance 0.0508)
			(thermal_gap 0.0508)
		)
		(pad "P24" thru_hole circle
			(at -2.70002 20.32)
			(size 1.1684 1.1684)
			(drill 0.762)
			(layers "*.Cu" "*.Mask")
			(remove_unused_layers no)
			(net "P12V")
			(clearance 0.0508)
			(thermal_gap 0.0508)
		)
		(pad "P25" thru_hole circle
			(at -2.70002 17.78)
			(size 1.1684 1.1684)
			(drill 0.762)
			(layers "*.Cu" "*.Mask")
			(remove_unused_layers no)
			(net "GND")
			(clearance 0.0508)
			(thermal_gap 0.0508)
		)
		(pad "P26" thru_hole circle
			(at -2.70002 15.24)
			(size 1.1684 1.1684)
			(drill 0.762)
			(layers "*.Cu" "*.Mask")
			(remove_unused_layers no)
			(net "GND")
			(clearance 0.0508)
			(thermal_gap 0.0508)
		)
		(pad "P27" thru_hole circle
			(at -2.70002 12.7)
			(size 1.1684 1.1684)
			(drill 0.762)
			(layers "*.Cu" "*.Mask")
			(remove_unused_layers no)
			(net "GND")
			(clearance 0.0508)
			(thermal_gap 0.0508)
		)
		(pad "P28" thru_hole circle
			(at -2.70002 10.16)
			(size 1.1684 1.1684)
			(drill 0.762)
			(layers "*.Cu" "*.Mask")
			(remove_unused_layers no)
			(net "GND")
			(clearance 0.0508)
			(thermal_gap 0.0508)
		)
		(pad "P29" thru_hole circle
			(at -2.70002 7.62)
			(size 1.1684 1.1684)
			(drill 0.762)
			(layers "*.Cu" "*.Mask")
			(remove_unused_layers no)
			(net "GND")
			(clearance 0.0508)
			(thermal_gap 0.0508)
		)
		(pad "P30" thru_hole circle
			(at -2.70002 5.08)
			(size 1.1684 1.1684)
			(drill 0.762)
			(layers "*.Cu" "*.Mask")
			(remove_unused_layers no)
			(net "GND")
			(clearance 0.0508)
			(thermal_gap 0.0508)
		)
		(pad "P31" thru_hole circle
			(at -2.70002 2.54)
			(size 1.1684 1.1684)
			(drill 0.762)
			(layers "*.Cu" "*.Mask")
			(remove_unused_layers no)
			(net "GND")
			(clearance 0.0508)
			(thermal_gap 0.0508)
		)
		(pad "P32" thru_hole circle
			(at -2.70002 0)
			(size 1.1684 1.1684)
			(drill 0.762)
			(layers "*.Cu" "*.Mask")
			(remove_unused_layers no)
			(net "GND")
			(clearance 0.0508)
			(thermal_gap 0.0508)
		)
		(pad "S1" thru_hole circle
			(at 0.55499 41.60012)
			(size 1.1684 1.1684)
			(drill 0.762)
			(layers "*.Cu" "*.Mask")
			(remove_unused_layers no)
			(net "T1_BLAD1_TXD")
			(clearance 0.0508)
			(thermal_gap 0.0508)
		)
		(pad "S2" thru_hole circle
			(at -0.71501 42.87012)
			(size 1.1684 1.1684)
			(drill 0.762)
			(layers "*.Cu" "*.Mask")
			(remove_unused_layers no)
			(net "T1_BLAD1_RXD")
			(clearance 0.0508)
			(thermal_gap 0.0508)
		)
		(pad "S3" thru_hole circle
			(at 0.55499 44.14012)
			(size 1.1684 1.1684)
			(drill 0.762)
			(layers "*.Cu" "*.Mask")
			(remove_unused_layers no)
			(net "T1_BLAD1_EN")
			(clearance 0.0508)
			(thermal_gap 0.0508)
		)
		(pad "S4" thru_hole circle
			(at -0.71501 45.41012)
			(size 1.1684 1.1684)
			(drill 0.762)
			(layers "*.Cu" "*.Mask")
			(remove_unused_layers no)
			(net "T1_BLAD2_EN")
			(clearance 0.0508)
			(thermal_gap 0.0508)
		)
		(pad "S5" thru_hole circle
			(at 0.55499 46.68012)
			(size 1.1684 1.1684)
			(drill 0.762)
			(layers "*.Cu" "*.Mask")
			(remove_unused_layers no)
			(net "T1_BLAD2_TXD")
			(clearance 0.0508)
			(thermal_gap 0.0508)
		)
		(pad "S6" thru_hole circle
			(at -0.71501 47.95012)
			(size 1.1684 1.1684)
			(drill 0.762)
			(layers "*.Cu" "*.Mask")
			(remove_unused_layers no)
			(net "T1_BLAD2_RXD")
			(clearance 0.0508)
			(thermal_gap 0.0508)
		)
		(pad "S7" thru_hole circle
			(at -3.25501 47.95012)
			(size 1.1684 1.1684)
			(drill 0.762)
			(layers "*.Cu" "*.Mask")
			(remove_unused_layers no)
			(net "T1_BLAD4_RXD")
			(clearance 0.0508)
			(thermal_gap 0.0508)
		)
		(pad "S8" thru_hole circle
			(at -1.98501 46.68012)
			(size 1.1684 1.1684)
			(drill 0.762)
			(layers "*.Cu" "*.Mask")
			(remove_unused_layers no)
			(net "T1_BLAD4_TXD")
			(clearance 0.0508)
			(thermal_gap 0.0508)
		)
		(pad "S9" thru_hole circle
			(at -3.25501 45.41012)
			(size 1.1684 1.1684)
			(drill 0.762)
			(layers "*.Cu" "*.Mask")
			(remove_unused_layers no)
			(net "T1_BLAD4_EN")
			(clearance 0.0508)
			(thermal_gap 0.0508)
		)
		(pad "S10" thru_hole circle
			(at -1.98501 44.14012)
			(size 1.1684 1.1684)
			(drill 0.762)
			(layers "*.Cu" "*.Mask")
			(remove_unused_layers no)
			(net "T1_BLAD3_EN")
			(clearance 0.0508)
			(thermal_gap 0.0508)
		)
		(pad "S11" thru_hole circle
			(at -3.25501 42.87012)
			(size 1.1684 1.1684)
			(drill 0.762)
			(layers "*.Cu" "*.Mask")
			(remove_unused_layers no)
			(net "T1_BLAD3_RXD")
			(clearance 0.0508)
			(thermal_gap 0.0508)
		)
		(pad "S12" thru_hole circle
			(at -1.98501 41.60012)
			(size 1.1684 1.1684)
			(drill 0.762)
			(layers "*.Cu" "*.Mask")
			(remove_unused_layers no)
			(net "T1_BLAD3_TXD")
			(clearance 0.0508)
			(thermal_gap 0.0508)
		)
		(zone
			(layer "F.Cu")
			(hatch none 0.5)
			(connect_pads
				(clearance 0)
			)
			(min_thickness 0.25)
			(keepout
				(tracks allowed)
				(vias not_allowed)
				(pads allowed)
				(copperpour not_allowed)
				(footprints allowed)
			)
			(placement
				(enabled no)
				(sheetname "")
			)
			(fill
				(thermal_gap 0.5)
				(thermal_bridge_width 0.5)
				(island_removal_mode 0)
			)
			(polygon
				(pts
					(xy 85.00999 -9.45388) (xy 92.65539 -9.45388) (xy 92.65539 -4.34848) (xy 85.00999 -4.34848) (xy 84.98459 -4.34848)
					(xy 84.98459 -9.45388)
				)
			)
		)
		(zone
			(layer "F.Cu")
			(hatch none 0.5)
			(connect_pads
				(clearance 0)
			)
			(min_thickness 0.25)
			(keepout
				(tracks allowed)
				(vias not_allowed)
				(pads allowed)
				(copperpour not_allowed)
				(footprints allowed)
			)
			(placement
				(enabled no)
				(sheetname "")
			)
			(fill
				(thermal_gap 0.5)
				(thermal_bridge_width 0.5)
				(island_removal_mode 0)
			)
			(polygon
				(pts
					(xy 43.37939 -4.93268) (xy 43.37939 -8.89508) (xy 82.77479 -8.89508) (xy 82.80019 -8.89508) (xy 82.80019 -4.93268)
					(xy 82.80019 -4.90728) (xy 43.37939 -4.90728)
				)
			)
		)
		(zone
			(layers "F.Cu" "B.Cu" "In1.Cu" "In2.Cu" "In3.Cu" "In4.Cu" "In5.Cu" "In6.Cu")
			(hatch none 0.5)
			(connect_pads
				(clearance 0)
			)
			(min_thickness 0.25)
			(keepout
				(tracks not_allowed)
				(vias allowed)
				(pads allowed)
				(copperpour not_allowed)
				(footprints allowed)
			)
			(placement
				(enabled no)
				(sheetname "")
			)
			(fill
				(thermal_gap 0.5)
				(thermal_bridge_width 0.5)
				(island_removal_mode 0)
			)
			(polygon
				(pts
					(arc
						(start 43.18 -6.91007)
						(mid 39.81958 -6.91007)
						(end 43.18 -6.91007)
					)
				)
			)
		)
		(zone
			(layers "F.Cu" "B.Cu" "In1.Cu" "In2.Cu" "In3.Cu" "In4.Cu" "In5.Cu" "In6.Cu")
			(hatch none 0.5)
			(connect_pads
				(clearance 0)
			)
			(min_thickness 0.25)
			(keepout
				(tracks not_allowed)
				(vias allowed)
				(pads allowed)
				(copperpour not_allowed)
				(footprints allowed)
			)
			(placement
				(enabled no)
				(sheetname "")
			)
			(fill
				(thermal_gap 0.5)
				(thermal_bridge_width 0.5)
				(island_removal_mode 0)
			)
			(polygon
				(pts
					(arc
						(start 96.52381 -8.26008)
						(mid 93.15577 -8.26008)
						(end 96.52381 -8.26008)
					)
				)
			)
		)
	)
	(footprint ""
		(layer "B.Cu")
		(at 14.010132 -224.098358)
		(property "Reference" ""
			(at 0 0 0)
			(layer "B.SilkS")
			(hide yes)
			(effects
				(font
					(size 1.27 1.27)
				)
				(justify mirror)
			)
		)
		(property "Value" ""
			(at 0 0 0)
			(layer "B.Fab")
			(effects
				(font
					(size 1.27 1.27)
				)
				(justify mirror)
			)
		)
		(duplicate_pad_numbers_are_jumpers no)
		(fp_poly
			(pts
				(arc
					(start 1.4986 0)
					(mid -1.4986 0)
					(end 1.4986 0)
				)
			)
			(stroke
				(width 0)
				(type default)
			)
			(fill no)
			(layer "B.CrtYd")
		)
		(pad "1" smd circle
			(at 0 0 180)
			(size 0.9906 0.9906)
			(layers "B.Cu" "B.Mask" "B.Paste")
			(net "Net_3")
		)
		(zone
			(layer "B.Cu")
			(hatch none 0.5)
			(connect_pads
				(clearance 0)
			)
			(min_thickness 0.25)
			(keepout
				(tracks not_allowed)
				(vias allowed)
				(pads allowed)
				(copperpour not_allowed)
				(footprints allowed)
			)
			(placement
				(enabled no)
				(sheetname "")
			)
			(fill
				(thermal_gap 0.5)
				(thermal_bridge_width 0.5)
				(island_removal_mode 0)
			)
			(polygon
				(pts
					(arc
						(start 15.635732 -224.098358)
						(mid 12.384532 -224.098358)
						(end 15.635732 -224.098358)
					)
				)
			)
		)
	)
	(footprint ""
		(layer "B.Cu")
		(at 44.03979 -497.21008 90)
		(property "Reference" "J18"
			(at 6.695948 -2.740406 0)
			(unlocked yes)
			(layer "B.SilkS")
			(effects
				(font
					(size 0.7874 0.5842)
					(thickness 0.1524)
				)
				(justify left mirror)
			)
		)
		(property "Value" ""
			(at 0 0 90)
			(layer "B.Fab")
			(effects
				(font
					(size 1.27 1.27)
				)
				(justify mirror)
			)
		)
		(duplicate_pad_numbers_are_jumpers no)
		(fp_line
			(start 5.275072 -13.910056)
			(end -7.975092 -13.910056)
			(stroke
				(width 0.1524)
				(type default)
			)
			(layer "F.SilkS")
		)
		(fp_line
			(start -7.975092 -13.910056)
			(end -7.975092 62.170056)
			(stroke
				(width 0.1524)
				(type default)
			)
			(layer "F.SilkS")
		)
		(fp_line
			(start 5.275072 62.170056)
			(end 5.275072 -13.910056)
			(stroke
				(width 0.1524)
				(type default)
			)
			(layer "F.SilkS")
		)
		(fp_line
			(start -7.975092 62.170056)
			(end 5.275072 62.170056)
			(stroke
				(width 0.1524)
				(type default)
			)
			(layer "F.SilkS")
		)
		(fp_line
			(start 4.066286 -13.910056)
			(end -7.975092 -13.910056)
			(stroke
				(width 0.1524)
				(type default)
			)
			(layer "B.SilkS")
		)
		(fp_line
			(start -7.975092 -13.910056)
			(end -7.975092 62.170056)
			(stroke
				(width 0.1524)
				(type default)
			)
			(layer "B.SilkS")
		)
		(fp_line
			(start 2.275078 -10.910062)
			(end 2.275078 59.170062)
			(stroke
				(width 0.1524)
				(type default)
			)
			(layer "B.SilkS")
		)
		(fp_line
			(start -4.975098 -10.910062)
			(end 2.275078 -10.910062)
			(stroke
				(width 0.1524)
				(type default)
			)
			(layer "B.SilkS")
		)
		(fp_line
			(start 2.275078 59.170062)
			(end -4.975098 59.170062)
			(stroke
				(width 0.1524)
				(type default)
			)
			(layer "B.SilkS")
		)
		(fp_line
			(start -4.975098 59.170062)
			(end -4.975098 -10.910062)
			(stroke
				(width 0.1524)
				(type default)
			)
			(layer "B.SilkS")
		)
		(fp_line
			(start 5.275072 62.170056)
			(end 5.275072 -12.454128)
			(stroke
				(width 0.1524)
				(type default)
			)
			(layer "B.SilkS")
		)
		(fp_line
			(start -7.975092 62.170056)
			(end 5.275072 62.170056)
			(stroke
				(width 0.1524)
				(type default)
			)
			(layer "B.SilkS")
		)
		(fp_poly
			(pts
				(xy 4.103878 -0.759206) (xy 4.103878 0.764794) (xy 2.579878 0.002794)
			)
			(stroke
				(width 0)
				(type default)
			)
			(fill yes)
			(layer "B.SilkS")
		)
		(fp_poly
			(pts
				(xy 2.275078 -10.910062) (xy 2.275078 59.170062) (xy -4.975098 59.170062) (xy -4.975098 -10.910062)
			)
			(stroke
				(width 0)
				(type default)
			)
			(fill no)
			(layer "B.CrtYd")
		)
		(fp_poly
			(pts
				(xy 1.1938 40.9702) (xy 1.1938 48.6156) (xy -3.9116 48.6156) (xy -3.9116 40.9702) (xy -3.9116 40.9448)
				(xy 1.1938 40.9448)
			)
			(stroke
				(width 0)
				(type default)
			)
			(fill no)
			(layer "F.CrtYd")
		)
		(fp_poly
			(pts
				(xy -3.3274 -0.6604) (xy 0.635 -0.6604) (xy 0.635 38.735) (xy 0.635 38.7604) (xy -3.3274 38.7604)
				(xy -3.3528 38.7604) (xy -3.3528 -0.6604)
			)
			(stroke
				(width 0)
				(type default)
			)
			(fill no)
			(layer "F.CrtYd")
		)
		(fp_poly
			(pts
				(arc
					(start -1.35001 -1.01219)
					(mid -1.35001 -4.06781)
					(end -1.35001 -1.01219)
				)
			)
			(stroke
				(width 0)
				(type default)
			)
			(fill no)
			(layer "F.CrtYd")
		)
		(fp_poly
			(pts
				(arc
					(start 0 52.33162)
					(mid 0 49.26838)
					(end 0 52.33162)
				)
			)
			(stroke
				(width 0)
				(type default)
			)
			(fill no)
			(layer "F.CrtYd")
		)
		(fp_line
			(start 2.275078 -10.910062)
			(end 2.275078 59.170062)
			(stroke
				(width 0.1)
				(type default)
			)
			(layer "B.Fab")
		)
		(fp_line
			(start -4.975098 -10.910062)
			(end 2.275078 -10.910062)
			(stroke
				(width 0.1)
				(type default)
			)
			(layer "B.Fab")
		)
		(fp_line
			(start 2.275078 59.170062)
			(end -4.975098 59.170062)
			(stroke
				(width 0.1)
				(type default)
			)
			(layer "B.Fab")
		)
		(fp_line
			(start -4.975098 59.170062)
			(end -4.975098 -10.910062)
			(stroke
				(width 0.1)
				(type default)
			)
			(layer "B.Fab")
		)
		(fp_poly
			(pts
				(xy 4.103878 -0.759206) (xy 4.103878 0.764794) (xy 2.579878 0.002794)
			)
			(stroke
				(width 0)
				(type default)
			)
			(fill yes)
			(layer "B.Fab")
		)
		(fp_line
			(start 5.275072 -13.910056)
			(end -7.975092 -13.910056)
			(stroke
				(width 0.1)
				(type default)
			)
			(layer "F.Fab")
		)
		(fp_line
			(start -7.975092 -13.910056)
			(end -7.975092 62.170056)
			(stroke
				(width 0.1)
				(type default)
			)
			(layer "F.Fab")
		)
		(fp_line
			(start 5.275072 62.170056)
			(end 5.275072 -13.910056)
			(stroke
				(width 0.1)
				(type default)
			)
			(layer "F.Fab")
		)
		(fp_line
			(start -7.975092 62.170056)
			(end 5.275072 62.170056)
			(stroke
				(width 0.1)
				(type default)
			)
			(layer "F.Fab")
		)
		(fp_text user "P32"
			(at -8.943086 -0.332486 0)
			(unlocked yes)
			(layer "F.SilkS")
			(effects
				(font
					(size 0.7874 0.5842)
					(thickness 0.1524)
				)
			)
		)
		(fp_text user "P1"
			(at 6.095492 -0.065278 0)
			(unlocked yes)
			(layer "F.SilkS")
			(effects
				(font
					(size 0.7874 0.5842)
					(thickness 0.1524)
				)
			)
		)
		(fp_text user "PRESS-FIT"
			(at -9.344152 3.343402 0)
			(unlocked yes)
			(layer "F.SilkS")
			(effects
				(font
					(size 0.7874 0.5842)
					(thickness 0.1524)
				)
				(justify left)
			)
		)
		(fp_text user "P17"
			(at -9.676638 38.171628 0)
			(unlocked yes)
			(layer "F.SilkS")
			(effects
				(font
					(size 0.7874 0.5842)
					(thickness 0.1524)
				)
			)
		)
		(fp_text user "P16"
			(at 6.32968 41.040558 0)
			(unlocked yes)
			(layer "F.SilkS")
			(effects
				(font
					(size 0.7874 0.5842)
					(thickness 0.1524)
				)
			)
		)
		(fp_text user "S12"
			(at -9.711436 42.05478 0)
			(unlocked yes)
			(layer "F.SilkS")
			(effects
				(font
					(size 0.7874 0.5842)
					(thickness 0.1524)
				)
			)
		)
		(fp_text user "S1"
			(at 6.32968 43.179492 0)
			(unlocked yes)
			(layer "F.SilkS")
			(effects
				(font
					(size 0.7874 0.5842)
					(thickness 0.1524)
				)
			)
		)
		(fp_text user "S7"
			(at -9.884664 49.058322 0)
			(unlocked yes)
			(layer "F.SilkS")
			(effects
				(font
					(size 0.7874 0.5842)
					(thickness 0.1524)
				)
			)
		)
		(fp_text user "S6"
			(at 6.229096 50.832258 0)
			(unlocked yes)
			(layer "F.SilkS")
			(effects
				(font
					(size 0.7874 0.5842)
					(thickness 0.1524)
				)
			)
		)
		(fp_text user "P1"
			(at 3.015488 -1.521714 0)
			(unlocked yes)
			(layer "B.SilkS")
			(effects
				(font
					(size 0.7874 0.5842)
					(thickness 0.1524)
				)
				(justify mirror)
			)
		)
		(fp_text user "P32"
			(at -5.97281 -0.357124 0)
			(unlocked yes)
			(layer "B.SilkS")
			(effects
				(font
					(size 0.7874 0.5842)
					(thickness 0.1524)
				)
				(justify mirror)
			)
		)
		(fp_text user "PRESS-FIT"
			(at -7.18947 29.8831 0)
			(unlocked yes)
			(layer "B.SilkS")
			(effects
				(font
					(size 0.7874 0.5842)
					(thickness 0.1524)
				)
				(justify left mirror)
			)
		)
		(fp_text user "P17"
			(at -5.998972 37.934138 0)
			(unlocked yes)
			(layer "B.SilkS")
			(effects
				(font
					(size 0.7874 0.5842)
					(thickness 0.1524)
				)
				(justify mirror)
			)
		)
		(fp_text user "P16"
			(at 3.100832 38.038024 0)
			(unlocked yes)
			(layer "B.SilkS")
			(effects
				(font
					(size 0.7874 0.5842)
					(thickness 0.1524)
				)
				(justify mirror)
			)
		)
		(fp_text user "S1"
			(at 3.02768 41.844468 0)
			(unlocked yes)
			(layer "B.SilkS")
			(effects
				(font
					(size 0.7874 0.5842)
					(thickness 0.1524)
				)
				(justify mirror)
			)
		)
		(fp_text user "S12"
			(at -5.926582 42.72534 0)
			(unlocked yes)
			(layer "B.SilkS")
			(effects
				(font
					(size 0.7874 0.5842)
					(thickness 0.1524)
				)
				(justify mirror)
			)
		)
		(fp_text user "S6"
			(at 3.126232 47.643542 0)
			(unlocked yes)
			(layer "B.SilkS")
			(effects
				(font
					(size 0.7874 0.5842)
					(thickness 0.1524)
				)
				(justify mirror)
			)
		)
		(fp_text user "S7"
			(at -5.836412 48.290734 0)
			(unlocked yes)
			(layer "B.SilkS")
			(effects
				(font
					(size 0.7874 0.5842)
					(thickness 0.1524)
				)
				(justify mirror)
			)
		)
		(fp_text user "P1"
			(at 3.108452 -1.27 180)
			(unlocked yes)
			(layer "B.Fab")
			(effects
				(font
					(size 0.7874 0.5842)
					(thickness 0.000001)
				)
				(justify mirror)
			)
		)
		(fp_text user "P32"
			(at -5.781548 -0.0508 180)
			(unlocked yes)
			(layer "B.Fab")
			(effects
				(font
					(size 0.7874 0.5842)
					(thickness 0.000001)
				)
				(justify mirror)
			)
		)
		(fp_text user "PRESS-FIT"
			(at -6.82371 29.8831 0)
			(unlocked yes)
			(layer "B.Fab")
			(effects
				(font
					(size 1.6002 1.1938)
					(thickness 0.000001)
				)
				(justify left mirror)
			)
		)
		(fp_text user "P17"
			(at -5.72135 38.0746 180)
			(unlocked yes)
			(layer "B.Fab")
			(effects
				(font
					(size 0.7874 0.5842)
					(thickness 0.000001)
				)
				(justify mirror)
			)
		)
		(fp_text user "P16"
			(at 3.159252 38.3794 180)
			(unlocked yes)
			(layer "B.Fab")
			(effects
				(font
					(size 0.7874 0.5842)
					(thickness 0.000001)
				)
				(justify mirror)
			)
		)
		(fp_text user "S12"
			(at -5.79374 41.42232 180)
			(unlocked yes)
			(layer "B.Fab")
			(effects
				(font
					(size 0.7874 0.5842)
					(thickness 0.000001)
				)
				(justify mirror)
			)
		)
		(fp_text user "S1"
			(at 3.09626 41.656 180)
			(unlocked yes)
			(layer "B.Fab")
			(effects
				(font
					(size 0.7874 0.5842)
					(thickness 0.000001)
				)
				(justify mirror)
			)
		)
		(fp_text user "S6"
			(at 3.133852 48.0822 180)
			(unlocked yes)
			(layer "B.Fab")
			(effects
				(font
					(size 0.7874 0.5842)
					(thickness 0.000001)
				)
				(justify mirror)
			)
		)
		(fp_text user "S7"
			(at -5.781548 48.0822 180)
			(unlocked yes)
			(layer "B.Fab")
			(effects
				(font
					(size 0.7874 0.5842)
					(thickness 0.000001)
				)
				(justify mirror)
			)
		)
		(fp_text user "P32"
			(at -4.071112 -0.0762 180)
			(unlocked yes)
			(layer "F.Fab")
			(effects
				(font
					(size 0.7874 0.5842)
					(thickness 0.000001)
				)
			)
		)
		(fp_text user "P1"
			(at 1.516888 0 180)
			(unlocked yes)
			(layer "F.Fab")
			(effects
				(font
					(size 0.7874 0.5842)
					(thickness 0.000001)
				)
			)
		)
		(fp_text user "PRESS-FIT"
			(at -6.762496 16.251428 0)
			(unlocked yes)
			(layer "F.Fab")
			(effects
				(font
					(size 1.6002 1.1938)
					(thickness 0.000001)
				)
				(justify left)
			)
		)
		(fp_text user "P17"
			(at -4.366768 38.227 180)
			(unlocked yes)
			(layer "F.Fab")
			(effects
				(font
					(size 0.7874 0.5842)
					(thickness 0.000001)
				)
			)
		)
		(fp_text user "P16"
			(at 2.228088 38.354 180)
			(unlocked yes)
			(layer "F.Fab")
			(effects
				(font
					(size 0.7874 0.5842)
					(thickness 0.000001)
				)
			)
		)
		(fp_text user "S12"
			(at -4.362958 41.09212 180)
			(unlocked yes)
			(layer "F.Fab")
			(effects
				(font
					(size 0.7874 0.5842)
					(thickness 0.000001)
				)
			)
		)
		(fp_text user "S1"
			(at 2.164842 41.6306 180)
			(unlocked yes)
			(layer "F.Fab")
			(effects
				(font
					(size 0.7874 0.5842)
					(thickness 0.000001)
				)
			)
		)
		(fp_text user "S6"
			(at 1.923288 48.133 180)
			(unlocked yes)
			(layer "F.Fab")
			(effects
				(font
					(size 0.7874 0.5842)
					(thickness 0.000001)
				)
			)
		)
		(fp_text user "S7"
			(at -4.426712 48.2346 180)
			(unlocked yes)
			(layer "F.Fab")
			(effects
				(font
					(size 0.7874 0.5842)
					(thickness 0.000001)
				)
			)
		)
		(pad "" np_thru_hole circle
			(at -1.35001 -2.54)
			(size 2.5146 2.5146)
			(drill 2.5146)
			(layers "*.Cu" "*.Mask")
			(clearance 0.381)
			(thermal_gap 0.381)
		)
		(pad "" np_thru_hole circle
			(at 0 50.8)
			(size 2.5146 2.5146)
			(drill 2.5146)
			(layers "*.Cu" "*.Mask")
			(clearance 0.381)
			(thermal_gap 0.381)
		)
		(pad "P1" thru_hole rect
			(at 0 0)
			(size 1.1684 1.1684)
			(drill 0.762)
			(layers "*.Cu" "*.Mask")
			(remove_unused_layers no)
			(net "GND")
			(clearance 0.0508)
			(padstack
				(mode front_inner_back)
				(layer "Inner"
					(shape circle)
					(size 1.1684 1.1684)
					(clearance 0.0508)
				)
				(layer "B.Cu"
					(shape rect)
					(size 1.1684 1.1684)
					(thermal_gap 0.0508)
					(clearance 0.0508)
				)
			)
		)
		(pad "P2" thru_hole circle
			(at 0 2.54)
			(size 1.1684 1.1684)
			(drill 0.762)
			(layers "*.Cu" "*.Mask")
			(remove_unused_layers no)
			(net "GND")
			(clearance 0.0508)
			(thermal_gap 0.0508)
		)
		(pad "P3" thru_hole circle
			(at 0 5.08)
			(size 1.1684 1.1684)
			(drill 0.762)
			(layers "*.Cu" "*.Mask")
			(remove_unused_layers no)
			(net "GND")
			(clearance 0.0508)
			(thermal_gap 0.0508)
		)
		(pad "P4" thru_hole circle
			(at 0 7.62)
			(size 1.1684 1.1684)
			(drill 0.762)
			(layers "*.Cu" "*.Mask")
			(remove_unused_layers no)
			(net "GND")
			(clearance 0.0508)
			(thermal_gap 0.0508)
		)
		(pad "P5" thru_hole circle
			(at 0 10.16)
			(size 1.1684 1.1684)
			(drill 0.762)
			(layers "*.Cu" "*.Mask")
			(remove_unused_layers no)
			(net "GND")
			(clearance 0.0508)
			(thermal_gap 0.0508)
		)
		(pad "P6" thru_hole circle
			(at 0 12.7)
			(size 1.1684 1.1684)
			(drill 0.762)
			(layers "*.Cu" "*.Mask")
			(remove_unused_layers no)
			(net "GND")
			(clearance 0.0508)
			(thermal_gap 0.0508)
		)
		(pad "P7" thru_hole circle
			(at 0 15.24)
			(size 1.1684 1.1684)
			(drill 0.762)
			(layers "*.Cu" "*.Mask")
			(remove_unused_layers no)
			(net "GND")
			(clearance 0.0508)
			(thermal_gap 0.0508)
		)
		(pad "P8" thru_hole circle
			(at 0 17.78)
			(size 1.1684 1.1684)
			(drill 0.762)
			(layers "*.Cu" "*.Mask")
			(remove_unused_layers no)
			(net "GND")
			(clearance 0.0508)
			(thermal_gap 0.0508)
		)
		(pad "P9" thru_hole circle
			(at 0 20.32)
			(size 1.1684 1.1684)
			(drill 0.762)
			(layers "*.Cu" "*.Mask")
			(remove_unused_layers no)
			(net "P12V")
			(clearance 0.0508)
			(thermal_gap 0.0508)
		)
		(pad "P10" thru_hole circle
			(at 0 22.86)
			(size 1.1684 1.1684)
			(drill 0.762)
			(layers "*.Cu" "*.Mask")
			(remove_unused_layers no)
			(net "P12V")
			(clearance 0.0508)
			(thermal_gap 0.0508)
		)
		(pad "P11" thru_hole circle
			(at 0 25.4)
			(size 1.1684 1.1684)
			(drill 0.762)
			(layers "*.Cu" "*.Mask")
			(remove_unused_layers no)
			(net "P12V")
			(clearance 0.0508)
			(thermal_gap 0.0508)
		)
		(pad "P12" thru_hole circle
			(at 0 27.94)
			(size 1.1684 1.1684)
			(drill 0.762)
			(layers "*.Cu" "*.Mask")
			(remove_unused_layers no)
			(net "P12V")
			(clearance 0.0508)
			(thermal_gap 0.0508)
		)
		(pad "P13" thru_hole circle
			(at 0 30.48)
			(size 1.1684 1.1684)
			(drill 0.762)
			(layers "*.Cu" "*.Mask")
			(remove_unused_layers no)
			(net "P12V")
			(clearance 0.0508)
			(thermal_gap 0.0508)
		)
		(pad "P14" thru_hole circle
			(at 0 33.02)
			(size 1.1684 1.1684)
			(drill 0.762)
			(layers "*.Cu" "*.Mask")
			(remove_unused_layers no)
			(net "P12V")
			(clearance 0.0508)
			(thermal_gap 0.0508)
		)
		(pad "P15" thru_hole circle
			(at 0 35.56)
			(size 1.1684 1.1684)
			(drill 0.762)
			(layers "*.Cu" "*.Mask")
			(remove_unused_layers no)
			(net "P12V")
			(clearance 0.0508)
			(thermal_gap 0.0508)
		)
		(pad "P16" thru_hole circle
			(at 0 38.1)
			(size 1.1684 1.1684)
			(drill 0.762)
			(layers "*.Cu" "*.Mask")
			(remove_unused_layers no)
			(net "P12V")
			(clearance 0.0508)
			(thermal_gap 0.0508)
		)
		(pad "P17" thru_hole circle
			(at -2.70002 38.1)
			(size 1.1684 1.1684)
			(drill 0.762)
			(layers "*.Cu" "*.Mask")
			(remove_unused_layers no)
			(net "P12V")
			(clearance 0.0508)
			(thermal_gap 0.0508)
		)
		(pad "P18" thru_hole circle
			(at -2.70002 35.56)
			(size 1.1684 1.1684)
			(drill 0.762)
			(layers "*.Cu" "*.Mask")
			(remove_unused_layers no)
			(net "P12V")
			(clearance 0.0508)
			(thermal_gap 0.0508)
		)
		(pad "P19" thru_hole circle
			(at -2.70002 33.02)
			(size 1.1684 1.1684)
			(drill 0.762)
			(layers "*.Cu" "*.Mask")
			(remove_unused_layers no)
			(net "P12V")
			(clearance 0.0508)
			(thermal_gap 0.0508)
		)
		(pad "P20" thru_hole circle
			(at -2.70002 30.48)
			(size 1.1684 1.1684)
			(drill 0.762)
			(layers "*.Cu" "*.Mask")
			(remove_unused_layers no)
			(net "P12V")
			(clearance 0.0508)
			(thermal_gap 0.0508)
		)
		(pad "P21" thru_hole circle
			(at -2.70002 27.94)
			(size 1.1684 1.1684)
			(drill 0.762)
			(layers "*.Cu" "*.Mask")
			(remove_unused_layers no)
			(net "P12V")
			(clearance 0.0508)
			(thermal_gap 0.0508)
		)
		(pad "P22" thru_hole circle
			(at -2.70002 25.4)
			(size 1.1684 1.1684)
			(drill 0.762)
			(layers "*.Cu" "*.Mask")
			(remove_unused_layers no)
			(net "P12V")
			(clearance 0.0508)
			(thermal_gap 0.0508)
		)
		(pad "P23" thru_hole circle
			(at -2.70002 22.86)
			(size 1.1684 1.1684)
			(drill 0.762)
			(layers "*.Cu" "*.Mask")
			(remove_unused_layers no)
			(net "P12V")
			(clearance 0.0508)
			(thermal_gap 0.0508)
		)
		(pad "P24" thru_hole circle
			(at -2.70002 20.32)
			(size 1.1684 1.1684)
			(drill 0.762)
			(layers "*.Cu" "*.Mask")
			(remove_unused_layers no)
			(net "P12V")
			(clearance 0.0508)
			(thermal_gap 0.0508)
		)
		(pad "P25" thru_hole circle
			(at -2.70002 17.78)
			(size 1.1684 1.1684)
			(drill 0.762)
			(layers "*.Cu" "*.Mask")
			(remove_unused_layers no)
			(net "GND")
			(clearance 0.0508)
			(thermal_gap 0.0508)
		)
		(pad "P26" thru_hole circle
			(at -2.70002 15.24)
			(size 1.1684 1.1684)
			(drill 0.762)
			(layers "*.Cu" "*.Mask")
			(remove_unused_layers no)
			(net "GND")
			(clearance 0.0508)
			(thermal_gap 0.0508)
		)
		(pad "P27" thru_hole circle
			(at -2.70002 12.7)
			(size 1.1684 1.1684)
			(drill 0.762)
			(layers "*.Cu" "*.Mask")
			(remove_unused_layers no)
			(net "GND")
			(clearance 0.0508)
			(thermal_gap 0.0508)
		)
		(pad "P28" thru_hole circle
			(at -2.70002 10.16)
			(size 1.1684 1.1684)
			(drill 0.762)
			(layers "*.Cu" "*.Mask")
			(remove_unused_layers no)
			(net "GND")
			(clearance 0.0508)
			(thermal_gap 0.0508)
		)
		(pad "P29" thru_hole circle
			(at -2.70002 7.62)
			(size 1.1684 1.1684)
			(drill 0.762)
			(layers "*.Cu" "*.Mask")
			(remove_unused_layers no)
			(net "GND")
			(clearance 0.0508)
			(thermal_gap 0.0508)
		)
		(pad "P30" thru_hole circle
			(at -2.70002 5.08)
			(size 1.1684 1.1684)
			(drill 0.762)
			(layers "*.Cu" "*.Mask")
			(remove_unused_layers no)
			(net "GND")
			(clearance 0.0508)
			(thermal_gap 0.0508)
		)
		(pad "P31" thru_hole circle
			(at -2.70002 2.54)
			(size 1.1684 1.1684)
			(drill 0.762)
			(layers "*.Cu" "*.Mask")
			(remove_unused_layers no)
			(net "GND")
			(clearance 0.0508)
			(thermal_gap 0.0508)
		)
		(pad "P32" thru_hole circle
			(at -2.70002 0)
			(size 1.1684 1.1684)
			(drill 0.762)
			(layers "*.Cu" "*.Mask")
			(remove_unused_layers no)
			(net "GND")
			(clearance 0.0508)
			(thermal_gap 0.0508)
		)
		(pad "S1" thru_hole circle
			(at 0.55499 41.60012)
			(size 1.1684 1.1684)
			(drill 0.762)
			(layers "*.Cu" "*.Mask")
			(remove_unused_layers no)
			(net "T12_BLAD1_TXD")
			(clearance 0.0508)
			(thermal_gap 0.0508)
		)
		(pad "S2" thru_hole circle
			(at -0.71501 42.87012)
			(size 1.1684 1.1684)
			(drill 0.762)
			(layers "*.Cu" "*.Mask")
			(remove_unused_layers no)
			(net "T12_BLAD1_RXD")
			(clearance 0.0508)
			(thermal_gap 0.0508)
		)
		(pad "S3" thru_hole circle
			(at 0.55499 44.14012)
			(size 1.1684 1.1684)
			(drill 0.762)
			(layers "*.Cu" "*.Mask")
			(remove_unused_layers no)
			(net "T12_BLAD1_EN")
			(clearance 0.0508)
			(thermal_gap 0.0508)
		)
		(pad "S4" thru_hole circle
			(at -0.71501 45.41012)
			(size 1.1684 1.1684)
			(drill 0.762)
			(layers "*.Cu" "*.Mask")
			(remove_unused_layers no)
			(net "T12_BLAD2_EN")
			(clearance 0.0508)
			(thermal_gap 0.0508)
		)
		(pad "S5" thru_hole circle
			(at 0.55499 46.68012)
			(size 1.1684 1.1684)
			(drill 0.762)
			(layers "*.Cu" "*.Mask")
			(remove_unused_layers no)
			(net "T12_BLAD2_TXD")
			(clearance 0.0508)
			(thermal_gap 0.0508)
		)
		(pad "S6" thru_hole circle
			(at -0.71501 47.95012)
			(size 1.1684 1.1684)
			(drill 0.762)
			(layers "*.Cu" "*.Mask")
			(remove_unused_layers no)
			(net "T12_BLAD2_RXD")
			(clearance 0.0508)
			(thermal_gap 0.0508)
		)
		(pad "S7" thru_hole circle
			(at -3.25501 47.95012)
			(size 1.1684 1.1684)
			(drill 0.762)
			(layers "*.Cu" "*.Mask")
			(remove_unused_layers no)
			(net "T12_BLAD4_RXD")
			(clearance 0.0508)
			(thermal_gap 0.0508)
		)
		(pad "S8" thru_hole circle
			(at -1.98501 46.68012)
			(size 1.1684 1.1684)
			(drill 0.762)
			(layers "*.Cu" "*.Mask")
			(remove_unused_layers no)
			(net "T12_BLAD4_TXD")
			(clearance 0.0508)
			(thermal_gap 0.0508)
		)
		(pad "S9" thru_hole circle
			(at -3.25501 45.41012)
			(size 1.1684 1.1684)
			(drill 0.762)
			(layers "*.Cu" "*.Mask")
			(remove_unused_layers no)
			(net "T12_BLAD4_EN")
			(clearance 0.0508)
			(thermal_gap 0.0508)
		)
		(pad "S10" thru_hole circle
			(at -1.98501 44.14012)
			(size 1.1684 1.1684)
			(drill 0.762)
			(layers "*.Cu" "*.Mask")
			(remove_unused_layers no)
			(net "T12_BLAD3_EN")
			(clearance 0.0508)
			(thermal_gap 0.0508)
		)
		(pad "S11" thru_hole circle
			(at -3.25501 42.87012)
			(size 1.1684 1.1684)
			(drill 0.762)
			(layers "*.Cu" "*.Mask")
			(remove_unused_layers no)
			(net "T12_BLAD3_RXD")
			(clearance 0.0508)
			(thermal_gap 0.0508)
		)
		(pad "S12" thru_hole circle
			(at -1.98501 41.60012)
			(size 1.1684 1.1684)
			(drill 0.762)
			(layers "*.Cu" "*.Mask")
			(remove_unused_layers no)
			(net "T12_BLAD3_TXD")
			(clearance 0.0508)
			(thermal_gap 0.0508)
		)
		(zone
			(layer "F.Cu")
			(hatch none 0.5)
			(connect_pads
				(clearance 0)
			)
			(min_thickness 0.25)
			(keepout
				(tracks allowed)
				(vias not_allowed)
				(pads allowed)
				(copperpour not_allowed)
				(footprints allowed)
			)
			(placement
				(enabled no)
				(sheetname "")
			)
			(fill
				(thermal_gap 0.5)
				(thermal_bridge_width 0.5)
				(island_removal_mode 0)
			)
			(polygon
				(pts
					(xy 85.00999 -498.40388) (xy 92.65539 -498.40388) (xy 92.65539 -493.29848) (xy 85.00999 -493.29848)
					(xy 84.98459 -493.29848) (xy 84.98459 -498.40388)
				)
			)
		)
		(zone
			(layer "F.Cu")
			(hatch none 0.5)
			(connect_pads
				(clearance 0)
			)
			(min_thickness 0.25)
			(keepout
				(tracks allowed)
				(vias not_allowed)
				(pads allowed)
				(copperpour not_allowed)
				(footprints allowed)
			)
			(placement
				(enabled no)
				(sheetname "")
			)
			(fill
				(thermal_gap 0.5)
				(thermal_bridge_width 0.5)
				(island_removal_mode 0)
			)
			(polygon
				(pts
					(xy 43.37939 -493.88268) (xy 43.37939 -497.84508) (xy 82.77479 -497.84508) (xy 82.80019 -497.84508)
					(xy 82.80019 -493.88268) (xy 82.80019 -493.85728) (xy 43.37939 -493.85728)
				)
			)
		)
		(zone
			(layers "F.Cu" "B.Cu" "In1.Cu" "In2.Cu" "In3.Cu" "In4.Cu" "In5.Cu" "In6.Cu")
			(hatch none 0.5)
			(connect_pads
				(clearance 0)
			)
			(min_thickness 0.25)
			(keepout
				(tracks not_allowed)
				(vias allowed)
				(pads allowed)
				(copperpour not_allowed)
				(footprints allowed)
			)
			(placement
				(enabled no)
				(sheetname "")
			)
			(fill
				(thermal_gap 0.5)
				(thermal_bridge_width 0.5)
				(island_removal_mode 0)
			)
			(polygon
				(pts
					(arc
						(start 43.18 -495.86007)
						(mid 39.81958 -495.86007)
						(end 43.18 -495.86007)
					)
				)
			)
		)
		(zone
			(layers "F.Cu" "B.Cu" "In1.Cu" "In2.Cu" "In3.Cu" "In4.Cu" "In5.Cu" "In6.Cu")
			(hatch none 0.5)
			(connect_pads
				(clearance 0)
			)
			(min_thickness 0.25)
			(keepout
				(tracks not_allowed)
				(vias allowed)
				(pads allowed)
				(copperpour not_allowed)
				(footprints allowed)
			)
			(placement
				(enabled no)
				(sheetname "")
			)
			(fill
				(thermal_gap 0.5)
				(thermal_bridge_width 0.5)
				(island_removal_mode 0)
			)
			(polygon
				(pts
					(arc
						(start 96.52381 -497.21008)
						(mid 93.15577 -497.21008)
						(end 96.52381 -497.21008)
					)
				)
			)
		)
	)
	(footprint ""
		(layer "B.Cu")
		(at 44.03979 -97.16008 90)
		(property "Reference" "J9"
			(at 6.238748 -5.04063 0)
			(unlocked yes)
			(layer "B.SilkS")
			(effects
				(font
					(size 0.7874 0.5842)
					(thickness 0.1524)
				)
				(justify left mirror)
			)
		)
		(property "Value" ""
			(at 0 0 90)
			(layer "B.Fab")
			(effects
				(font
					(size 1.27 1.27)
				)
				(justify mirror)
			)
		)
		(duplicate_pad_numbers_are_jumpers no)
		(fp_line
			(start 5.275072 -13.910056)
			(end -7.975092 -13.910056)
			(stroke
				(width 0.1524)
				(type default)
			)
			(layer "F.SilkS")
		)
		(fp_line
			(start -7.975092 -13.910056)
			(end -7.975092 62.170056)
			(stroke
				(width 0.1524)
				(type default)
			)
			(layer "F.SilkS")
		)
		(fp_line
			(start 5.275072 62.170056)
			(end 5.275072 -13.910056)
			(stroke
				(width 0.1524)
				(type default)
			)
			(layer "F.SilkS")
		)
		(fp_line
			(start -7.975092 62.170056)
			(end 5.275072 62.170056)
			(stroke
				(width 0.1524)
				(type default)
			)
			(layer "F.SilkS")
		)
		(fp_line
			(start 5.275072 -13.910056)
			(end -7.975092 -13.910056)
			(stroke
				(width 0.1524)
				(type default)
			)
			(layer "B.SilkS")
		)
		(fp_line
			(start -7.975092 -13.910056)
			(end -7.975092 62.170056)
			(stroke
				(width 0.1524)
				(type default)
			)
			(layer "B.SilkS")
		)
		(fp_line
			(start 2.275078 -10.910062)
			(end 2.275078 59.170062)
			(stroke
				(width 0.1524)
				(type default)
			)
			(layer "B.SilkS")
		)
		(fp_line
			(start -4.975098 -10.910062)
			(end 2.275078 -10.910062)
			(stroke
				(width 0.1524)
				(type default)
			)
			(layer "B.SilkS")
		)
		(fp_line
			(start 2.275078 59.170062)
			(end -4.975098 59.170062)
			(stroke
				(width 0.1524)
				(type default)
			)
			(layer "B.SilkS")
		)
		(fp_line
			(start -4.975098 59.170062)
			(end -4.975098 -10.910062)
			(stroke
				(width 0.1524)
				(type default)
			)
			(layer "B.SilkS")
		)
		(fp_line
			(start 5.275072 62.170056)
			(end 5.275072 -13.910056)
			(stroke
				(width 0.1524)
				(type default)
			)
			(layer "B.SilkS")
		)
		(fp_line
			(start -7.975092 62.170056)
			(end 5.275072 62.170056)
			(stroke
				(width 0.1524)
				(type default)
			)
			(layer "B.SilkS")
		)
		(fp_poly
			(pts
				(xy 4.103878 -0.759206) (xy 4.103878 0.764794) (xy 2.579878 0.002794)
			)
			(stroke
				(width 0)
				(type default)
			)
			(fill yes)
			(layer "B.SilkS")
		)
		(fp_poly
			(pts
				(xy 2.275078 -10.910062) (xy 2.275078 59.170062) (xy -4.975098 59.170062) (xy -4.975098 -10.910062)
			)
			(stroke
				(width 0)
				(type default)
			)
			(fill no)
			(layer "B.CrtYd")
		)
		(fp_poly
			(pts
				(xy 1.1938 40.9702) (xy 1.1938 48.6156) (xy -3.9116 48.6156) (xy -3.9116 40.9702) (xy -3.9116 40.9448)
				(xy 1.1938 40.9448)
			)
			(stroke
				(width 0)
				(type default)
			)
			(fill no)
			(layer "F.CrtYd")
		)
		(fp_poly
			(pts
				(xy -3.3274 -0.6604) (xy 0.635 -0.6604) (xy 0.635 38.735) (xy 0.635 38.7604) (xy -3.3274 38.7604)
				(xy -3.3528 38.7604) (xy -3.3528 -0.6604)
			)
			(stroke
				(width 0)
				(type default)
			)
			(fill no)
			(layer "F.CrtYd")
		)
		(fp_poly
			(pts
				(arc
					(start -1.35001 -1.01219)
					(mid -1.35001 -4.06781)
					(end -1.35001 -1.01219)
				)
			)
			(stroke
				(width 0)
				(type default)
			)
			(fill no)
			(layer "F.CrtYd")
		)
		(fp_poly
			(pts
				(arc
					(start 0 52.33162)
					(mid 0 49.26838)
					(end 0 52.33162)
				)
			)
			(stroke
				(width 0)
				(type default)
			)
			(fill no)
			(layer "F.CrtYd")
		)
		(fp_line
			(start 2.275078 -10.910062)
			(end 2.275078 59.170062)
			(stroke
				(width 0.1)
				(type default)
			)
			(layer "B.Fab")
		)
		(fp_line
			(start -4.975098 -10.910062)
			(end 2.275078 -10.910062)
			(stroke
				(width 0.1)
				(type default)
			)
			(layer "B.Fab")
		)
		(fp_line
			(start 2.275078 59.170062)
			(end -4.975098 59.170062)
			(stroke
				(width 0.1)
				(type default)
			)
			(layer "B.Fab")
		)
		(fp_line
			(start -4.975098 59.170062)
			(end -4.975098 -10.910062)
			(stroke
				(width 0.1)
				(type default)
			)
			(layer "B.Fab")
		)
		(fp_poly
			(pts
				(xy 4.103878 -0.759206) (xy 4.103878 0.764794) (xy 2.579878 0.002794)
			)
			(stroke
				(width 0)
				(type default)
			)
			(fill yes)
			(layer "B.Fab")
		)
		(fp_line
			(start 5.275072 -13.910056)
			(end -7.975092 -13.910056)
			(stroke
				(width 0.1)
				(type default)
			)
			(layer "F.Fab")
		)
		(fp_line
			(start -7.975092 -13.910056)
			(end -7.975092 62.170056)
			(stroke
				(width 0.1)
				(type default)
			)
			(layer "F.Fab")
		)
		(fp_line
			(start 5.275072 62.170056)
			(end 5.275072 -13.910056)
			(stroke
				(width 0.1)
				(type default)
			)
			(layer "F.Fab")
		)
		(fp_line
			(start -7.975092 62.170056)
			(end 5.275072 62.170056)
			(stroke
				(width 0.1)
				(type default)
			)
			(layer "F.Fab")
		)
		(fp_text user "P32"
			(at -8.987536 -0.131826 0)
			(unlocked yes)
			(layer "F.SilkS")
			(effects
				(font
					(size 0.7874 0.5842)
					(thickness 0.1524)
				)
			)
		)
		(fp_text user "P1"
			(at 6.585966 2.207514 0)
			(unlocked yes)
			(layer "F.SilkS")
			(effects
				(font
					(size 0.7874 0.5842)
					(thickness 0.1524)
				)
			)
		)
		(fp_text user "PRESS-FIT"
			(at -10.457942 9.760204 0)
			(unlocked yes)
			(layer "F.SilkS")
			(effects
				(font
					(size 0.7874 0.5842)
					(thickness 0.1524)
				)
				(justify left)
			)
		)
		(fp_text user "P16"
			(at 6.97992 37.823394 0)
			(unlocked yes)
			(layer "F.SilkS")
			(effects
				(font
					(size 0.7874 0.5842)
					(thickness 0.1524)
				)
			)
		)
		(fp_text user "P17"
			(at -8.79221 38.342824 0)
			(unlocked yes)
			(layer "F.SilkS")
			(effects
				(font
					(size 0.7874 0.5842)
					(thickness 0.1524)
				)
			)
		)
		(fp_text user "S1"
			(at 6.452362 41.608502 0)
			(unlocked yes)
			(layer "F.SilkS")
			(effects
				(font
					(size 0.7874 0.5842)
					(thickness 0.1524)
				)
			)
		)
		(fp_text user "S12"
			(at -9.221724 41.726612 0)
			(unlocked yes)
			(layer "F.SilkS")
			(effects
				(font
					(size 0.7874 0.5842)
					(thickness 0.1524)
				)
			)
		)
		(fp_text user "S6"
			(at 6.08457 47.991522 0)
			(unlocked yes)
			(layer "F.SilkS")
			(effects
				(font
					(size 0.7874 0.5842)
					(thickness 0.1524)
				)
			)
		)
		(fp_text user "S7"
			(at -9.294368 48.61433 0)
			(unlocked yes)
			(layer "F.SilkS")
			(effects
				(font
					(size 0.7874 0.5842)
					(thickness 0.1524)
				)
			)
		)
		(fp_text user "P1"
			(at 3.052318 -1.361948 0)
			(unlocked yes)
			(layer "B.SilkS")
			(effects
				(font
					(size 0.7874 0.5842)
					(thickness 0.1524)
				)
				(justify mirror)
			)
		)
		(fp_text user "P32"
			(at -5.867654 -0.333502 0)
			(unlocked yes)
			(layer "B.SilkS")
			(effects
				(font
					(size 0.7874 0.5842)
					(thickness 0.1524)
				)
				(justify mirror)
			)
		)
		(fp_text user "PRESS-FIT"
			(at -7.18947 29.8831 0)
			(unlocked yes)
			(layer "B.SilkS")
			(effects
				(font
					(size 0.7874 0.5842)
					(thickness 0.1524)
				)
				(justify left mirror)
			)
		)
		(fp_text user "P17"
			(at -5.72389 37.92347 0)
			(unlocked yes)
			(layer "B.SilkS")
			(effects
				(font
					(size 0.7874 0.5842)
					(thickness 0.1524)
				)
				(justify mirror)
			)
		)
		(fp_text user "P16"
			(at 3.103626 37.925248 0)
			(unlocked yes)
			(layer "B.SilkS")
			(effects
				(font
					(size 0.7874 0.5842)
					(thickness 0.1524)
				)
				(justify mirror)
			)
		)
		(fp_text user "S1"
			(at 3.064256 41.595548 0)
			(unlocked yes)
			(layer "B.SilkS")
			(effects
				(font
					(size 0.7874 0.5842)
					(thickness 0.1524)
				)
				(justify mirror)
			)
		)
		(fp_text user "S12"
			(at -5.753608 42.06748 0)
			(unlocked yes)
			(layer "B.SilkS")
			(effects
				(font
					(size 0.7874 0.5842)
					(thickness 0.1524)
				)
				(justify mirror)
			)
		)
		(fp_text user "S7"
			(at -5.867908 47.837344 0)
			(unlocked yes)
			(layer "B.SilkS")
			(effects
				(font
					(size 0.7874 0.5842)
					(thickness 0.1524)
				)
				(justify mirror)
			)
		)
		(fp_text user "S6"
			(at 2.992628 47.90567 0)
			(unlocked yes)
			(layer "B.SilkS")
			(effects
				(font
					(size 0.7874 0.5842)
					(thickness 0.1524)
				)
				(justify mirror)
			)
		)
		(fp_text user "P1"
			(at 3.108452 -1.27 180)
			(unlocked yes)
			(layer "B.Fab")
			(effects
				(font
					(size 0.7874 0.5842)
					(thickness 0.000001)
				)
				(justify mirror)
			)
		)
		(fp_text user "P32"
			(at -5.781548 -0.0508 180)
			(unlocked yes)
			(layer "B.Fab")
			(effects
				(font
					(size 0.7874 0.5842)
					(thickness 0.000001)
				)
				(justify mirror)
			)
		)
		(fp_text user "PRESS-FIT"
			(at -6.82371 29.8831 0)
			(unlocked yes)
			(layer "B.Fab")
			(effects
				(font
					(size 1.6002 1.1938)
					(thickness 0.000001)
				)
				(justify left mirror)
			)
		)
		(fp_text user "P17"
			(at -5.72135 38.0746 180)
			(unlocked yes)
			(layer "B.Fab")
			(effects
				(font
					(size 0.7874 0.5842)
					(thickness 0.000001)
				)
				(justify mirror)
			)
		)
		(fp_text user "P16"
			(at 3.159252 38.3794 180)
			(unlocked yes)
			(layer "B.Fab")
			(effects
				(font
					(size 0.7874 0.5842)
					(thickness 0.000001)
				)
				(justify mirror)
			)
		)
		(fp_text user "S12"
			(at -5.79374 41.42232 180)
			(unlocked yes)
			(layer "B.Fab")
			(effects
				(font
					(size 0.7874 0.5842)
					(thickness 0.000001)
				)
				(justify mirror)
			)
		)
		(fp_text user "S1"
			(at 3.09626 41.656 180)
			(unlocked yes)
			(layer "B.Fab")
			(effects
				(font
					(size 0.7874 0.5842)
					(thickness 0.000001)
				)
				(justify mirror)
			)
		)
		(fp_text user "S6"
			(at 3.133852 48.0822 180)
			(unlocked yes)
			(layer "B.Fab")
			(effects
				(font
					(size 0.7874 0.5842)
					(thickness 0.000001)
				)
				(justify mirror)
			)
		)
		(fp_text user "S7"
			(at -5.781548 48.0822 180)
			(unlocked yes)
			(layer "B.Fab")
			(effects
				(font
					(size 0.7874 0.5842)
					(thickness 0.000001)
				)
				(justify mirror)
			)
		)
		(fp_text user "P32"
			(at -4.071112 -0.0762 180)
			(unlocked yes)
			(layer "F.Fab")
			(effects
				(font
					(size 0.7874 0.5842)
					(thickness 0.000001)
				)
			)
		)
		(fp_text user "P1"
			(at 1.516888 0 180)
			(unlocked yes)
			(layer "F.Fab")
			(effects
				(font
					(size 0.7874 0.5842)
					(thickness 0.000001)
				)
			)
		)
		(fp_text user "PRESS-FIT"
			(at -6.762496 16.251428 0)
			(unlocked yes)
			(layer "F.Fab")
			(effects
				(font
					(size 1.6002 1.1938)
					(thickness 0.000001)
				)
				(justify left)
			)
		)
		(fp_text user "P17"
			(at -4.366768 38.227 180)
			(unlocked yes)
			(layer "F.Fab")
			(effects
				(font
					(size 0.7874 0.5842)
					(thickness 0.000001)
				)
			)
		)
		(fp_text user "P16"
			(at 2.228088 38.354 180)
			(unlocked yes)
			(layer "F.Fab")
			(effects
				(font
					(size 0.7874 0.5842)
					(thickness 0.000001)
				)
			)
		)
		(fp_text user "S12"
			(at -4.362958 41.09212 180)
			(unlocked yes)
			(layer "F.Fab")
			(effects
				(font
					(size 0.7874 0.5842)
					(thickness 0.000001)
				)
			)
		)
		(fp_text user "S1"
			(at 2.164842 41.6306 180)
			(unlocked yes)
			(layer "F.Fab")
			(effects
				(font
					(size 0.7874 0.5842)
					(thickness 0.000001)
				)
			)
		)
		(fp_text user "S6"
			(at 1.923288 48.133 180)
			(unlocked yes)
			(layer "F.Fab")
			(effects
				(font
					(size 0.7874 0.5842)
					(thickness 0.000001)
				)
			)
		)
		(fp_text user "S7"
			(at -4.426712 48.2346 180)
			(unlocked yes)
			(layer "F.Fab")
			(effects
				(font
					(size 0.7874 0.5842)
					(thickness 0.000001)
				)
			)
		)
		(pad "" np_thru_hole circle
			(at -1.35001 -2.54)
			(size 2.5146 2.5146)
			(drill 2.5146)
			(layers "*.Cu" "*.Mask")
			(clearance 0.381)
			(thermal_gap 0.381)
		)
		(pad "" np_thru_hole circle
			(at 0 50.8)
			(size 2.5146 2.5146)
			(drill 2.5146)
			(layers "*.Cu" "*.Mask")
			(clearance 0.381)
			(thermal_gap 0.381)
		)
		(pad "P1" thru_hole rect
			(at 0 0)
			(size 1.1684 1.1684)
			(drill 0.762)
			(layers "*.Cu" "*.Mask")
			(remove_unused_layers no)
			(net "GND")
			(clearance 0.0508)
			(padstack
				(mode front_inner_back)
				(layer "Inner"
					(shape circle)
					(size 1.1684 1.1684)
					(clearance 0.0508)
				)
				(layer "B.Cu"
					(shape rect)
					(size 1.1684 1.1684)
					(thermal_gap 0.0508)
					(clearance 0.0508)
				)
			)
		)
		(pad "P2" thru_hole circle
			(at 0 2.54)
			(size 1.1684 1.1684)
			(drill 0.762)
			(layers "*.Cu" "*.Mask")
			(remove_unused_layers no)
			(net "GND")
			(clearance 0.0508)
			(thermal_gap 0.0508)
		)
		(pad "P3" thru_hole circle
			(at 0 5.08)
			(size 1.1684 1.1684)
			(drill 0.762)
			(layers "*.Cu" "*.Mask")
			(remove_unused_layers no)
			(net "GND")
			(clearance 0.0508)
			(thermal_gap 0.0508)
		)
		(pad "P4" thru_hole circle
			(at 0 7.62)
			(size 1.1684 1.1684)
			(drill 0.762)
			(layers "*.Cu" "*.Mask")
			(remove_unused_layers no)
			(net "GND")
			(clearance 0.0508)
			(thermal_gap 0.0508)
		)
		(pad "P5" thru_hole circle
			(at 0 10.16)
			(size 1.1684 1.1684)
			(drill 0.762)
			(layers "*.Cu" "*.Mask")
			(remove_unused_layers no)
			(net "GND")
			(clearance 0.0508)
			(thermal_gap 0.0508)
		)
		(pad "P6" thru_hole circle
			(at 0 12.7)
			(size 1.1684 1.1684)
			(drill 0.762)
			(layers "*.Cu" "*.Mask")
			(remove_unused_layers no)
			(net "GND")
			(clearance 0.0508)
			(thermal_gap 0.0508)
		)
		(pad "P7" thru_hole circle
			(at 0 15.24)
			(size 1.1684 1.1684)
			(drill 0.762)
			(layers "*.Cu" "*.Mask")
			(remove_unused_layers no)
			(net "GND")
			(clearance 0.0508)
			(thermal_gap 0.0508)
		)
		(pad "P8" thru_hole circle
			(at 0 17.78)
			(size 1.1684 1.1684)
			(drill 0.762)
			(layers "*.Cu" "*.Mask")
			(remove_unused_layers no)
			(net "GND")
			(clearance 0.0508)
			(thermal_gap 0.0508)
		)
		(pad "P9" thru_hole circle
			(at 0 20.32)
			(size 1.1684 1.1684)
			(drill 0.762)
			(layers "*.Cu" "*.Mask")
			(remove_unused_layers no)
			(net "P12V")
			(clearance 0.0508)
			(thermal_gap 0.0508)
		)
		(pad "P10" thru_hole circle
			(at 0 22.86)
			(size 1.1684 1.1684)
			(drill 0.762)
			(layers "*.Cu" "*.Mask")
			(remove_unused_layers no)
			(net "P12V")
			(clearance 0.0508)
			(thermal_gap 0.0508)
		)
		(pad "P11" thru_hole circle
			(at 0 25.4)
			(size 1.1684 1.1684)
			(drill 0.762)
			(layers "*.Cu" "*.Mask")
			(remove_unused_layers no)
			(net "P12V")
			(clearance 0.0508)
			(thermal_gap 0.0508)
		)
		(pad "P12" thru_hole circle
			(at 0 27.94)
			(size 1.1684 1.1684)
			(drill 0.762)
			(layers "*.Cu" "*.Mask")
			(remove_unused_layers no)
			(net "P12V")
			(clearance 0.0508)
			(thermal_gap 0.0508)
		)
		(pad "P13" thru_hole circle
			(at 0 30.48)
			(size 1.1684 1.1684)
			(drill 0.762)
			(layers "*.Cu" "*.Mask")
			(remove_unused_layers no)
			(net "P12V")
			(clearance 0.0508)
			(thermal_gap 0.0508)
		)
		(pad "P14" thru_hole circle
			(at 0 33.02)
			(size 1.1684 1.1684)
			(drill 0.762)
			(layers "*.Cu" "*.Mask")
			(remove_unused_layers no)
			(net "P12V")
			(clearance 0.0508)
			(thermal_gap 0.0508)
		)
		(pad "P15" thru_hole circle
			(at 0 35.56)
			(size 1.1684 1.1684)
			(drill 0.762)
			(layers "*.Cu" "*.Mask")
			(remove_unused_layers no)
			(net "P12V")
			(clearance 0.0508)
			(thermal_gap 0.0508)
		)
		(pad "P16" thru_hole circle
			(at 0 38.1)
			(size 1.1684 1.1684)
			(drill 0.762)
			(layers "*.Cu" "*.Mask")
			(remove_unused_layers no)
			(net "P12V")
			(clearance 0.0508)
			(thermal_gap 0.0508)
		)
		(pad "P17" thru_hole circle
			(at -2.70002 38.1)
			(size 1.1684 1.1684)
			(drill 0.762)
			(layers "*.Cu" "*.Mask")
			(remove_unused_layers no)
			(net "P12V")
			(clearance 0.0508)
			(thermal_gap 0.0508)
		)
		(pad "P18" thru_hole circle
			(at -2.70002 35.56)
			(size 1.1684 1.1684)
			(drill 0.762)
			(layers "*.Cu" "*.Mask")
			(remove_unused_layers no)
			(net "P12V")
			(clearance 0.0508)
			(thermal_gap 0.0508)
		)
		(pad "P19" thru_hole circle
			(at -2.70002 33.02)
			(size 1.1684 1.1684)
			(drill 0.762)
			(layers "*.Cu" "*.Mask")
			(remove_unused_layers no)
			(net "P12V")
			(clearance 0.0508)
			(thermal_gap 0.0508)
		)
		(pad "P20" thru_hole circle
			(at -2.70002 30.48)
			(size 1.1684 1.1684)
			(drill 0.762)
			(layers "*.Cu" "*.Mask")
			(remove_unused_layers no)
			(net "P12V")
			(clearance 0.0508)
			(thermal_gap 0.0508)
		)
		(pad "P21" thru_hole circle
			(at -2.70002 27.94)
			(size 1.1684 1.1684)
			(drill 0.762)
			(layers "*.Cu" "*.Mask")
			(remove_unused_layers no)
			(net "P12V")
			(clearance 0.0508)
			(thermal_gap 0.0508)
		)
		(pad "P22" thru_hole circle
			(at -2.70002 25.4)
			(size 1.1684 1.1684)
			(drill 0.762)
			(layers "*.Cu" "*.Mask")
			(remove_unused_layers no)
			(net "P12V")
			(clearance 0.0508)
			(thermal_gap 0.0508)
		)
		(pad "P23" thru_hole circle
			(at -2.70002 22.86)
			(size 1.1684 1.1684)
			(drill 0.762)
			(layers "*.Cu" "*.Mask")
			(remove_unused_layers no)
			(net "P12V")
			(clearance 0.0508)
			(thermal_gap 0.0508)
		)
		(pad "P24" thru_hole circle
			(at -2.70002 20.32)
			(size 1.1684 1.1684)
			(drill 0.762)
			(layers "*.Cu" "*.Mask")
			(remove_unused_layers no)
			(net "P12V")
			(clearance 0.0508)
			(thermal_gap 0.0508)
		)
		(pad "P25" thru_hole circle
			(at -2.70002 17.78)
			(size 1.1684 1.1684)
			(drill 0.762)
			(layers "*.Cu" "*.Mask")
			(remove_unused_layers no)
			(net "GND")
			(clearance 0.0508)
			(thermal_gap 0.0508)
		)
		(pad "P26" thru_hole circle
			(at -2.70002 15.24)
			(size 1.1684 1.1684)
			(drill 0.762)
			(layers "*.Cu" "*.Mask")
			(remove_unused_layers no)
			(net "GND")
			(clearance 0.0508)
			(thermal_gap 0.0508)
		)
		(pad "P27" thru_hole circle
			(at -2.70002 12.7)
			(size 1.1684 1.1684)
			(drill 0.762)
			(layers "*.Cu" "*.Mask")
			(remove_unused_layers no)
			(net "GND")
			(clearance 0.0508)
			(thermal_gap 0.0508)
		)
		(pad "P28" thru_hole circle
			(at -2.70002 10.16)
			(size 1.1684 1.1684)
			(drill 0.762)
			(layers "*.Cu" "*.Mask")
			(remove_unused_layers no)
			(net "GND")
			(clearance 0.0508)
			(thermal_gap 0.0508)
		)
		(pad "P29" thru_hole circle
			(at -2.70002 7.62)
			(size 1.1684 1.1684)
			(drill 0.762)
			(layers "*.Cu" "*.Mask")
			(remove_unused_layers no)
			(net "GND")
			(clearance 0.0508)
			(thermal_gap 0.0508)
		)
		(pad "P30" thru_hole circle
			(at -2.70002 5.08)
			(size 1.1684 1.1684)
			(drill 0.762)
			(layers "*.Cu" "*.Mask")
			(remove_unused_layers no)
			(net "GND")
			(clearance 0.0508)
			(thermal_gap 0.0508)
		)
		(pad "P31" thru_hole circle
			(at -2.70002 2.54)
			(size 1.1684 1.1684)
			(drill 0.762)
			(layers "*.Cu" "*.Mask")
			(remove_unused_layers no)
			(net "GND")
			(clearance 0.0508)
			(thermal_gap 0.0508)
		)
		(pad "P32" thru_hole circle
			(at -2.70002 0)
			(size 1.1684 1.1684)
			(drill 0.762)
			(layers "*.Cu" "*.Mask")
			(remove_unused_layers no)
			(net "GND")
			(clearance 0.0508)
			(thermal_gap 0.0508)
		)
		(pad "S1" thru_hole circle
			(at 0.55499 41.60012)
			(size 1.1684 1.1684)
			(drill 0.762)
			(layers "*.Cu" "*.Mask")
			(remove_unused_layers no)
			(net "T3_BLAD1_TXD")
			(clearance 0.0508)
			(thermal_gap 0.0508)
		)
		(pad "S2" thru_hole circle
			(at -0.71501 42.87012)
			(size 1.1684 1.1684)
			(drill 0.762)
			(layers "*.Cu" "*.Mask")
			(remove_unused_layers no)
			(net "T3_BLAD1_RXD")
			(clearance 0.0508)
			(thermal_gap 0.0508)
		)
		(pad "S3" thru_hole circle
			(at 0.55499 44.14012)
			(size 1.1684 1.1684)
			(drill 0.762)
			(layers "*.Cu" "*.Mask")
			(remove_unused_layers no)
			(net "T3_BLAD1_EN")
			(clearance 0.0508)
			(thermal_gap 0.0508)
		)
		(pad "S4" thru_hole circle
			(at -0.71501 45.41012)
			(size 1.1684 1.1684)
			(drill 0.762)
			(layers "*.Cu" "*.Mask")
			(remove_unused_layers no)
			(net "T3_BLAD2_EN")
			(clearance 0.0508)
			(thermal_gap 0.0508)
		)
		(pad "S5" thru_hole circle
			(at 0.55499 46.68012)
			(size 1.1684 1.1684)
			(drill 0.762)
			(layers "*.Cu" "*.Mask")
			(remove_unused_layers no)
			(net "T3_BLAD2_TXD")
			(clearance 0.0508)
			(thermal_gap 0.0508)
		)
		(pad "S6" thru_hole circle
			(at -0.71501 47.95012)
			(size 1.1684 1.1684)
			(drill 0.762)
			(layers "*.Cu" "*.Mask")
			(remove_unused_layers no)
			(net "T3_BLAD2_RXD")
			(clearance 0.0508)
			(thermal_gap 0.0508)
		)
		(pad "S7" thru_hole circle
			(at -3.25501 47.95012)
			(size 1.1684 1.1684)
			(drill 0.762)
			(layers "*.Cu" "*.Mask")
			(remove_unused_layers no)
			(net "T3_BLAD4_RXD")
			(clearance 0.0508)
			(thermal_gap 0.0508)
		)
		(pad "S8" thru_hole circle
			(at -1.98501 46.68012)
			(size 1.1684 1.1684)
			(drill 0.762)
			(layers "*.Cu" "*.Mask")
			(remove_unused_layers no)
			(net "T3_BLAD4_TXD")
			(clearance 0.0508)
			(thermal_gap 0.0508)
		)
		(pad "S9" thru_hole circle
			(at -3.25501 45.41012)
			(size 1.1684 1.1684)
			(drill 0.762)
			(layers "*.Cu" "*.Mask")
			(remove_unused_layers no)
			(net "T3_BLAD4_EN")
			(clearance 0.0508)
			(thermal_gap 0.0508)
		)
		(pad "S10" thru_hole circle
			(at -1.98501 44.14012)
			(size 1.1684 1.1684)
			(drill 0.762)
			(layers "*.Cu" "*.Mask")
			(remove_unused_layers no)
			(net "T3_BLAD3_EN")
			(clearance 0.0508)
			(thermal_gap 0.0508)
		)
		(pad "S11" thru_hole circle
			(at -3.25501 42.87012)
			(size 1.1684 1.1684)
			(drill 0.762)
			(layers "*.Cu" "*.Mask")
			(remove_unused_layers no)
			(net "T3_BLAD3_RXD")
			(clearance 0.0508)
			(thermal_gap 0.0508)
		)
		(pad "S12" thru_hole circle
			(at -1.98501 41.60012)
			(size 1.1684 1.1684)
			(drill 0.762)
			(layers "*.Cu" "*.Mask")
			(remove_unused_layers no)
			(net "T3_BLAD3_TXD")
			(clearance 0.0508)
			(thermal_gap 0.0508)
		)
		(zone
			(layer "F.Cu")
			(hatch none 0.5)
			(connect_pads
				(clearance 0)
			)
			(min_thickness 0.25)
			(keepout
				(tracks allowed)
				(vias not_allowed)
				(pads allowed)
				(copperpour not_allowed)
				(footprints allowed)
			)
			(placement
				(enabled no)
				(sheetname "")
			)
			(fill
				(thermal_gap 0.5)
				(thermal_bridge_width 0.5)
				(island_removal_mode 0)
			)
			(polygon
				(pts
					(xy 85.00999 -98.35388) (xy 92.65539 -98.35388) (xy 92.65539 -93.24848) (xy 85.00999 -93.24848)
					(xy 84.98459 -93.24848) (xy 84.98459 -98.35388)
				)
			)
		)
		(zone
			(layer "F.Cu")
			(hatch none 0.5)
			(connect_pads
				(clearance 0)
			)
			(min_thickness 0.25)
			(keepout
				(tracks allowed)
				(vias not_allowed)
				(pads allowed)
				(copperpour not_allowed)
				(footprints allowed)
			)
			(placement
				(enabled no)
				(sheetname "")
			)
			(fill
				(thermal_gap 0.5)
				(thermal_bridge_width 0.5)
				(island_removal_mode 0)
			)
			(polygon
				(pts
					(xy 43.37939 -93.83268) (xy 43.37939 -97.79508) (xy 82.77479 -97.79508) (xy 82.80019 -97.79508)
					(xy 82.80019 -93.83268) (xy 82.80019 -93.80728) (xy 43.37939 -93.80728)
				)
			)
		)
		(zone
			(layers "F.Cu" "B.Cu" "In1.Cu" "In2.Cu" "In3.Cu" "In4.Cu" "In5.Cu" "In6.Cu")
			(hatch none 0.5)
			(connect_pads
				(clearance 0)
			)
			(min_thickness 0.25)
			(keepout
				(tracks not_allowed)
				(vias allowed)
				(pads allowed)
				(copperpour not_allowed)
				(footprints allowed)
			)
			(placement
				(enabled no)
				(sheetname "")
			)
			(fill
				(thermal_gap 0.5)
				(thermal_bridge_width 0.5)
				(island_removal_mode 0)
			)
			(polygon
				(pts
					(arc
						(start 43.18 -95.81007)
						(mid 39.81958 -95.81007)
						(end 43.18 -95.81007)
					)
				)
			)
		)
		(zone
			(layers "F.Cu" "B.Cu" "In1.Cu" "In2.Cu" "In3.Cu" "In4.Cu" "In5.Cu" "In6.Cu")
			(hatch none 0.5)
			(connect_pads
				(clearance 0)
			)
			(min_thickness 0.25)
			(keepout
				(tracks not_allowed)
				(vias allowed)
				(pads allowed)
				(copperpour not_allowed)
				(footprints allowed)
			)
			(placement
				(enabled no)
				(sheetname "")
			)
			(fill
				(thermal_gap 0.5)
				(thermal_bridge_width 0.5)
				(island_removal_mode 0)
			)
			(polygon
				(pts
					(arc
						(start 96.52381 -97.16008)
						(mid 93.15577 -97.16008)
						(end 96.52381 -97.16008)
					)
				)
			)
		)
	)
	(gr_poly
		(pts
			(xy 14.568932 -328.07656) (xy 15.251176 -328.07656) (xy 17.832324 -328.07656) (xy 21.457666 -328.07656)
			(xy 21.936456 -327.59777) (xy 21.936456 -320.261742) (xy 19.476974 -317.80226) (xy 15.26667 -317.80226)
			(xy 15.151608 -317.917322) (xy 15.151608 -318.720216) (xy 14.938248 -318.933576) (xy 13.675106 -318.933576)
			(xy 13.523976 -319.084706) (xy 13.523976 -320.07175) (xy 13.523976 -326.502776) (xy 13.523976 -327.757028)
			(xy 13.844016 -328.077068) (xy 14.568424 -328.077068)
		)
		(stroke
			(width 0)
			(type solid)
		)
		(fill yes)
		(layer "F.Cu")
		(net "P12V")
	)
	(gr_poly
		(pts
			(arc
				(start 1.27 -181.889146)
				(mid 1.394159 -182.107451)
				(end 1.645158 -182.112158)
			)
			(arc
				(start 1.645158 -182.112158)
				(mid 1.836287 -182.044923)
				(end 2.038858 -182.041292)
			)
			(arc
				(start 2.038858 -182.041292)
				(mid 2.096939 -182.0361)
				(end 2.146554 -182.005478)
			)
			(xy 2.330704 -181.821328) (xy 2.330704 -162.4457)
			(arc
				(start 1.703578 -161.818574)
				(mid 1.426813 -161.763522)
				(end 1.27 -161.998152)
			)
		)
		(stroke
			(width 0)
			(type solid)
		)
		(fill yes)
		(layer "F.Cu")
		(net "P12V")
	)
	(gr_poly
		(pts
			(xy 83.003644 -430.150016) (xy 83.003143 -430.049886) (xy 82.995131 -429.849786) (xy 82.979119 -429.650167)
			(xy 82.955133 -429.451348) (xy 82.923212 -429.253649) (xy 82.883407 -429.057384) (xy 82.835781 -428.86287)
			(xy 82.78041 -428.670416) (xy 82.717384 -428.480333) (xy 82.646804 -428.292923) (xy 82.568781 -428.108487)
			(xy 82.483442 -427.92732) (xy 82.390923 -427.749713) (xy 82.291372 -427.575949) (xy 82.184948 -427.406308)
			(xy 82.071822 -427.24106) (xy 81.952176 -427.080471) (xy 81.8262 -426.924798) (xy 81.694096 -426.774289)
			(xy 81.556077 -426.629187) (xy 81.412362 -426.489723) (xy 81.263183 -426.35612) (xy 81.108778 -426.228593)
			(xy 80.949394 -426.107345) (xy 80.785286 -425.992572) (xy 80.616718 -425.884457) (xy 80.44396 -425.783172)
			(xy 80.267287 -425.68888) (xy 80.086983 -425.601733) (xy 79.903337 -425.521869) (xy 79.716642 -425.449417)
			(xy 79.527199 -425.384492) (xy 79.335309 -425.327199) (xy 79.141281 -425.277629) (xy 78.945424 -425.235862)
			(xy 78.748054 -425.201965) (xy 78.549485 -425.175991) (xy 78.350036 -425.157983) (xy 78.150027 -425.147969)
			(xy 77.949776 -425.145965) (xy 77.749606 -425.151975) (xy 77.549837 -425.165989) (xy 77.350789 -425.187985)
			(xy 77.152779 -425.217926) (xy 76.956127 -425.255766) (xy 76.761145 -425.301444) (xy 76.568148 -425.354886)
			(xy 76.377443 -425.416007) (xy 76.189336 -425.484709) (xy 76.004129 -425.560882) (xy 75.822117 -425.644405)
			(xy 75.643593 -425.735142) (xy 75.468842 -425.83295) (xy 75.298145 -425.937671) (xy 75.131774 -426.049138)
			(xy 74.969996 -426.167172) (xy 74.81307 -426.291584) (xy 74.661247 -426.422175) (xy 74.514771 -426.558736)
			(xy 74.373876 -426.701048) (xy 74.238787 -426.848883) (xy 74.109722 -427.002005) (xy 73.986886 -427.160167)
			(xy 73.870476 -427.323118) (xy 73.76068 -427.490596) (xy 73.657672 -427.662333) (xy 73.561617 -427.838053)
			(xy 73.47267 -428.017476) (xy 73.390973 -428.200314) (xy 73.316657 -428.386275) (xy 73.24984 -428.575059)
			(xy 73.19063 -428.766366) (xy 73.139121 -428.959889) (xy 73.095397 -429.155317) (xy 73.059526 -429.352339)
			(xy 73.031567 -429.550638) (xy 73.011564 -429.749896) (xy 72.99955 -429.949796) (xy 72.995543 -430.150016)
			(xy 75.484741 -430.150016) (xy 75.488769 -430.007724) (xy 75.500841 -429.865888) (xy 75.520918 -429.724961)
			(xy 75.548936 -429.585397) (xy 75.584805 -429.447641) (xy 75.62841 -429.312135) (xy 75.679611 -429.179313)
			(xy 75.738245 -429.0496) (xy 75.804123 -428.923413) (xy 75.877035 -428.801154) (xy 75.956747 -428.683217)
			(xy 76.043004 -428.569978) (xy 76.135528 -428.4618) (xy 76.234025 -428.35903) (xy 76.338179 -428.261997)
			(xy 76.447655 -428.171013) (xy 76.562103 -428.086367) (xy 76.681157 -428.008332) (xy 76.804435 -427.937158)
			(xy 76.931542 -427.873071) (xy 77.062071 -427.816279) (xy 77.195605 -427.766962) (xy 77.331714 -427.725279)
			(xy 77.469964 -427.691363) (xy 77.609911 -427.665323) (xy 77.751107 -427.647242) (xy 77.8931 -427.637179)
			(xy 78.035435 -427.635164) (xy 78.177656 -427.641206) (xy 78.319307 -427.655284) (xy 78.459935 -427.677353)
			(xy 78.599089 -427.707343) (xy 78.736324 -427.745158) (xy 78.871199 -427.790676) (xy 79.003283 -427.843752)
			(xy 79.132153 -427.904215) (xy 79.257396 -427.971872) (xy 79.37861 -428.046507) (xy 79.495408 -428.12788)
			(xy 79.607415 -428.21573) (xy 79.714273 -428.309777) (xy 79.815638 -428.409718) (xy 79.911187 -428.515234)
			(xy 80.000614 -428.625987) (xy 80.083632 -428.741621) (xy 80.159974 -428.861768) (xy 80.229397 -428.98604)
			(xy 80.291678 -429.114042) (xy 80.346618 -429.245362) (xy 80.39404 -429.379579) (xy 80.433793 -429.516265)
			(xy 80.465749 -429.654981) (xy 80.489806 -429.795282) (xy 80.505887 -429.93672) (xy 80.51394 -430.078841)
			(xy 80.514444 -430.150016) (xy 80.51394 -430.221191) (xy 80.505887 -430.363312) (xy 80.489806 -430.50475)
			(xy 80.465749 -430.645051) (xy 80.433793 -430.783767) (xy 80.39404 -430.920453) (xy 80.346618 -431.05467)
			(xy 80.291678 -431.18599) (xy 80.229397 -431.313992) (xy 80.159974 -431.438264) (xy 80.083632 -431.558411)
			(xy 80.000614 -431.674045) (xy 79.911187 -431.784798) (xy 79.815638 -431.890314) (xy 79.714273 -431.990255)
			(xy 79.607415 -432.084302) (xy 79.495408 -432.172152) (xy 79.37861 -432.253525) (xy 79.257396 -432.32816)
			(xy 79.132153 -432.395817) (xy 79.003283 -432.45628) (xy 78.871199 -432.509356) (xy 78.736324 -432.554874)
			(xy 78.599089 -432.592689) (xy 78.459935 -432.622679) (xy 78.319307 -432.644748) (xy 78.177656 -432.658826)
			(xy 78.035435 -432.664868) (xy 77.8931 -432.662853) (xy 77.751107 -432.65279) (xy 77.609911 -432.634709)
			(xy 77.469964 -432.608669) (xy 77.331714 -432.574753) (xy 77.195605 -432.53307) (xy 77.062071 -432.483753)
			(xy 76.931542 -432.426961) (xy 76.804435 -432.362874) (xy 76.681157 -432.2917) (xy 76.562103 -432.213665)
			(xy 76.447655 -432.129019) (xy 76.338179 -432.038035) (xy 76.234025 -431.941002) (xy 76.135528 -431.838232)
			(xy 76.043004 -431.730054) (xy 75.956747 -431.616815) (xy 75.877035 -431.498878) (xy 75.804123 -431.376619)
			(xy 75.738245 -431.250432) (xy 75.679611 -431.120719) (xy 75.62841 -430.987897) (xy 75.584805 -430.852391)
			(xy 75.548936 -430.714635) (xy 75.520918 -430.575071) (xy 75.500841 -430.434144) (xy 75.488769 -430.292308)
			(xy 75.484741 -430.150016) (xy 72.995543 -430.150016) (xy 72.99955 -430.350236) (xy 73.011564 -430.550136)
			(xy 73.031567 -430.749394) (xy 73.059526 -430.947693) (xy 73.095397 -431.144715) (xy 73.139121 -431.340143)
			(xy 73.19063 -431.533666) (xy 73.24984 -431.724973) (xy 73.316657 -431.913757) (xy 73.390973 -432.099718)
			(xy 73.47267 -432.282556) (xy 73.561617 -432.461979) (xy 73.657672 -432.637699) (xy 73.76068 -432.809436)
			(xy 73.870476 -432.976914) (xy 73.986886 -433.139865) (xy 74.109722 -433.298027) (xy 74.238787 -433.451149)
			(xy 74.373876 -433.598984) (xy 74.514771 -433.741296) (xy 74.661247 -433.877857) (xy 74.81307 -434.008448)
			(xy 74.969996 -434.13286) (xy 75.131774 -434.250894) (xy 75.298145 -434.362361) (xy 75.468842 -434.467082)
			(xy 75.643593 -434.56489) (xy 75.822117 -434.655627) (xy 76.004129 -434.73915) (xy 76.189336 -434.815323)
			(xy 76.377443 -434.884025) (xy 76.568148 -434.945146) (xy 76.761145 -434.998588) (xy 76.956127 -435.044266)
			(xy 77.152779 -435.082106) (xy 77.350789 -435.112047) (xy 77.549837 -435.134043) (xy 77.749606 -435.148057)
			(xy 77.949776 -435.154067) (xy 78.150027 -435.152063) (xy 78.350036 -435.142049) (xy 78.549485 -435.124041)
			(xy 78.748054 -435.098067) (xy 78.945424 -435.06417) (xy 79.141281 -435.022403) (xy 79.335309 -434.972833)
			(xy 79.527199 -434.91554) (xy 79.716642 -434.850615) (xy 79.903337 -434.778163) (xy 80.086983 -434.698299)
			(xy 80.267287 -434.611152) (xy 80.44396 -434.51686) (xy 80.616718 -434.415575) (xy 80.785286 -434.30746)
			(xy 80.949394 -434.192687) (xy 81.108778 -434.071439) (xy 81.263183 -433.943912) (xy 81.412362 -433.810309)
			(xy 81.556077 -433.670845) (xy 81.694096 -433.525743) (xy 81.8262 -433.375234) (xy 81.952176 -433.219561)
			(xy 82.071822 -433.058972) (xy 82.184948 -432.893724) (xy 82.291372 -432.724083) (xy 82.390923 -432.550319)
			(xy 82.483442 -432.372712) (xy 82.568781 -432.191545) (xy 82.646804 -432.007109) (xy 82.717384 -431.819699)
			(xy 82.78041 -431.629616) (xy 82.835781 -431.437162) (xy 82.883407 -431.242648) (xy 82.923212 -431.046383)
			(xy 82.955133 -430.848684) (xy 82.979119 -430.649865) (xy 82.995131 -430.450246) (xy 83.003143 -430.250146)
		)
		(stroke
			(width 0)
			(type solid)
		)
		(fill yes)
		(layer "F.Cu")
		(net "GND")
	)
	(gr_poly
		(pts
			(xy 83.003644 -341.250016) (xy 83.003143 -341.149886) (xy 82.995131 -340.949786) (xy 82.979119 -340.750167)
			(xy 82.955133 -340.551348) (xy 82.923212 -340.353649) (xy 82.883407 -340.157384) (xy 82.835781 -339.96287)
			(xy 82.78041 -339.770416) (xy 82.717384 -339.580333) (xy 82.646804 -339.392923) (xy 82.568781 -339.208487)
			(xy 82.483442 -339.02732) (xy 82.390923 -338.849713) (xy 82.291372 -338.675949) (xy 82.184948 -338.506308)
			(xy 82.071822 -338.34106) (xy 81.952176 -338.180471) (xy 81.8262 -338.024798) (xy 81.694096 -337.874289)
			(xy 81.556077 -337.729187) (xy 81.412362 -337.589723) (xy 81.263183 -337.45612) (xy 81.108778 -337.328593)
			(xy 80.949394 -337.207345) (xy 80.785286 -337.092572) (xy 80.616718 -336.984457) (xy 80.44396 -336.883172)
			(xy 80.267287 -336.78888) (xy 80.086983 -336.701733) (xy 79.903337 -336.621869) (xy 79.716642 -336.549417)
			(xy 79.527199 -336.484492) (xy 79.335309 -336.427199) (xy 79.141281 -336.377629) (xy 78.945424 -336.335862)
			(xy 78.748054 -336.301965) (xy 78.549485 -336.275991) (xy 78.350036 -336.257983) (xy 78.150027 -336.247969)
			(xy 77.949776 -336.245965) (xy 77.749606 -336.251975) (xy 77.549837 -336.265989) (xy 77.350789 -336.287985)
			(xy 77.152779 -336.317926) (xy 76.956127 -336.355766) (xy 76.761145 -336.401444) (xy 76.568148 -336.454886)
			(xy 76.377443 -336.516007) (xy 76.189336 -336.584709) (xy 76.004129 -336.660882) (xy 75.822117 -336.744405)
			(xy 75.643593 -336.835142) (xy 75.468842 -336.93295) (xy 75.298145 -337.037671) (xy 75.131774 -337.149138)
			(xy 74.969996 -337.267172) (xy 74.81307 -337.391584) (xy 74.661247 -337.522175) (xy 74.514771 -337.658736)
			(xy 74.373876 -337.801048) (xy 74.238787 -337.948883) (xy 74.109722 -338.102005) (xy 73.986886 -338.260167)
			(xy 73.870476 -338.423118) (xy 73.76068 -338.590596) (xy 73.657672 -338.762333) (xy 73.561617 -338.938053)
			(xy 73.47267 -339.117476) (xy 73.390973 -339.300314) (xy 73.316657 -339.486275) (xy 73.24984 -339.675059)
			(xy 73.19063 -339.866366) (xy 73.139121 -340.059889) (xy 73.095397 -340.255317) (xy 73.059526 -340.452339)
			(xy 73.031567 -340.650638) (xy 73.011564 -340.849896) (xy 72.99955 -341.049796) (xy 72.995543 -341.250016)
			(xy 75.484741 -341.250016) (xy 75.488769 -341.107724) (xy 75.500841 -340.965888) (xy 75.520918 -340.824961)
			(xy 75.548936 -340.685397) (xy 75.584805 -340.547641) (xy 75.62841 -340.412135) (xy 75.679611 -340.279313)
			(xy 75.738245 -340.1496) (xy 75.804123 -340.023413) (xy 75.877035 -339.901154) (xy 75.956747 -339.783217)
			(xy 76.043004 -339.669978) (xy 76.135528 -339.5618) (xy 76.234025 -339.45903) (xy 76.338179 -339.361997)
			(xy 76.447655 -339.271013) (xy 76.562103 -339.186367) (xy 76.681157 -339.108332) (xy 76.804435 -339.037158)
			(xy 76.931542 -338.973071) (xy 77.062071 -338.916279) (xy 77.195605 -338.866962) (xy 77.331714 -338.825279)
			(xy 77.469964 -338.791363) (xy 77.609911 -338.765323) (xy 77.751107 -338.747242) (xy 77.8931 -338.737179)
			(xy 78.035435 -338.735164) (xy 78.177656 -338.741206) (xy 78.319307 -338.755284) (xy 78.459935 -338.777353)
			(xy 78.599089 -338.807343) (xy 78.736324 -338.845158) (xy 78.871199 -338.890676) (xy 79.003283 -338.943752)
			(xy 79.132153 -339.004215) (xy 79.257396 -339.071872) (xy 79.37861 -339.146507) (xy 79.495408 -339.22788)
			(xy 79.607415 -339.31573) (xy 79.714273 -339.409777) (xy 79.815638 -339.509718) (xy 79.911187 -339.615234)
			(xy 80.000614 -339.725987) (xy 80.083632 -339.841621) (xy 80.159974 -339.961768) (xy 80.229397 -340.08604)
			(xy 80.291678 -340.214042) (xy 80.346618 -340.345362) (xy 80.39404 -340.479579) (xy 80.433793 -340.616265)
			(xy 80.465749 -340.754981) (xy 80.489806 -340.895282) (xy 80.505887 -341.03672) (xy 80.51394 -341.178841)
			(xy 80.514444 -341.250016) (xy 80.51394 -341.321191) (xy 80.505887 -341.463312) (xy 80.489806 -341.60475)
			(xy 80.465749 -341.745051) (xy 80.433793 -341.883767) (xy 80.39404 -342.020453) (xy 80.346618 -342.15467)
			(xy 80.291678 -342.28599) (xy 80.229397 -342.413992) (xy 80.159974 -342.538264) (xy 80.083632 -342.658411)
			(xy 80.000614 -342.774045) (xy 79.911187 -342.884798) (xy 79.815638 -342.990314) (xy 79.714273 -343.090255)
			(xy 79.607415 -343.184302) (xy 79.495408 -343.272152) (xy 79.37861 -343.353525) (xy 79.257396 -343.42816)
			(xy 79.132153 -343.495817) (xy 79.003283 -343.55628) (xy 78.871199 -343.609356) (xy 78.736324 -343.654874)
			(xy 78.599089 -343.692689) (xy 78.459935 -343.722679) (xy 78.319307 -343.744748) (xy 78.177656 -343.758826)
			(xy 78.035435 -343.764868) (xy 77.8931 -343.762853) (xy 77.751107 -343.75279) (xy 77.609911 -343.734709)
			(xy 77.469964 -343.708669) (xy 77.331714 -343.674753) (xy 77.195605 -343.63307) (xy 77.062071 -343.583753)
			(xy 76.931542 -343.526961) (xy 76.804435 -343.462874) (xy 76.681157 -343.3917) (xy 76.562103 -343.313665)
			(xy 76.447655 -343.229019) (xy 76.338179 -343.138035) (xy 76.234025 -343.041002) (xy 76.135528 -342.938232)
			(xy 76.043004 -342.830054) (xy 75.956747 -342.716815) (xy 75.877035 -342.598878) (xy 75.804123 -342.476619)
			(xy 75.738245 -342.350432) (xy 75.679611 -342.220719) (xy 75.62841 -342.087897) (xy 75.584805 -341.952391)
			(xy 75.548936 -341.814635) (xy 75.520918 -341.675071) (xy 75.500841 -341.534144) (xy 75.488769 -341.392308)
			(xy 75.484741 -341.250016) (xy 72.995543 -341.250016) (xy 72.99955 -341.450236) (xy 73.011564 -341.650136)
			(xy 73.031567 -341.849394) (xy 73.059526 -342.047693) (xy 73.095397 -342.244715) (xy 73.139121 -342.440143)
			(xy 73.19063 -342.633666) (xy 73.24984 -342.824973) (xy 73.316657 -343.013757) (xy 73.390973 -343.199718)
			(xy 73.47267 -343.382556) (xy 73.561617 -343.561979) (xy 73.657672 -343.737699) (xy 73.76068 -343.909436)
			(xy 73.870476 -344.076914) (xy 73.986886 -344.239865) (xy 74.109722 -344.398027) (xy 74.238787 -344.551149)
			(xy 74.373876 -344.698984) (xy 74.514771 -344.841296) (xy 74.661247 -344.977857) (xy 74.81307 -345.108448)
			(xy 74.969996 -345.23286) (xy 75.131774 -345.350894) (xy 75.298145 -345.462361) (xy 75.468842 -345.567082)
			(xy 75.643593 -345.66489) (xy 75.822117 -345.755627) (xy 76.004129 -345.83915) (xy 76.189336 -345.915323)
			(xy 76.377443 -345.984025) (xy 76.568148 -346.045146) (xy 76.761145 -346.098588) (xy 76.956127 -346.144266)
			(xy 77.152779 -346.182106) (xy 77.350789 -346.212047) (xy 77.549837 -346.234043) (xy 77.749606 -346.248057)
			(xy 77.949776 -346.254067) (xy 78.150027 -346.252063) (xy 78.350036 -346.242049) (xy 78.549485 -346.224041)
			(xy 78.748054 -346.198067) (xy 78.945424 -346.16417) (xy 79.141281 -346.122403) (xy 79.335309 -346.072833)
			(xy 79.527199 -346.01554) (xy 79.716642 -345.950615) (xy 79.903337 -345.878163) (xy 80.086983 -345.798299)
			(xy 80.267287 -345.711152) (xy 80.44396 -345.61686) (xy 80.616718 -345.515575) (xy 80.785286 -345.40746)
			(xy 80.949394 -345.292687) (xy 81.108778 -345.171439) (xy 81.263183 -345.043912) (xy 81.412362 -344.910309)
			(xy 81.556077 -344.770845) (xy 81.694096 -344.625743) (xy 81.8262 -344.475234) (xy 81.952176 -344.319561)
			(xy 82.071822 -344.158972) (xy 82.184948 -343.993724) (xy 82.291372 -343.824083) (xy 82.390923 -343.650319)
			(xy 82.483442 -343.472712) (xy 82.568781 -343.291545) (xy 82.646804 -343.107109) (xy 82.717384 -342.919699)
			(xy 82.78041 -342.729616) (xy 82.835781 -342.537162) (xy 82.883407 -342.342648) (xy 82.923212 -342.146383)
			(xy 82.955133 -341.948684) (xy 82.979119 -341.749865) (xy 82.995131 -341.550246) (xy 83.003143 -341.350146)
		)
		(stroke
			(width 0)
			(type solid)
		)
		(fill yes)
		(layer "F.Cu")
		(net "GND")
	)
	(gr_poly
		(pts
			(xy 83.003644 -210.09991) (xy 83.003143 -209.99978) (xy 82.995131 -209.79968) (xy 82.979119 -209.600061)
			(xy 82.955133 -209.401242) (xy 82.923212 -209.203543) (xy 82.883407 -209.007278) (xy 82.835781 -208.812764)
			(xy 82.78041 -208.62031) (xy 82.717384 -208.430227) (xy 82.646804 -208.242817) (xy 82.568781 -208.058381)
			(xy 82.483442 -207.877214) (xy 82.390923 -207.699607) (xy 82.291372 -207.525843) (xy 82.184948 -207.356202)
			(xy 82.071822 -207.190954) (xy 81.952176 -207.030365) (xy 81.8262 -206.874692) (xy 81.694096 -206.724183)
			(xy 81.556077 -206.579081) (xy 81.412362 -206.439617) (xy 81.263183 -206.306014) (xy 81.108778 -206.178487)
			(xy 80.949394 -206.057239) (xy 80.785286 -205.942466) (xy 80.616718 -205.834351) (xy 80.44396 -205.733066)
			(xy 80.267287 -205.638774) (xy 80.086983 -205.551627) (xy 79.903337 -205.471763) (xy 79.716642 -205.399311)
			(xy 79.527199 -205.334386) (xy 79.335309 -205.277093) (xy 79.141281 -205.227523) (xy 78.945424 -205.185756)
			(xy 78.748054 -205.151859) (xy 78.549485 -205.125885) (xy 78.350036 -205.107877) (xy 78.150027 -205.097863)
			(xy 77.949776 -205.095859) (xy 77.749606 -205.101869) (xy 77.549837 -205.115883) (xy 77.350789 -205.137879)
			(xy 77.152779 -205.16782) (xy 76.956127 -205.20566) (xy 76.761145 -205.251338) (xy 76.568148 -205.30478)
			(xy 76.377443 -205.365901) (xy 76.189336 -205.434603) (xy 76.004129 -205.510776) (xy 75.822117 -205.594299)
			(xy 75.643593 -205.685036) (xy 75.468842 -205.782844) (xy 75.298145 -205.887565) (xy 75.131774 -205.999032)
			(xy 74.969996 -206.117066) (xy 74.81307 -206.241478) (xy 74.661247 -206.372069) (xy 74.514771 -206.50863)
			(xy 74.373876 -206.650942) (xy 74.238787 -206.798777) (xy 74.109722 -206.951899) (xy 73.986886 -207.110061)
			(xy 73.870476 -207.273012) (xy 73.76068 -207.44049) (xy 73.657672 -207.612227) (xy 73.561617 -207.787947)
			(xy 73.47267 -207.96737) (xy 73.390973 -208.150208) (xy 73.316657 -208.336169) (xy 73.24984 -208.524953)
			(xy 73.19063 -208.71626) (xy 73.139121 -208.909783) (xy 73.095397 -209.105211) (xy 73.059526 -209.302233)
			(xy 73.031567 -209.500532) (xy 73.011564 -209.69979) (xy 72.99955 -209.89969) (xy 72.995543 -210.09991)
			(xy 75.484741 -210.09991) (xy 75.488769 -209.957618) (xy 75.500841 -209.815782) (xy 75.520918 -209.674855)
			(xy 75.548936 -209.535291) (xy 75.584805 -209.397535) (xy 75.62841 -209.262029) (xy 75.679611 -209.129207)
			(xy 75.738245 -208.999494) (xy 75.804123 -208.873307) (xy 75.877035 -208.751048) (xy 75.956747 -208.633111)
			(xy 76.043004 -208.519872) (xy 76.135528 -208.411694) (xy 76.234025 -208.308924) (xy 76.338179 -208.211891)
			(xy 76.447655 -208.120907) (xy 76.562103 -208.036261) (xy 76.681157 -207.958226) (xy 76.804435 -207.887052)
			(xy 76.931542 -207.822965) (xy 77.062071 -207.766173) (xy 77.195605 -207.716856) (xy 77.331714 -207.675173)
			(xy 77.469964 -207.641257) (xy 77.609911 -207.615217) (xy 77.751107 -207.597136) (xy 77.8931 -207.587073)
			(xy 78.035435 -207.585058) (xy 78.177656 -207.5911) (xy 78.319307 -207.605178) (xy 78.459935 -207.627247)
			(xy 78.599089 -207.657237) (xy 78.736324 -207.695052) (xy 78.871199 -207.74057) (xy 79.003283 -207.793646)
			(xy 79.132153 -207.854109) (xy 79.257396 -207.921766) (xy 79.37861 -207.996401) (xy 79.495408 -208.077774)
			(xy 79.607415 -208.165624) (xy 79.714273 -208.259671) (xy 79.815638 -208.359612) (xy 79.911187 -208.465128)
			(xy 80.000614 -208.575881) (xy 80.083632 -208.691515) (xy 80.159974 -208.811662) (xy 80.229397 -208.935934)
			(xy 80.291678 -209.063936) (xy 80.346618 -209.195256) (xy 80.39404 -209.329473) (xy 80.433793 -209.466159)
			(xy 80.465749 -209.604875) (xy 80.489806 -209.745176) (xy 80.505887 -209.886614) (xy 80.51394 -210.028735)
			(xy 80.514444 -210.09991) (xy 80.51394 -210.171085) (xy 80.505887 -210.313206) (xy 80.489806 -210.454644)
			(xy 80.465749 -210.594945) (xy 80.433793 -210.733661) (xy 80.39404 -210.870347) (xy 80.346618 -211.004564)
			(xy 80.291678 -211.135884) (xy 80.229397 -211.263886) (xy 80.159974 -211.388158) (xy 80.083632 -211.508305)
			(xy 80.000614 -211.623939) (xy 79.911187 -211.734692) (xy 79.815638 -211.840208) (xy 79.714273 -211.940149)
			(xy 79.607415 -212.034196) (xy 79.495408 -212.122046) (xy 79.37861 -212.203419) (xy 79.257396 -212.278054)
			(xy 79.132153 -212.345711) (xy 79.003283 -212.406174) (xy 78.871199 -212.45925) (xy 78.736324 -212.504768)
			(xy 78.599089 -212.542583) (xy 78.459935 -212.572573) (xy 78.319307 -212.594642) (xy 78.177656 -212.60872)
			(xy 78.035435 -212.614762) (xy 77.8931 -212.612747) (xy 77.751107 -212.602684) (xy 77.609911 -212.584603)
			(xy 77.469964 -212.558563) (xy 77.331714 -212.524647) (xy 77.195605 -212.482964) (xy 77.062071 -212.433647)
			(xy 76.931542 -212.376855) (xy 76.804435 -212.312768) (xy 76.681157 -212.241594) (xy 76.562103 -212.163559)
			(xy 76.447655 -212.078913) (xy 76.338179 -211.987929) (xy 76.234025 -211.890896) (xy 76.135528 -211.788126)
			(xy 76.043004 -211.679948) (xy 75.956747 -211.566709) (xy 75.877035 -211.448772) (xy 75.804123 -211.326513)
			(xy 75.738245 -211.200326) (xy 75.679611 -211.070613) (xy 75.62841 -210.937791) (xy 75.584805 -210.802285)
			(xy 75.548936 -210.664529) (xy 75.520918 -210.524965) (xy 75.500841 -210.384038) (xy 75.488769 -210.242202)
			(xy 75.484741 -210.09991) (xy 72.995543 -210.09991) (xy 72.99955 -210.30013) (xy 73.011564 -210.50003)
			(xy 73.031567 -210.699288) (xy 73.059526 -210.897587) (xy 73.095397 -211.094609) (xy 73.139121 -211.290037)
			(xy 73.19063 -211.48356) (xy 73.24984 -211.674867) (xy 73.316657 -211.863651) (xy 73.390973 -212.049612)
			(xy 73.47267 -212.23245) (xy 73.561617 -212.411873) (xy 73.657672 -212.587593) (xy 73.76068 -212.75933)
			(xy 73.870476 -212.926808) (xy 73.986886 -213.089759) (xy 74.109722 -213.247921) (xy 74.238787 -213.401043)
			(xy 74.373876 -213.548878) (xy 74.514771 -213.69119) (xy 74.661247 -213.827751) (xy 74.81307 -213.958342)
			(xy 74.969996 -214.082754) (xy 75.131774 -214.200788) (xy 75.298145 -214.312255) (xy 75.468842 -214.416976)
			(xy 75.643593 -214.514784) (xy 75.822117 -214.605521) (xy 76.004129 -214.689044) (xy 76.189336 -214.765217)
			(xy 76.377443 -214.833919) (xy 76.568148 -214.89504) (xy 76.761145 -214.948482) (xy 76.956127 -214.99416)
			(xy 77.152779 -215.032) (xy 77.350789 -215.061941) (xy 77.549837 -215.083937) (xy 77.749606 -215.097951)
			(xy 77.949776 -215.103961) (xy 78.150027 -215.101957) (xy 78.350036 -215.091943) (xy 78.549485 -215.073935)
			(xy 78.748054 -215.047961) (xy 78.945424 -215.014064) (xy 79.141281 -214.972297) (xy 79.335309 -214.922727)
			(xy 79.527199 -214.865434) (xy 79.716642 -214.800509) (xy 79.903337 -214.728057) (xy 80.086983 -214.648193)
			(xy 80.267287 -214.561046) (xy 80.44396 -214.466754) (xy 80.616718 -214.365469) (xy 80.785286 -214.257354)
			(xy 80.949394 -214.142581) (xy 81.108778 -214.021333) (xy 81.263183 -213.893806) (xy 81.412362 -213.760203)
			(xy 81.556077 -213.620739) (xy 81.694096 -213.475637) (xy 81.8262 -213.325128) (xy 81.952176 -213.169455)
			(xy 82.071822 -213.008866) (xy 82.184948 -212.843618) (xy 82.291372 -212.673977) (xy 82.390923 -212.500213)
			(xy 82.483442 -212.322606) (xy 82.568781 -212.141439) (xy 82.646804 -211.957003) (xy 82.717384 -211.769593)
			(xy 82.78041 -211.57951) (xy 82.835781 -211.387056) (xy 82.883407 -211.192542) (xy 82.923212 -210.996277)
			(xy 82.955133 -210.798578) (xy 82.979119 -210.599759) (xy 82.995131 -210.40014) (xy 83.003143 -210.20004)
		)
		(stroke
			(width 0)
			(type solid)
		)
		(fill yes)
		(layer "F.Cu")
		(net "GND")
	)
	(gr_poly
		(pts
			(xy 83.003644 -121.19991) (xy 83.003143 -121.09978) (xy 82.995131 -120.89968) (xy 82.979119 -120.700061)
			(xy 82.955133 -120.501242) (xy 82.923212 -120.303543) (xy 82.883407 -120.107278) (xy 82.835781 -119.912764)
			(xy 82.78041 -119.72031) (xy 82.717384 -119.530227) (xy 82.646804 -119.342817) (xy 82.568781 -119.158381)
			(xy 82.483442 -118.977214) (xy 82.390923 -118.799607) (xy 82.291372 -118.625843) (xy 82.184948 -118.456202)
			(xy 82.071822 -118.290954) (xy 81.952176 -118.130365) (xy 81.8262 -117.974692) (xy 81.694096 -117.824183)
			(xy 81.556077 -117.679081) (xy 81.412362 -117.539617) (xy 81.263183 -117.406014) (xy 81.108778 -117.278487)
			(xy 80.949394 -117.157239) (xy 80.785286 -117.042466) (xy 80.616718 -116.934351) (xy 80.44396 -116.833066)
			(xy 80.267287 -116.738774) (xy 80.086983 -116.651627) (xy 79.903337 -116.571763) (xy 79.716642 -116.499311)
			(xy 79.527199 -116.434386) (xy 79.335309 -116.377093) (xy 79.141281 -116.327523) (xy 78.945424 -116.285756)
			(xy 78.748054 -116.251859) (xy 78.549485 -116.225885) (xy 78.350036 -116.207877) (xy 78.150027 -116.197863)
			(xy 77.949776 -116.195859) (xy 77.749606 -116.201869) (xy 77.549837 -116.215883) (xy 77.350789 -116.237879)
			(xy 77.152779 -116.26782) (xy 76.956127 -116.30566) (xy 76.761145 -116.351338) (xy 76.568148 -116.40478)
			(xy 76.377443 -116.465901) (xy 76.189336 -116.534603) (xy 76.004129 -116.610776) (xy 75.822117 -116.694299)
			(xy 75.643593 -116.785036) (xy 75.468842 -116.882844) (xy 75.298145 -116.987565) (xy 75.131774 -117.099032)
			(xy 74.969996 -117.217066) (xy 74.81307 -117.341478) (xy 74.661247 -117.472069) (xy 74.514771 -117.60863)
			(xy 74.373876 -117.750942) (xy 74.238787 -117.898777) (xy 74.109722 -118.051899) (xy 73.986886 -118.210061)
			(xy 73.870476 -118.373012) (xy 73.76068 -118.54049) (xy 73.657672 -118.712227) (xy 73.561617 -118.887947)
			(xy 73.47267 -119.06737) (xy 73.390973 -119.250208) (xy 73.316657 -119.436169) (xy 73.24984 -119.624953)
			(xy 73.19063 -119.81626) (xy 73.139121 -120.009783) (xy 73.095397 -120.205211) (xy 73.059526 -120.402233)
			(xy 73.031567 -120.600532) (xy 73.011564 -120.79979) (xy 72.99955 -120.99969) (xy 72.995543 -121.19991)
			(xy 75.484741 -121.19991) (xy 75.488769 -121.057618) (xy 75.500841 -120.915782) (xy 75.520918 -120.774855)
			(xy 75.548936 -120.635291) (xy 75.584805 -120.497535) (xy 75.62841 -120.362029) (xy 75.679611 -120.229207)
			(xy 75.738245 -120.099494) (xy 75.804123 -119.973307) (xy 75.877035 -119.851048) (xy 75.956747 -119.733111)
			(xy 76.043004 -119.619872) (xy 76.135528 -119.511694) (xy 76.234025 -119.408924) (xy 76.338179 -119.311891)
			(xy 76.447655 -119.220907) (xy 76.562103 -119.136261) (xy 76.681157 -119.058226) (xy 76.804435 -118.987052)
			(xy 76.931542 -118.922965) (xy 77.062071 -118.866173) (xy 77.195605 -118.816856) (xy 77.331714 -118.775173)
			(xy 77.469964 -118.741257) (xy 77.609911 -118.715217) (xy 77.751107 -118.697136) (xy 77.8931 -118.687073)
			(xy 78.035435 -118.685058) (xy 78.177656 -118.6911) (xy 78.319307 -118.705178) (xy 78.459935 -118.727247)
			(xy 78.599089 -118.757237) (xy 78.736324 -118.795052) (xy 78.871199 -118.84057) (xy 79.003283 -118.893646)
			(xy 79.132153 -118.954109) (xy 79.257396 -119.021766) (xy 79.37861 -119.096401) (xy 79.495408 -119.177774)
			(xy 79.607415 -119.265624) (xy 79.714273 -119.359671) (xy 79.815638 -119.459612) (xy 79.911187 -119.565128)
			(xy 80.000614 -119.675881) (xy 80.083632 -119.791515) (xy 80.159974 -119.911662) (xy 80.229397 -120.035934)
			(xy 80.291678 -120.163936) (xy 80.346618 -120.295256) (xy 80.39404 -120.429473) (xy 80.433793 -120.566159)
			(xy 80.465749 -120.704875) (xy 80.489806 -120.845176) (xy 80.505887 -120.986614) (xy 80.51394 -121.128735)
			(xy 80.514444 -121.19991) (xy 80.51394 -121.271085) (xy 80.505887 -121.413206) (xy 80.489806 -121.554644)
			(xy 80.465749 -121.694945) (xy 80.433793 -121.833661) (xy 80.39404 -121.970347) (xy 80.346618 -122.104564)
			(xy 80.291678 -122.235884) (xy 80.229397 -122.363886) (xy 80.159974 -122.488158) (xy 80.083632 -122.608305)
			(xy 80.000614 -122.723939) (xy 79.911187 -122.834692) (xy 79.815638 -122.940208) (xy 79.714273 -123.040149)
			(xy 79.607415 -123.134196) (xy 79.495408 -123.222046) (xy 79.37861 -123.303419) (xy 79.257396 -123.378054)
			(xy 79.132153 -123.445711) (xy 79.003283 -123.506174) (xy 78.871199 -123.55925) (xy 78.736324 -123.604768)
			(xy 78.599089 -123.642583) (xy 78.459935 -123.672573) (xy 78.319307 -123.694642) (xy 78.177656 -123.70872)
			(xy 78.035435 -123.714762) (xy 77.8931 -123.712747) (xy 77.751107 -123.702684) (xy 77.609911 -123.684603)
			(xy 77.469964 -123.658563) (xy 77.331714 -123.624647) (xy 77.195605 -123.582964) (xy 77.062071 -123.533647)
			(xy 76.931542 -123.476855) (xy 76.804435 -123.412768) (xy 76.681157 -123.341594) (xy 76.562103 -123.263559)
			(xy 76.447655 -123.178913) (xy 76.338179 -123.087929) (xy 76.234025 -122.990896) (xy 76.135528 -122.888126)
			(xy 76.043004 -122.779948) (xy 75.956747 -122.666709) (xy 75.877035 -122.548772) (xy 75.804123 -122.426513)
			(xy 75.738245 -122.300326) (xy 75.679611 -122.170613) (xy 75.62841 -122.037791) (xy 75.584805 -121.902285)
			(xy 75.548936 -121.764529) (xy 75.520918 -121.624965) (xy 75.500841 -121.484038) (xy 75.488769 -121.342202)
			(xy 75.484741 -121.19991) (xy 72.995543 -121.19991) (xy 72.99955 -121.40013) (xy 73.011564 -121.60003)
			(xy 73.031567 -121.799288) (xy 73.059526 -121.997587) (xy 73.095397 -122.194609) (xy 73.139121 -122.390037)
			(xy 73.19063 -122.58356) (xy 73.24984 -122.774867) (xy 73.316657 -122.963651) (xy 73.390973 -123.149612)
			(xy 73.47267 -123.33245) (xy 73.561617 -123.511873) (xy 73.657672 -123.687593) (xy 73.76068 -123.85933)
			(xy 73.870476 -124.026808) (xy 73.986886 -124.189759) (xy 74.109722 -124.347921) (xy 74.238787 -124.501043)
			(xy 74.373876 -124.648878) (xy 74.514771 -124.79119) (xy 74.661247 -124.927751) (xy 74.81307 -125.058342)
			(xy 74.969996 -125.182754) (xy 75.131774 -125.300788) (xy 75.298145 -125.412255) (xy 75.468842 -125.516976)
			(xy 75.643593 -125.614784) (xy 75.822117 -125.705521) (xy 76.004129 -125.789044) (xy 76.189336 -125.865217)
			(xy 76.377443 -125.933919) (xy 76.568148 -125.99504) (xy 76.761145 -126.048482) (xy 76.956127 -126.09416)
			(xy 77.152779 -126.132) (xy 77.350789 -126.161941) (xy 77.549837 -126.183937) (xy 77.749606 -126.197951)
			(xy 77.949776 -126.203961) (xy 78.150027 -126.201957) (xy 78.350036 -126.191943) (xy 78.549485 -126.173935)
			(xy 78.748054 -126.147961) (xy 78.945424 -126.114064) (xy 79.141281 -126.072297) (xy 79.335309 -126.022727)
			(xy 79.527199 -125.965434) (xy 79.716642 -125.900509) (xy 79.903337 -125.828057) (xy 80.086983 -125.748193)
			(xy 80.267287 -125.661046) (xy 80.44396 -125.566754) (xy 80.616718 -125.465469) (xy 80.785286 -125.357354)
			(xy 80.949394 -125.242581) (xy 81.108778 -125.121333) (xy 81.263183 -124.993806) (xy 81.412362 -124.860203)
			(xy 81.556077 -124.720739) (xy 81.694096 -124.575637) (xy 81.8262 -124.425128) (xy 81.952176 -124.269455)
			(xy 82.071822 -124.108866) (xy 82.184948 -123.943618) (xy 82.291372 -123.773977) (xy 82.390923 -123.600213)
			(xy 82.483442 -123.422606) (xy 82.568781 -123.241439) (xy 82.646804 -123.057003) (xy 82.717384 -122.869593)
			(xy 82.78041 -122.67951) (xy 82.835781 -122.487056) (xy 82.883407 -122.292542) (xy 82.923212 -122.096277)
			(xy 82.955133 -121.898578) (xy 82.979119 -121.699759) (xy 82.995131 -121.50014) (xy 83.003143 -121.30004)
		)
		(stroke
			(width 0)
			(type solid)
		)
		(fill yes)
		(layer "F.Cu")
		(net "GND")
	)
	(gr_poly
		(pts
			(xy 83.003644 -32.29991) (xy 83.003143 -32.19978) (xy 82.995131 -31.99968) (xy 82.979119 -31.800061)
			(xy 82.955133 -31.601242) (xy 82.923212 -31.403543) (xy 82.883407 -31.207278) (xy 82.835781 -31.012764)
			(xy 82.78041 -30.82031) (xy 82.717384 -30.630227) (xy 82.646804 -30.442817) (xy 82.568781 -30.258381)
			(xy 82.483442 -30.077214) (xy 82.390923 -29.899607) (xy 82.291372 -29.725843) (xy 82.184948 -29.556202)
			(xy 82.071822 -29.390954) (xy 81.952176 -29.230365) (xy 81.8262 -29.074692) (xy 81.694096 -28.924183)
			(xy 81.556077 -28.779081) (xy 81.412362 -28.639617) (xy 81.263183 -28.506014) (xy 81.108778 -28.378487)
			(xy 80.949394 -28.257239) (xy 80.785286 -28.142466) (xy 80.616718 -28.034351) (xy 80.44396 -27.933066)
			(xy 80.267287 -27.838774) (xy 80.086983 -27.751627) (xy 79.903337 -27.671763) (xy 79.716642 -27.599311)
			(xy 79.527199 -27.534386) (xy 79.335309 -27.477093) (xy 79.141281 -27.427523) (xy 78.945424 -27.385756)
			(xy 78.748054 -27.351859) (xy 78.549485 -27.325885) (xy 78.350036 -27.307877) (xy 78.150027 -27.297863)
			(xy 77.949776 -27.295859) (xy 77.749606 -27.301869) (xy 77.549837 -27.315883) (xy 77.350789 -27.337879)
			(xy 77.152779 -27.36782) (xy 76.956127 -27.40566) (xy 76.761145 -27.451338) (xy 76.568148 -27.50478)
			(xy 76.377443 -27.565901) (xy 76.189336 -27.634603) (xy 76.004129 -27.710776) (xy 75.822117 -27.794299)
			(xy 75.643593 -27.885036) (xy 75.468842 -27.982844) (xy 75.298145 -28.087565) (xy 75.131774 -28.199032)
			(xy 74.969996 -28.317066) (xy 74.81307 -28.441478) (xy 74.661247 -28.572069) (xy 74.514771 -28.70863)
			(xy 74.373876 -28.850942) (xy 74.238787 -28.998777) (xy 74.109722 -29.151899) (xy 73.986886 -29.310061)
			(xy 73.870476 -29.473012) (xy 73.76068 -29.64049) (xy 73.657672 -29.812227) (xy 73.561617 -29.987947)
			(xy 73.47267 -30.16737) (xy 73.390973 -30.350208) (xy 73.316657 -30.536169) (xy 73.24984 -30.724953)
			(xy 73.19063 -30.91626) (xy 73.139121 -31.109783) (xy 73.095397 -31.305211) (xy 73.059526 -31.502233)
			(xy 73.031567 -31.700532) (xy 73.011564 -31.89979) (xy 72.99955 -32.09969) (xy 72.995543 -32.29991)
			(xy 75.484741 -32.29991) (xy 75.488769 -32.157618) (xy 75.500841 -32.015782) (xy 75.520918 -31.874855)
			(xy 75.548936 -31.735291) (xy 75.584805 -31.597535) (xy 75.62841 -31.462029) (xy 75.679611 -31.329207)
			(xy 75.738245 -31.199494) (xy 75.804123 -31.073307) (xy 75.877035 -30.951048) (xy 75.956747 -30.833111)
			(xy 76.043004 -30.719872) (xy 76.135528 -30.611694) (xy 76.234025 -30.508924) (xy 76.338179 -30.411891)
			(xy 76.447655 -30.320907) (xy 76.562103 -30.236261) (xy 76.681157 -30.158226) (xy 76.804435 -30.087052)
			(xy 76.931542 -30.022965) (xy 77.062071 -29.966173) (xy 77.195605 -29.916856) (xy 77.331714 -29.875173)
			(xy 77.469964 -29.841257) (xy 77.609911 -29.815217) (xy 77.751107 -29.797136) (xy 77.8931 -29.787073)
			(xy 78.035435 -29.785058) (xy 78.177656 -29.7911) (xy 78.319307 -29.805178) (xy 78.459935 -29.827247)
			(xy 78.599089 -29.857237) (xy 78.736324 -29.895052) (xy 78.871199 -29.94057) (xy 79.003283 -29.993646)
			(xy 79.132153 -30.054109) (xy 79.257396 -30.121766) (xy 79.37861 -30.196401) (xy 79.495408 -30.277774)
			(xy 79.607415 -30.365624) (xy 79.714273 -30.459671) (xy 79.815638 -30.559612) (xy 79.911187 -30.665128)
			(xy 80.000614 -30.775881) (xy 80.083632 -30.891515) (xy 80.159974 -31.011662) (xy 80.229397 -31.135934)
			(xy 80.291678 -31.263936) (xy 80.346618 -31.395256) (xy 80.39404 -31.529473) (xy 80.433793 -31.666159)
			(xy 80.465749 -31.804875) (xy 80.489806 -31.945176) (xy 80.505887 -32.086614) (xy 80.51394 -32.228735)
			(xy 80.514444 -32.29991) (xy 80.51394 -32.371085) (xy 80.505887 -32.513206) (xy 80.489806 -32.654644)
			(xy 80.465749 -32.794945) (xy 80.433793 -32.933661) (xy 80.39404 -33.070347) (xy 80.346618 -33.204564)
			(xy 80.291678 -33.335884) (xy 80.229397 -33.463886) (xy 80.159974 -33.588158) (xy 80.083632 -33.708305)
			(xy 80.000614 -33.823939) (xy 79.911187 -33.934692) (xy 79.815638 -34.040208) (xy 79.714273 -34.140149)
			(xy 79.607415 -34.234196) (xy 79.495408 -34.322046) (xy 79.37861 -34.403419) (xy 79.257396 -34.478054)
			(xy 79.132153 -34.545711) (xy 79.003283 -34.606174) (xy 78.871199 -34.65925) (xy 78.736324 -34.704768)
			(xy 78.599089 -34.742583) (xy 78.459935 -34.772573) (xy 78.319307 -34.794642) (xy 78.177656 -34.80872)
			(xy 78.035435 -34.814762) (xy 77.8931 -34.812747) (xy 77.751107 -34.802684) (xy 77.609911 -34.784603)
			(xy 77.469964 -34.758563) (xy 77.331714 -34.724647) (xy 77.195605 -34.682964) (xy 77.062071 -34.633647)
			(xy 76.931542 -34.576855) (xy 76.804435 -34.512768) (xy 76.681157 -34.441594) (xy 76.562103 -34.363559)
			(xy 76.447655 -34.278913) (xy 76.338179 -34.187929) (xy 76.234025 -34.090896) (xy 76.135528 -33.988126)
			(xy 76.043004 -33.879948) (xy 75.956747 -33.766709) (xy 75.877035 -33.648772) (xy 75.804123 -33.526513)
			(xy 75.738245 -33.400326) (xy 75.679611 -33.270613) (xy 75.62841 -33.137791) (xy 75.584805 -33.002285)
			(xy 75.548936 -32.864529) (xy 75.520918 -32.724965) (xy 75.500841 -32.584038) (xy 75.488769 -32.442202)
			(xy 75.484741 -32.29991) (xy 72.995543 -32.29991) (xy 72.99955 -32.50013) (xy 73.011564 -32.70003)
			(xy 73.031567 -32.899288) (xy 73.059526 -33.097587) (xy 73.095397 -33.294609) (xy 73.139121 -33.490037)
			(xy 73.19063 -33.68356) (xy 73.24984 -33.874867) (xy 73.316657 -34.063651) (xy 73.390973 -34.249612)
			(xy 73.47267 -34.43245) (xy 73.561617 -34.611873) (xy 73.657672 -34.787593) (xy 73.76068 -34.95933)
			(xy 73.870476 -35.126808) (xy 73.986886 -35.289759) (xy 74.109722 -35.447921) (xy 74.238787 -35.601043)
			(xy 74.373876 -35.748878) (xy 74.514771 -35.89119) (xy 74.661247 -36.027751) (xy 74.81307 -36.158342)
			(xy 74.969996 -36.282754) (xy 75.131774 -36.400788) (xy 75.298145 -36.512255) (xy 75.468842 -36.616976)
			(xy 75.643593 -36.714784) (xy 75.822117 -36.805521) (xy 76.004129 -36.889044) (xy 76.189336 -36.965217)
			(xy 76.377443 -37.033919) (xy 76.568148 -37.09504) (xy 76.761145 -37.148482) (xy 76.956127 -37.19416)
			(xy 77.152779 -37.232) (xy 77.350789 -37.261941) (xy 77.549837 -37.283937) (xy 77.749606 -37.297951)
			(xy 77.949776 -37.303961) (xy 78.150027 -37.301957) (xy 78.350036 -37.291943) (xy 78.549485 -37.273935)
			(xy 78.748054 -37.247961) (xy 78.945424 -37.214064) (xy 79.141281 -37.172297) (xy 79.335309 -37.122727)
			(xy 79.527199 -37.065434) (xy 79.716642 -37.000509) (xy 79.903337 -36.928057) (xy 80.086983 -36.848193)
			(xy 80.267287 -36.761046) (xy 80.44396 -36.666754) (xy 80.616718 -36.565469) (xy 80.785286 -36.457354)
			(xy 80.949394 -36.342581) (xy 81.108778 -36.221333) (xy 81.263183 -36.093806) (xy 81.412362 -35.960203)
			(xy 81.556077 -35.820739) (xy 81.694096 -35.675637) (xy 81.8262 -35.525128) (xy 81.952176 -35.369455)
			(xy 82.071822 -35.208866) (xy 82.184948 -35.043618) (xy 82.291372 -34.873977) (xy 82.390923 -34.700213)
			(xy 82.483442 -34.522606) (xy 82.568781 -34.341439) (xy 82.646804 -34.157003) (xy 82.717384 -33.969593)
			(xy 82.78041 -33.77951) (xy 82.835781 -33.587056) (xy 82.883407 -33.392542) (xy 82.923212 -33.196277)
			(xy 82.955133 -32.998578) (xy 82.979119 -32.799759) (xy 82.995131 -32.60014) (xy 83.003143 -32.40004)
		)
		(stroke
			(width 0)
			(type solid)
		)
		(fill yes)
		(layer "F.Cu")
		(net "GND")
	)
	(gr_poly
		(pts
			(xy 83.003898 -519.049762) (xy 83.003397 -518.949632) (xy 82.995385 -518.749532) (xy 82.979373 -518.549913)
			(xy 82.955387 -518.351094) (xy 82.923466 -518.153395) (xy 82.883661 -517.95713) (xy 82.836035 -517.762616)
			(xy 82.780664 -517.570162) (xy 82.717638 -517.380079) (xy 82.647058 -517.192669) (xy 82.569035 -517.008233)
			(xy 82.483696 -516.827066) (xy 82.391177 -516.649459) (xy 82.291626 -516.475695) (xy 82.185202 -516.306054)
			(xy 82.072076 -516.140806) (xy 81.95243 -515.980217) (xy 81.826454 -515.824544) (xy 81.69435 -515.674035)
			(xy 81.556331 -515.528933) (xy 81.412616 -515.389469) (xy 81.263437 -515.255866) (xy 81.109032 -515.128339)
			(xy 80.949648 -515.007091) (xy 80.78554 -514.892318) (xy 80.616972 -514.784203) (xy 80.444214 -514.682918)
			(xy 80.267541 -514.588626) (xy 80.087237 -514.501479) (xy 79.903591 -514.421615) (xy 79.716896 -514.349163)
			(xy 79.527453 -514.284238) (xy 79.335563 -514.226945) (xy 79.141535 -514.177375) (xy 78.945678 -514.135608)
			(xy 78.748308 -514.101711) (xy 78.549739 -514.075737) (xy 78.35029 -514.057729) (xy 78.150281 -514.047715)
			(xy 77.95003 -514.045711) (xy 77.74986 -514.051721) (xy 77.550091 -514.065735) (xy 77.351043 -514.087731)
			(xy 77.153033 -514.117672) (xy 76.956381 -514.155512) (xy 76.761399 -514.20119) (xy 76.568402 -514.254632)
			(xy 76.377697 -514.315753) (xy 76.18959 -514.384455) (xy 76.004383 -514.460628) (xy 75.822371 -514.544151)
			(xy 75.643847 -514.634888) (xy 75.469096 -514.732696) (xy 75.298399 -514.837417) (xy 75.132028 -514.948884)
			(xy 74.97025 -515.066918) (xy 74.813324 -515.19133) (xy 74.661501 -515.321921) (xy 74.515025 -515.458482)
			(xy 74.37413 -515.600794) (xy 74.239041 -515.748629) (xy 74.109976 -515.901751) (xy 73.98714 -516.059913)
			(xy 73.87073 -516.222864) (xy 73.760934 -516.390342) (xy 73.657926 -516.562079) (xy 73.561871 -516.737799)
			(xy 73.472924 -516.917222) (xy 73.391227 -517.10006) (xy 73.316911 -517.286021) (xy 73.250094 -517.474805)
			(xy 73.190884 -517.666112) (xy 73.139375 -517.859635) (xy 73.095651 -518.055063) (xy 73.05978 -518.252085)
			(xy 73.031821 -518.450384) (xy 73.011818 -518.649642) (xy 72.999804 -518.849542) (xy 72.995797 -519.049762)
			(xy 75.484995 -519.049762) (xy 75.489023 -518.90747) (xy 75.501095 -518.765634) (xy 75.521172 -518.624707)
			(xy 75.54919 -518.485143) (xy 75.585059 -518.347387) (xy 75.628664 -518.211881) (xy 75.679865 -518.079059)
			(xy 75.738499 -517.949346) (xy 75.804377 -517.823159) (xy 75.877289 -517.7009) (xy 75.957001 -517.582963)
			(xy 76.043258 -517.469724) (xy 76.135782 -517.361546) (xy 76.234279 -517.258776) (xy 76.338433 -517.161743)
			(xy 76.447909 -517.070759) (xy 76.562357 -516.986113) (xy 76.681411 -516.908078) (xy 76.804689 -516.836904)
			(xy 76.931796 -516.772817) (xy 77.062325 -516.716025) (xy 77.195859 -516.666708) (xy 77.331968 -516.625025)
			(xy 77.470218 -516.591109) (xy 77.610165 -516.565069) (xy 77.751361 -516.546988) (xy 77.893354 -516.536925)
			(xy 78.035689 -516.53491) (xy 78.17791 -516.540952) (xy 78.319561 -516.55503) (xy 78.460189 -516.577099)
			(xy 78.599343 -516.607089) (xy 78.736578 -516.644904) (xy 78.871453 -516.690422) (xy 79.003537 -516.743498)
			(xy 79.132407 -516.803961) (xy 79.25765 -516.871618) (xy 79.378864 -516.946253) (xy 79.495662 -517.027626)
			(xy 79.607669 -517.115476) (xy 79.714527 -517.209523) (xy 79.815892 -517.309464) (xy 79.911441 -517.41498)
			(xy 80.000868 -517.525733) (xy 80.083886 -517.641367) (xy 80.160228 -517.761514) (xy 80.229651 -517.885786)
			(xy 80.291932 -518.013788) (xy 80.346872 -518.145108) (xy 80.394294 -518.279325) (xy 80.434047 -518.416011)
			(xy 80.466003 -518.554727) (xy 80.49006 -518.695028) (xy 80.506141 -518.836466) (xy 80.514194 -518.978587)
			(xy 80.514698 -519.049762) (xy 80.514194 -519.120937) (xy 80.506141 -519.263058) (xy 80.49006 -519.404496)
			(xy 80.466003 -519.544797) (xy 80.434047 -519.683513) (xy 80.394294 -519.820199) (xy 80.346872 -519.954416)
			(xy 80.291932 -520.085736) (xy 80.229651 -520.213738) (xy 80.160228 -520.33801) (xy 80.083886 -520.458157)
			(xy 80.000868 -520.573791) (xy 79.911441 -520.684544) (xy 79.815892 -520.79006) (xy 79.714527 -520.890001)
			(xy 79.607669 -520.984048) (xy 79.495662 -521.071898) (xy 79.378864 -521.153271) (xy 79.25765 -521.227906)
			(xy 79.132407 -521.295563) (xy 79.003537 -521.356026) (xy 78.871453 -521.409102) (xy 78.736578 -521.45462)
			(xy 78.599343 -521.492435) (xy 78.460189 -521.522425) (xy 78.319561 -521.544494) (xy 78.17791 -521.558572)
			(xy 78.035689 -521.564614) (xy 77.893354 -521.562599) (xy 77.751361 -521.552536) (xy 77.610165 -521.534455)
			(xy 77.470218 -521.508415) (xy 77.331968 -521.474499) (xy 77.195859 -521.432816) (xy 77.062325 -521.383499)
			(xy 76.931796 -521.326707) (xy 76.804689 -521.26262) (xy 76.681411 -521.191446) (xy 76.562357 -521.113411)
			(xy 76.447909 -521.028765) (xy 76.338433 -520.937781) (xy 76.234279 -520.840748) (xy 76.135782 -520.737978)
			(xy 76.043258 -520.6298) (xy 75.957001 -520.516561) (xy 75.877289 -520.398624) (xy 75.804377 -520.276365)
			(xy 75.738499 -520.150178) (xy 75.679865 -520.020465) (xy 75.628664 -519.887643) (xy 75.585059 -519.752137)
			(xy 75.54919 -519.614381) (xy 75.521172 -519.474817) (xy 75.501095 -519.33389) (xy 75.489023 -519.192054)
			(xy 75.484995 -519.049762) (xy 72.995797 -519.049762) (xy 72.999804 -519.249982) (xy 73.011818 -519.449882)
			(xy 73.031821 -519.64914) (xy 73.05978 -519.847439) (xy 73.095651 -520.044461) (xy 73.139375 -520.239889)
			(xy 73.190884 -520.433412) (xy 73.250094 -520.624719) (xy 73.316911 -520.813503) (xy 73.391227 -520.999464)
			(xy 73.472924 -521.182302) (xy 73.561871 -521.361725) (xy 73.657926 -521.537445) (xy 73.760934 -521.709182)
			(xy 73.87073 -521.87666) (xy 73.98714 -522.039611) (xy 74.109976 -522.197773) (xy 74.239041 -522.350895)
			(xy 74.37413 -522.49873) (xy 74.515025 -522.641042) (xy 74.661501 -522.777603) (xy 74.813324 -522.908194)
			(xy 74.97025 -523.032606) (xy 75.132028 -523.15064) (xy 75.298399 -523.262107) (xy 75.469096 -523.366828)
			(xy 75.643847 -523.464636) (xy 75.822371 -523.555373) (xy 76.004383 -523.638896) (xy 76.18959 -523.715069)
			(xy 76.377697 -523.783771) (xy 76.568402 -523.844892) (xy 76.761399 -523.898334) (xy 76.956381 -523.944012)
			(xy 77.153033 -523.981852) (xy 77.351043 -524.011793) (xy 77.550091 -524.033789) (xy 77.74986 -524.047803)
			(xy 77.95003 -524.053813) (xy 78.150281 -524.051809) (xy 78.35029 -524.041795) (xy 78.549739 -524.023787)
			(xy 78.748308 -523.997813) (xy 78.945678 -523.963916) (xy 79.141535 -523.922149) (xy 79.335563 -523.872579)
			(xy 79.527453 -523.815286) (xy 79.716896 -523.750361) (xy 79.903591 -523.677909) (xy 80.087237 -523.598045)
			(xy 80.267541 -523.510898) (xy 80.444214 -523.416606) (xy 80.616972 -523.315321) (xy 80.78554 -523.207206)
			(xy 80.949648 -523.092433) (xy 81.109032 -522.971185) (xy 81.263437 -522.843658) (xy 81.412616 -522.710055)
			(xy 81.556331 -522.570591) (xy 81.69435 -522.425489) (xy 81.826454 -522.27498) (xy 81.95243 -522.119307)
			(xy 82.072076 -521.958718) (xy 82.185202 -521.79347) (xy 82.291626 -521.623829) (xy 82.391177 -521.450065)
			(xy 82.483696 -521.272458) (xy 82.569035 -521.091291) (xy 82.647058 -520.906855) (xy 82.717638 -520.719445)
			(xy 82.780664 -520.529362) (xy 82.836035 -520.336908) (xy 82.883661 -520.142394) (xy 82.923466 -519.946129)
			(xy 82.955387 -519.74843) (xy 82.979373 -519.549611) (xy 82.995385 -519.349992) (xy 83.003397 -519.149892)
		)
		(stroke
			(width 0)
			(type solid)
		)
		(fill yes)
		(layer "F.Cu")
		(net "GND")
	)
	(gr_poly
		(pts
			(xy 16.599916 -468.69604) (xy 16.499786 -468.696541) (xy 16.299686 -468.704553) (xy 16.100067 -468.720565)
			(xy 15.901248 -468.744551) (xy 15.703549 -468.776472) (xy 15.507284 -468.816277) (xy 15.31277 -468.863903)
			(xy 15.120316 -468.919274) (xy 14.930233 -468.9823) (xy 14.742823 -469.05288) (xy 14.558387 -469.130903)
			(xy 14.37722 -469.216242) (xy 14.199613 -469.308761) (xy 14.025849 -469.408312) (xy 13.856208 -469.514736)
			(xy 13.69096 -469.627862) (xy 13.530371 -469.747508) (xy 13.374698 -469.873484) (xy 13.224189 -470.005588)
			(xy 13.079087 -470.143607) (xy 12.939623 -470.287322) (xy 12.80602 -470.436501) (xy 12.678493 -470.590906)
			(xy 12.557245 -470.75029) (xy 12.442472 -470.914398) (xy 12.334357 -471.082966) (xy 12.233072 -471.255724)
			(xy 12.13878 -471.432397) (xy 12.051633 -471.612701) (xy 11.971769 -471.796347) (xy 11.899317 -471.983042)
			(xy 11.834392 -472.172485) (xy 11.777099 -472.364375) (xy 11.727529 -472.558403) (xy 11.685762 -472.75426)
			(xy 11.651865 -472.95163) (xy 11.625891 -473.150199) (xy 11.607883 -473.349648) (xy 11.597869 -473.549657)
			(xy 11.596722 -473.664249) (xy 14.085064 -473.664249) (xy 14.091106 -473.522028) (xy 14.105184 -473.380377)
			(xy 14.127253 -473.239749) (xy 14.157243 -473.100595) (xy 14.195058 -472.96336) (xy 14.240576 -472.828485)
			(xy 14.293652 -472.696401) (xy 14.354115 -472.567531) (xy 14.421772 -472.442288) (xy 14.496407 -472.321074)
			(xy 14.57778 -472.204276) (xy 14.66563 -472.092269) (xy 14.759677 -471.985411) (xy 14.859618 -471.884046)
			(xy 14.965134 -471.788497) (xy 15.075887 -471.69907) (xy 15.191521 -471.616052) (xy 15.311668 -471.53971)
			(xy 15.43594 -471.470287) (xy 15.563942 -471.408006) (xy 15.695262 -471.353066) (xy 15.829479 -471.305644)
			(xy 15.966165 -471.265891) (xy 16.104881 -471.233935) (xy 16.245182 -471.209878) (xy 16.38662 -471.193797)
			(xy 16.528741 -471.185744) (xy 16.599916 -471.18524) (xy 16.671091 -471.185744) (xy 16.813212 -471.193797)
			(xy 16.95465 -471.209878) (xy 17.094951 -471.233935) (xy 17.233667 -471.265891) (xy 17.370353 -471.305644)
			(xy 17.50457 -471.353066) (xy 17.63589 -471.408006) (xy 17.763892 -471.470287) (xy 17.888164 -471.53971)
			(xy 18.008311 -471.616052) (xy 18.123945 -471.69907) (xy 18.234698 -471.788497) (xy 18.340214 -471.884046)
			(xy 18.440155 -471.985411) (xy 18.534202 -472.092269) (xy 18.622052 -472.204276) (xy 18.703425 -472.321074)
			(xy 18.77806 -472.442288) (xy 18.845717 -472.567531) (xy 18.90618 -472.696401) (xy 18.959256 -472.828485)
			(xy 19.004774 -472.96336) (xy 19.042589 -473.100595) (xy 19.072579 -473.239749) (xy 19.094648 -473.380377)
			(xy 19.108726 -473.522028) (xy 19.114768 -473.664249) (xy 19.112753 -473.806584) (xy 19.10269 -473.948577)
			(xy 19.084609 -474.089773) (xy 19.058569 -474.22972) (xy 19.024653 -474.36797) (xy 18.98297 -474.504079)
			(xy 18.933653 -474.637613) (xy 18.876861 -474.768142) (xy 18.812774 -474.895249) (xy 18.7416 -475.018527)
			(xy 18.663565 -475.137581) (xy 18.578919 -475.252029) (xy 18.487935 -475.361505) (xy 18.390902 -475.465659)
			(xy 18.288132 -475.564156) (xy 18.179954 -475.65668) (xy 18.066715 -475.742937) (xy 17.948778 -475.822649)
			(xy 17.826519 -475.895561) (xy 17.700332 -475.961439) (xy 17.570619 -476.020073) (xy 17.437797 -476.071274)
			(xy 17.302291 -476.114879) (xy 17.164535 -476.150748) (xy 17.024971 -476.178766) (xy 16.884044 -476.198843)
			(xy 16.742208 -476.210915) (xy 16.599916 -476.214944) (xy 16.457624 -476.210915) (xy 16.315788 -476.198843)
			(xy 16.174861 -476.178766) (xy 16.035297 -476.150748) (xy 15.897541 -476.114879) (xy 15.762035 -476.071274)
			(xy 15.629213 -476.020073) (xy 15.4995 -475.961439) (xy 15.373313 -475.895561) (xy 15.251054 -475.822649)
			(xy 15.133117 -475.742937) (xy 15.019878 -475.65668) (xy 14.9117 -475.564156) (xy 14.80893 -475.465659)
			(xy 14.711897 -475.361505) (xy 14.620913 -475.252029) (xy 14.536267 -475.137581) (xy 14.458232 -475.018527)
			(xy 14.387058 -474.895249) (xy 14.322971 -474.768142) (xy 14.266179 -474.637613) (xy 14.216862 -474.504079)
			(xy 14.175179 -474.36797) (xy 14.141263 -474.22972) (xy 14.115223 -474.089773) (xy 14.097142 -473.948577)
			(xy 14.087079 -473.806584) (xy 14.085064 -473.664249) (xy 11.596722 -473.664249) (xy 11.595865 -473.749908)
			(xy 11.601875 -473.950078) (xy 11.615889 -474.149847) (xy 11.637885 -474.348895) (xy 11.667826 -474.546905)
			(xy 11.705666 -474.743557) (xy 11.751344 -474.938539) (xy 11.804786 -475.131536) (xy 11.865907 -475.322241)
			(xy 11.934609 -475.510348) (xy 12.010782 -475.695555) (xy 12.094305 -475.877567) (xy 12.185042 -476.056091)
			(xy 12.28285 -476.230842) (xy 12.387571 -476.401539) (xy 12.499038 -476.56791) (xy 12.617072 -476.729688)
			(xy 12.741484 -476.886614) (xy 12.872075 -477.038437) (xy 13.008636 -477.184913) (xy 13.150948 -477.325808)
			(xy 13.298783 -477.460897) (xy 13.451905 -477.589962) (xy 13.610067 -477.712798) (xy 13.773018 -477.829208)
			(xy 13.940496 -477.939004) (xy 14.112233 -478.042012) (xy 14.287953 -478.138067) (xy 14.467376 -478.227014)
			(xy 14.650214 -478.308711) (xy 14.836175 -478.383027) (xy 15.024959 -478.449844) (xy 15.216266 -478.509054)
			(xy 15.409789 -478.560563) (xy 15.605217 -478.604287) (xy 15.802239 -478.640158) (xy 16.000538 -478.668117)
			(xy 16.199796 -478.68812) (xy 16.399696 -478.700134) (xy 16.599916 -478.704141) (xy 16.800136 -478.700134)
			(xy 17.000036 -478.68812) (xy 17.199294 -478.668117) (xy 17.397593 -478.640158) (xy 17.594615 -478.604287)
			(xy 17.790043 -478.560563) (xy 17.983566 -478.509054) (xy 18.174873 -478.449844) (xy 18.363657 -478.383027)
			(xy 18.549618 -478.308711) (xy 18.732456 -478.227014) (xy 18.911879 -478.138067) (xy 19.087599 -478.042012)
			(xy 19.259336 -477.939004) (xy 19.426814 -477.829208) (xy 19.589765 -477.712798) (xy 19.747927 -477.589962)
			(xy 19.901049 -477.460897) (xy 20.048884 -477.325808) (xy 20.191196 -477.184913) (xy 20.327757 -477.038437)
			(xy 20.458348 -476.886614) (xy 20.58276 -476.729688) (xy 20.700794 -476.56791) (xy 20.812261 -476.401539)
			(xy 20.916982 -476.230842) (xy 21.01479 -476.056091) (xy 21.105527 -475.877567) (xy 21.18905 -475.695555)
			(xy 21.265223 -475.510348) (xy 21.333925 -475.322241) (xy 21.395046 -475.131536) (xy 21.448488 -474.938539)
			(xy 21.494166 -474.743557) (xy 21.532006 -474.546905) (xy 21.561947 -474.348895) (xy 21.583943 -474.149847)
			(xy 21.597957 -473.950078) (xy 21.603967 -473.749908) (xy 21.601963 -473.549657) (xy 21.591949 -473.349648)
			(xy 21.573941 -473.150199) (xy 21.547967 -472.95163) (xy 21.51407 -472.75426) (xy 21.472303 -472.558403)
			(xy 21.422733 -472.364375) (xy 21.36544 -472.172485) (xy 21.300515 -471.983042) (xy 21.228063 -471.796347)
			(xy 21.148199 -471.612701) (xy 21.061052 -471.432397) (xy 20.96676 -471.255724) (xy 20.865475 -471.082966)
			(xy 20.75736 -470.914398) (xy 20.642587 -470.75029) (xy 20.521339 -470.590906) (xy 20.393812 -470.436501)
			(xy 20.260209 -470.287322) (xy 20.120745 -470.143607) (xy 19.975643 -470.005588) (xy 19.825134 -469.873484)
			(xy 19.669461 -469.747508) (xy 19.508872 -469.627862) (xy 19.343624 -469.514736) (xy 19.173983 -469.408312)
			(xy 19.000219 -469.308761) (xy 18.822612 -469.216242) (xy 18.641445 -469.130903) (xy 18.457009 -469.05288)
			(xy 18.269599 -468.9823) (xy 18.079516 -468.919274) (xy 17.887062 -468.863903) (xy 17.692548 -468.816277)
			(xy 17.496283 -468.776472) (xy 17.298584 -468.744551) (xy 17.099765 -468.720565) (xy 16.900146 -468.704553)
			(xy 16.700046 -468.696541)
		)
		(stroke
			(width 0)
			(type solid)
		)
		(fill yes)
		(layer "F.Cu")
		(net "GND")
	)
	(gr_poly
		(pts
			(xy 16.599916 -379.79604) (xy 16.499786 -379.796541) (xy 16.299686 -379.804553) (xy 16.100067 -379.820565)
			(xy 15.901248 -379.844551) (xy 15.703549 -379.876472) (xy 15.507284 -379.916277) (xy 15.31277 -379.963903)
			(xy 15.120316 -380.019274) (xy 14.930233 -380.0823) (xy 14.742823 -380.15288) (xy 14.558387 -380.230903)
			(xy 14.37722 -380.316242) (xy 14.199613 -380.408761) (xy 14.025849 -380.508312) (xy 13.856208 -380.614736)
			(xy 13.69096 -380.727862) (xy 13.530371 -380.847508) (xy 13.374698 -380.973484) (xy 13.224189 -381.105588)
			(xy 13.079087 -381.243607) (xy 12.939623 -381.387322) (xy 12.80602 -381.536501) (xy 12.678493 -381.690906)
			(xy 12.557245 -381.85029) (xy 12.442472 -382.014398) (xy 12.334357 -382.182966) (xy 12.233072 -382.355724)
			(xy 12.13878 -382.532397) (xy 12.051633 -382.712701) (xy 11.971769 -382.896347) (xy 11.899317 -383.083042)
			(xy 11.834392 -383.272485) (xy 11.777099 -383.464375) (xy 11.727529 -383.658403) (xy 11.685762 -383.85426)
			(xy 11.651865 -384.05163) (xy 11.625891 -384.250199) (xy 11.607883 -384.449648) (xy 11.597869 -384.649657)
			(xy 11.596722 -384.764249) (xy 14.085064 -384.764249) (xy 14.091106 -384.622028) (xy 14.105184 -384.480377)
			(xy 14.127253 -384.339749) (xy 14.157243 -384.200595) (xy 14.195058 -384.06336) (xy 14.240576 -383.928485)
			(xy 14.293652 -383.796401) (xy 14.354115 -383.667531) (xy 14.421772 -383.542288) (xy 14.496407 -383.421074)
			(xy 14.57778 -383.304276) (xy 14.66563 -383.192269) (xy 14.759677 -383.085411) (xy 14.859618 -382.984046)
			(xy 14.965134 -382.888497) (xy 15.075887 -382.79907) (xy 15.191521 -382.716052) (xy 15.311668 -382.63971)
			(xy 15.43594 -382.570287) (xy 15.563942 -382.508006) (xy 15.695262 -382.453066) (xy 15.829479 -382.405644)
			(xy 15.966165 -382.365891) (xy 16.104881 -382.333935) (xy 16.245182 -382.309878) (xy 16.38662 -382.293797)
			(xy 16.528741 -382.285744) (xy 16.599916 -382.28524) (xy 16.671091 -382.285744) (xy 16.813212 -382.293797)
			(xy 16.95465 -382.309878) (xy 17.094951 -382.333935) (xy 17.233667 -382.365891) (xy 17.370353 -382.405644)
			(xy 17.50457 -382.453066) (xy 17.63589 -382.508006) (xy 17.763892 -382.570287) (xy 17.888164 -382.63971)
			(xy 18.008311 -382.716052) (xy 18.123945 -382.79907) (xy 18.234698 -382.888497) (xy 18.340214 -382.984046)
			(xy 18.440155 -383.085411) (xy 18.534202 -383.192269) (xy 18.622052 -383.304276) (xy 18.703425 -383.421074)
			(xy 18.77806 -383.542288) (xy 18.845717 -383.667531) (xy 18.90618 -383.796401) (xy 18.959256 -383.928485)
			(xy 19.004774 -384.06336) (xy 19.042589 -384.200595) (xy 19.072579 -384.339749) (xy 19.094648 -384.480377)
			(xy 19.108726 -384.622028) (xy 19.114768 -384.764249) (xy 19.112753 -384.906584) (xy 19.10269 -385.048577)
			(xy 19.084609 -385.189773) (xy 19.058569 -385.32972) (xy 19.024653 -385.46797) (xy 18.98297 -385.604079)
			(xy 18.933653 -385.737613) (xy 18.876861 -385.868142) (xy 18.812774 -385.995249) (xy 18.7416 -386.118527)
			(xy 18.663565 -386.237581) (xy 18.578919 -386.352029) (xy 18.487935 -386.461505) (xy 18.390902 -386.565659)
			(xy 18.288132 -386.664156) (xy 18.179954 -386.75668) (xy 18.066715 -386.842937) (xy 17.948778 -386.922649)
			(xy 17.826519 -386.995561) (xy 17.700332 -387.061439) (xy 17.570619 -387.120073) (xy 17.437797 -387.171274)
			(xy 17.302291 -387.214879) (xy 17.164535 -387.250748) (xy 17.024971 -387.278766) (xy 16.884044 -387.298843)
			(xy 16.742208 -387.310915) (xy 16.599916 -387.314944) (xy 16.457624 -387.310915) (xy 16.315788 -387.298843)
			(xy 16.174861 -387.278766) (xy 16.035297 -387.250748) (xy 15.897541 -387.214879) (xy 15.762035 -387.171274)
			(xy 15.629213 -387.120073) (xy 15.4995 -387.061439) (xy 15.373313 -386.995561) (xy 15.251054 -386.922649)
			(xy 15.133117 -386.842937) (xy 15.019878 -386.75668) (xy 14.9117 -386.664156) (xy 14.80893 -386.565659)
			(xy 14.711897 -386.461505) (xy 14.620913 -386.352029) (xy 14.536267 -386.237581) (xy 14.458232 -386.118527)
			(xy 14.387058 -385.995249) (xy 14.322971 -385.868142) (xy 14.266179 -385.737613) (xy 14.216862 -385.604079)
			(xy 14.175179 -385.46797) (xy 14.141263 -385.32972) (xy 14.115223 -385.189773) (xy 14.097142 -385.048577)
			(xy 14.087079 -384.906584) (xy 14.085064 -384.764249) (xy 11.596722 -384.764249) (xy 11.595865 -384.849908)
			(xy 11.601875 -385.050078) (xy 11.615889 -385.249847) (xy 11.637885 -385.448895) (xy 11.667826 -385.646905)
			(xy 11.705666 -385.843557) (xy 11.751344 -386.038539) (xy 11.804786 -386.231536) (xy 11.865907 -386.422241)
			(xy 11.934609 -386.610348) (xy 12.010782 -386.795555) (xy 12.094305 -386.977567) (xy 12.185042 -387.156091)
			(xy 12.28285 -387.330842) (xy 12.387571 -387.501539) (xy 12.499038 -387.66791) (xy 12.617072 -387.829688)
			(xy 12.741484 -387.986614) (xy 12.872075 -388.138437) (xy 13.008636 -388.284913) (xy 13.150948 -388.425808)
			(xy 13.298783 -388.560897) (xy 13.451905 -388.689962) (xy 13.610067 -388.812798) (xy 13.773018 -388.929208)
			(xy 13.940496 -389.039004) (xy 14.112233 -389.142012) (xy 14.287953 -389.238067) (xy 14.467376 -389.327014)
			(xy 14.650214 -389.408711) (xy 14.836175 -389.483027) (xy 15.024959 -389.549844) (xy 15.216266 -389.609054)
			(xy 15.409789 -389.660563) (xy 15.605217 -389.704287) (xy 15.802239 -389.740158) (xy 16.000538 -389.768117)
			(xy 16.199796 -389.78812) (xy 16.399696 -389.800134) (xy 16.599916 -389.804141) (xy 16.800136 -389.800134)
			(xy 17.000036 -389.78812) (xy 17.199294 -389.768117) (xy 17.397593 -389.740158) (xy 17.594615 -389.704287)
			(xy 17.790043 -389.660563) (xy 17.983566 -389.609054) (xy 18.174873 -389.549844) (xy 18.363657 -389.483027)
			(xy 18.549618 -389.408711) (xy 18.732456 -389.327014) (xy 18.911879 -389.238067) (xy 19.087599 -389.142012)
			(xy 19.259336 -389.039004) (xy 19.426814 -388.929208) (xy 19.589765 -388.812798) (xy 19.747927 -388.689962)
			(xy 19.901049 -388.560897) (xy 20.048884 -388.425808) (xy 20.191196 -388.284913) (xy 20.327757 -388.138437)
			(xy 20.458348 -387.986614) (xy 20.58276 -387.829688) (xy 20.700794 -387.66791) (xy 20.812261 -387.501539)
			(xy 20.916982 -387.330842) (xy 21.01479 -387.156091) (xy 21.105527 -386.977567) (xy 21.18905 -386.795555)
			(xy 21.265223 -386.610348) (xy 21.333925 -386.422241) (xy 21.395046 -386.231536) (xy 21.448488 -386.038539)
			(xy 21.494166 -385.843557) (xy 21.532006 -385.646905) (xy 21.561947 -385.448895) (xy 21.583943 -385.249847)
			(xy 21.597957 -385.050078) (xy 21.603967 -384.849908) (xy 21.601963 -384.649657) (xy 21.591949 -384.449648)
			(xy 21.573941 -384.250199) (xy 21.547967 -384.05163) (xy 21.51407 -383.85426) (xy 21.472303 -383.658403)
			(xy 21.422733 -383.464375) (xy 21.36544 -383.272485) (xy 21.300515 -383.083042) (xy 21.228063 -382.896347)
			(xy 21.148199 -382.712701) (xy 21.061052 -382.532397) (xy 20.96676 -382.355724) (xy 20.865475 -382.182966)
			(xy 20.75736 -382.014398) (xy 20.642587 -381.85029) (xy 20.521339 -381.690906) (xy 20.393812 -381.536501)
			(xy 20.260209 -381.387322) (xy 20.120745 -381.243607) (xy 19.975643 -381.105588) (xy 19.825134 -380.973484)
			(xy 19.669461 -380.847508) (xy 19.508872 -380.727862) (xy 19.343624 -380.614736) (xy 19.173983 -380.508312)
			(xy 19.000219 -380.408761) (xy 18.822612 -380.316242) (xy 18.641445 -380.230903) (xy 18.457009 -380.15288)
			(xy 18.269599 -380.0823) (xy 18.079516 -380.019274) (xy 17.887062 -379.963903) (xy 17.692548 -379.916277)
			(xy 17.496283 -379.876472) (xy 17.298584 -379.844551) (xy 17.099765 -379.820565) (xy 16.900146 -379.804553)
			(xy 16.700046 -379.796541)
		)
		(stroke
			(width 0)
			(type solid)
		)
		(fill yes)
		(layer "F.Cu")
		(net "GND")
	)
	(gr_poly
		(pts
			(xy 16.599916 -290.89604) (xy 16.499786 -290.896541) (xy 16.299686 -290.904553) (xy 16.100067 -290.920565)
			(xy 15.901248 -290.944551) (xy 15.703549 -290.976472) (xy 15.507284 -291.016277) (xy 15.31277 -291.063903)
			(xy 15.120316 -291.119274) (xy 14.930233 -291.1823) (xy 14.742823 -291.25288) (xy 14.558387 -291.330903)
			(xy 14.37722 -291.416242) (xy 14.199613 -291.508761) (xy 14.025849 -291.608312) (xy 13.856208 -291.714736)
			(xy 13.69096 -291.827862) (xy 13.530371 -291.947508) (xy 13.374698 -292.073484) (xy 13.224189 -292.205588)
			(xy 13.079087 -292.343607) (xy 12.939623 -292.487322) (xy 12.80602 -292.636501) (xy 12.678493 -292.790906)
			(xy 12.557245 -292.95029) (xy 12.442472 -293.114398) (xy 12.334357 -293.282966) (xy 12.233072 -293.455724)
			(xy 12.13878 -293.632397) (xy 12.051633 -293.812701) (xy 11.971769 -293.996347) (xy 11.899317 -294.183042)
			(xy 11.834392 -294.372485) (xy 11.777099 -294.564375) (xy 11.727529 -294.758403) (xy 11.685762 -294.95426)
			(xy 11.651865 -295.15163) (xy 11.625891 -295.350199) (xy 11.607883 -295.549648) (xy 11.597869 -295.749657)
			(xy 11.596722 -295.864249) (xy 14.085064 -295.864249) (xy 14.091106 -295.722028) (xy 14.105184 -295.580377)
			(xy 14.127253 -295.439749) (xy 14.157243 -295.300595) (xy 14.195058 -295.16336) (xy 14.240576 -295.028485)
			(xy 14.293652 -294.896401) (xy 14.354115 -294.767531) (xy 14.421772 -294.642288) (xy 14.496407 -294.521074)
			(xy 14.57778 -294.404276) (xy 14.66563 -294.292269) (xy 14.759677 -294.185411) (xy 14.859618 -294.084046)
			(xy 14.965134 -293.988497) (xy 15.075887 -293.89907) (xy 15.191521 -293.816052) (xy 15.311668 -293.73971)
			(xy 15.43594 -293.670287) (xy 15.563942 -293.608006) (xy 15.695262 -293.553066) (xy 15.829479 -293.505644)
			(xy 15.966165 -293.465891) (xy 16.104881 -293.433935) (xy 16.245182 -293.409878) (xy 16.38662 -293.393797)
			(xy 16.528741 -293.385744) (xy 16.599916 -293.38524) (xy 16.671091 -293.385744) (xy 16.813212 -293.393797)
			(xy 16.95465 -293.409878) (xy 17.094951 -293.433935) (xy 17.233667 -293.465891) (xy 17.370353 -293.505644)
			(xy 17.50457 -293.553066) (xy 17.63589 -293.608006) (xy 17.763892 -293.670287) (xy 17.888164 -293.73971)
			(xy 18.008311 -293.816052) (xy 18.123945 -293.89907) (xy 18.234698 -293.988497) (xy 18.340214 -294.084046)
			(xy 18.440155 -294.185411) (xy 18.534202 -294.292269) (xy 18.622052 -294.404276) (xy 18.703425 -294.521074)
			(xy 18.77806 -294.642288) (xy 18.845717 -294.767531) (xy 18.90618 -294.896401) (xy 18.959256 -295.028485)
			(xy 19.004774 -295.16336) (xy 19.042589 -295.300595) (xy 19.072579 -295.439749) (xy 19.094648 -295.580377)
			(xy 19.108726 -295.722028) (xy 19.114768 -295.864249) (xy 19.112753 -296.006584) (xy 19.10269 -296.148577)
			(xy 19.084609 -296.289773) (xy 19.058569 -296.42972) (xy 19.024653 -296.56797) (xy 18.98297 -296.704079)
			(xy 18.933653 -296.837613) (xy 18.876861 -296.968142) (xy 18.812774 -297.095249) (xy 18.7416 -297.218527)
			(xy 18.663565 -297.337581) (xy 18.578919 -297.452029) (xy 18.487935 -297.561505) (xy 18.390902 -297.665659)
			(xy 18.288132 -297.764156) (xy 18.179954 -297.85668) (xy 18.066715 -297.942937) (xy 17.948778 -298.022649)
			(xy 17.826519 -298.095561) (xy 17.700332 -298.161439) (xy 17.570619 -298.220073) (xy 17.437797 -298.271274)
			(xy 17.302291 -298.314879) (xy 17.164535 -298.350748) (xy 17.024971 -298.378766) (xy 16.884044 -298.398843)
			(xy 16.742208 -298.410915) (xy 16.599916 -298.414944) (xy 16.457624 -298.410915) (xy 16.315788 -298.398843)
			(xy 16.174861 -298.378766) (xy 16.035297 -298.350748) (xy 15.897541 -298.314879) (xy 15.762035 -298.271274)
			(xy 15.629213 -298.220073) (xy 15.4995 -298.161439) (xy 15.373313 -298.095561) (xy 15.251054 -298.022649)
			(xy 15.133117 -297.942937) (xy 15.019878 -297.85668) (xy 14.9117 -297.764156) (xy 14.80893 -297.665659)
			(xy 14.711897 -297.561505) (xy 14.620913 -297.452029) (xy 14.536267 -297.337581) (xy 14.458232 -297.218527)
			(xy 14.387058 -297.095249) (xy 14.322971 -296.968142) (xy 14.266179 -296.837613) (xy 14.216862 -296.704079)
			(xy 14.175179 -296.56797) (xy 14.141263 -296.42972) (xy 14.115223 -296.289773) (xy 14.097142 -296.148577)
			(xy 14.087079 -296.006584) (xy 14.085064 -295.864249) (xy 11.596722 -295.864249) (xy 11.595865 -295.949908)
			(xy 11.601875 -296.150078) (xy 11.615889 -296.349847) (xy 11.637885 -296.548895) (xy 11.667826 -296.746905)
			(xy 11.705666 -296.943557) (xy 11.751344 -297.138539) (xy 11.804786 -297.331536) (xy 11.865907 -297.522241)
			(xy 11.934609 -297.710348) (xy 12.010782 -297.895555) (xy 12.094305 -298.077567) (xy 12.185042 -298.256091)
			(xy 12.28285 -298.430842) (xy 12.387571 -298.601539) (xy 12.499038 -298.76791) (xy 12.617072 -298.929688)
			(xy 12.741484 -299.086614) (xy 12.872075 -299.238437) (xy 13.008636 -299.384913) (xy 13.150948 -299.525808)
			(xy 13.298783 -299.660897) (xy 13.451905 -299.789962) (xy 13.610067 -299.912798) (xy 13.773018 -300.029208)
			(xy 13.940496 -300.139004) (xy 14.112233 -300.242012) (xy 14.287953 -300.338067) (xy 14.467376 -300.427014)
			(xy 14.650214 -300.508711) (xy 14.836175 -300.583027) (xy 15.024959 -300.649844) (xy 15.216266 -300.709054)
			(xy 15.409789 -300.760563) (xy 15.605217 -300.804287) (xy 15.802239 -300.840158) (xy 16.000538 -300.868117)
			(xy 16.199796 -300.88812) (xy 16.399696 -300.900134) (xy 16.599916 -300.904141) (xy 16.800136 -300.900134)
			(xy 17.000036 -300.88812) (xy 17.199294 -300.868117) (xy 17.397593 -300.840158) (xy 17.594615 -300.804287)
			(xy 17.790043 -300.760563) (xy 17.983566 -300.709054) (xy 18.174873 -300.649844) (xy 18.363657 -300.583027)
			(xy 18.549618 -300.508711) (xy 18.732456 -300.427014) (xy 18.911879 -300.338067) (xy 19.087599 -300.242012)
			(xy 19.259336 -300.139004) (xy 19.426814 -300.029208) (xy 19.589765 -299.912798) (xy 19.747927 -299.789962)
			(xy 19.901049 -299.660897) (xy 20.048884 -299.525808) (xy 20.191196 -299.384913) (xy 20.327757 -299.238437)
			(xy 20.458348 -299.086614) (xy 20.58276 -298.929688) (xy 20.700794 -298.76791) (xy 20.812261 -298.601539)
			(xy 20.916982 -298.430842) (xy 21.01479 -298.256091) (xy 21.105527 -298.077567) (xy 21.18905 -297.895555)
			(xy 21.265223 -297.710348) (xy 21.333925 -297.522241) (xy 21.395046 -297.331536) (xy 21.448488 -297.138539)
			(xy 21.494166 -296.943557) (xy 21.532006 -296.746905) (xy 21.561947 -296.548895) (xy 21.583943 -296.349847)
			(xy 21.597957 -296.150078) (xy 21.603967 -295.949908) (xy 21.601963 -295.749657) (xy 21.591949 -295.549648)
			(xy 21.573941 -295.350199) (xy 21.547967 -295.15163) (xy 21.51407 -294.95426) (xy 21.472303 -294.758403)
			(xy 21.422733 -294.564375) (xy 21.36544 -294.372485) (xy 21.300515 -294.183042) (xy 21.228063 -293.996347)
			(xy 21.148199 -293.812701) (xy 21.061052 -293.632397) (xy 20.96676 -293.455724) (xy 20.865475 -293.282966)
			(xy 20.75736 -293.114398) (xy 20.642587 -292.95029) (xy 20.521339 -292.790906) (xy 20.393812 -292.636501)
			(xy 20.260209 -292.487322) (xy 20.120745 -292.343607) (xy 19.975643 -292.205588) (xy 19.825134 -292.073484)
			(xy 19.669461 -291.947508) (xy 19.508872 -291.827862) (xy 19.343624 -291.714736) (xy 19.173983 -291.608312)
			(xy 19.000219 -291.508761) (xy 18.822612 -291.416242) (xy 18.641445 -291.330903) (xy 18.457009 -291.25288)
			(xy 18.269599 -291.1823) (xy 18.079516 -291.119274) (xy 17.887062 -291.063903) (xy 17.692548 -291.016277)
			(xy 17.496283 -290.976472) (xy 17.298584 -290.944551) (xy 17.099765 -290.920565) (xy 16.900146 -290.904553)
			(xy 16.700046 -290.896541)
		)
		(stroke
			(width 0)
			(type solid)
		)
		(fill yes)
		(layer "F.Cu")
		(net "GND")
	)
	(gr_poly
		(pts
			(xy 16.599916 -201.99604) (xy 16.499786 -201.996541) (xy 16.299686 -202.004553) (xy 16.100067 -202.020565)
			(xy 15.901248 -202.044551) (xy 15.703549 -202.076472) (xy 15.507284 -202.116277) (xy 15.31277 -202.163903)
			(xy 15.120316 -202.219274) (xy 14.930233 -202.2823) (xy 14.742823 -202.35288) (xy 14.558387 -202.430903)
			(xy 14.37722 -202.516242) (xy 14.199613 -202.608761) (xy 14.025849 -202.708312) (xy 13.856208 -202.814736)
			(xy 13.69096 -202.927862) (xy 13.530371 -203.047508) (xy 13.374698 -203.173484) (xy 13.224189 -203.305588)
			(xy 13.079087 -203.443607) (xy 12.939623 -203.587322) (xy 12.80602 -203.736501) (xy 12.678493 -203.890906)
			(xy 12.557245 -204.05029) (xy 12.442472 -204.214398) (xy 12.334357 -204.382966) (xy 12.233072 -204.555724)
			(xy 12.13878 -204.732397) (xy 12.051633 -204.912701) (xy 11.971769 -205.096347) (xy 11.899317 -205.283042)
			(xy 11.834392 -205.472485) (xy 11.777099 -205.664375) (xy 11.727529 -205.858403) (xy 11.685762 -206.05426)
			(xy 11.651865 -206.25163) (xy 11.625891 -206.450199) (xy 11.607883 -206.649648) (xy 11.597869 -206.849657)
			(xy 11.596722 -206.964249) (xy 14.085064 -206.964249) (xy 14.091106 -206.822028) (xy 14.105184 -206.680377)
			(xy 14.127253 -206.539749) (xy 14.157243 -206.400595) (xy 14.195058 -206.26336) (xy 14.240576 -206.128485)
			(xy 14.293652 -205.996401) (xy 14.354115 -205.867531) (xy 14.421772 -205.742288) (xy 14.496407 -205.621074)
			(xy 14.57778 -205.504276) (xy 14.66563 -205.392269) (xy 14.759677 -205.285411) (xy 14.859618 -205.184046)
			(xy 14.965134 -205.088497) (xy 15.075887 -204.99907) (xy 15.191521 -204.916052) (xy 15.311668 -204.83971)
			(xy 15.43594 -204.770287) (xy 15.563942 -204.708006) (xy 15.695262 -204.653066) (xy 15.829479 -204.605644)
			(xy 15.966165 -204.565891) (xy 16.104881 -204.533935) (xy 16.245182 -204.509878) (xy 16.38662 -204.493797)
			(xy 16.528741 -204.485744) (xy 16.599916 -204.48524) (xy 16.671091 -204.485744) (xy 16.813212 -204.493797)
			(xy 16.95465 -204.509878) (xy 17.094951 -204.533935) (xy 17.233667 -204.565891) (xy 17.370353 -204.605644)
			(xy 17.50457 -204.653066) (xy 17.63589 -204.708006) (xy 17.763892 -204.770287) (xy 17.888164 -204.83971)
			(xy 18.008311 -204.916052) (xy 18.123945 -204.99907) (xy 18.234698 -205.088497) (xy 18.340214 -205.184046)
			(xy 18.440155 -205.285411) (xy 18.534202 -205.392269) (xy 18.622052 -205.504276) (xy 18.703425 -205.621074)
			(xy 18.77806 -205.742288) (xy 18.845717 -205.867531) (xy 18.90618 -205.996401) (xy 18.959256 -206.128485)
			(xy 19.004774 -206.26336) (xy 19.042589 -206.400595) (xy 19.072579 -206.539749) (xy 19.094648 -206.680377)
			(xy 19.108726 -206.822028) (xy 19.114768 -206.964249) (xy 19.112753 -207.106584) (xy 19.10269 -207.248577)
			(xy 19.084609 -207.389773) (xy 19.058569 -207.52972) (xy 19.024653 -207.66797) (xy 18.98297 -207.804079)
			(xy 18.933653 -207.937613) (xy 18.876861 -208.068142) (xy 18.812774 -208.195249) (xy 18.7416 -208.318527)
			(xy 18.663565 -208.437581) (xy 18.578919 -208.552029) (xy 18.487935 -208.661505) (xy 18.390902 -208.765659)
			(xy 18.288132 -208.864156) (xy 18.179954 -208.95668) (xy 18.066715 -209.042937) (xy 17.948778 -209.122649)
			(xy 17.826519 -209.195561) (xy 17.700332 -209.261439) (xy 17.570619 -209.320073) (xy 17.437797 -209.371274)
			(xy 17.302291 -209.414879) (xy 17.164535 -209.450748) (xy 17.024971 -209.478766) (xy 16.884044 -209.498843)
			(xy 16.742208 -209.510915) (xy 16.599916 -209.514944) (xy 16.457624 -209.510915) (xy 16.315788 -209.498843)
			(xy 16.174861 -209.478766) (xy 16.035297 -209.450748) (xy 15.897541 -209.414879) (xy 15.762035 -209.371274)
			(xy 15.629213 -209.320073) (xy 15.4995 -209.261439) (xy 15.373313 -209.195561) (xy 15.251054 -209.122649)
			(xy 15.133117 -209.042937) (xy 15.019878 -208.95668) (xy 14.9117 -208.864156) (xy 14.80893 -208.765659)
			(xy 14.711897 -208.661505) (xy 14.620913 -208.552029) (xy 14.536267 -208.437581) (xy 14.458232 -208.318527)
			(xy 14.387058 -208.195249) (xy 14.322971 -208.068142) (xy 14.266179 -207.937613) (xy 14.216862 -207.804079)
			(xy 14.175179 -207.66797) (xy 14.141263 -207.52972) (xy 14.115223 -207.389773) (xy 14.097142 -207.248577)
			(xy 14.087079 -207.106584) (xy 14.085064 -206.964249) (xy 11.596722 -206.964249) (xy 11.595865 -207.049908)
			(xy 11.601875 -207.250078) (xy 11.615889 -207.449847) (xy 11.637885 -207.648895) (xy 11.667826 -207.846905)
			(xy 11.705666 -208.043557) (xy 11.751344 -208.238539) (xy 11.804786 -208.431536) (xy 11.865907 -208.622241)
			(xy 11.934609 -208.810348) (xy 12.010782 -208.995555) (xy 12.094305 -209.177567) (xy 12.185042 -209.356091)
			(xy 12.28285 -209.530842) (xy 12.387571 -209.701539) (xy 12.499038 -209.86791) (xy 12.617072 -210.029688)
			(xy 12.741484 -210.186614) (xy 12.872075 -210.338437) (xy 13.008636 -210.484913) (xy 13.150948 -210.625808)
			(xy 13.298783 -210.760897) (xy 13.451905 -210.889962) (xy 13.610067 -211.012798) (xy 13.773018 -211.129208)
			(xy 13.940496 -211.239004) (xy 14.112233 -211.342012) (xy 14.287953 -211.438067) (xy 14.467376 -211.527014)
			(xy 14.650214 -211.608711) (xy 14.836175 -211.683027) (xy 15.024959 -211.749844) (xy 15.216266 -211.809054)
			(xy 15.409789 -211.860563) (xy 15.605217 -211.904287) (xy 15.802239 -211.940158) (xy 16.000538 -211.968117)
			(xy 16.199796 -211.98812) (xy 16.399696 -212.000134) (xy 16.599916 -212.004141) (xy 16.800136 -212.000134)
			(xy 17.000036 -211.98812) (xy 17.199294 -211.968117) (xy 17.397593 -211.940158) (xy 17.594615 -211.904287)
			(xy 17.790043 -211.860563) (xy 17.983566 -211.809054) (xy 18.174873 -211.749844) (xy 18.363657 -211.683027)
			(xy 18.549618 -211.608711) (xy 18.732456 -211.527014) (xy 18.911879 -211.438067) (xy 19.087599 -211.342012)
			(xy 19.259336 -211.239004) (xy 19.426814 -211.129208) (xy 19.589765 -211.012798) (xy 19.747927 -210.889962)
			(xy 19.901049 -210.760897) (xy 20.048884 -210.625808) (xy 20.191196 -210.484913) (xy 20.327757 -210.338437)
			(xy 20.458348 -210.186614) (xy 20.58276 -210.029688) (xy 20.700794 -209.86791) (xy 20.812261 -209.701539)
			(xy 20.916982 -209.530842) (xy 21.01479 -209.356091) (xy 21.105527 -209.177567) (xy 21.18905 -208.995555)
			(xy 21.265223 -208.810348) (xy 21.333925 -208.622241) (xy 21.395046 -208.431536) (xy 21.448488 -208.238539)
			(xy 21.494166 -208.043557) (xy 21.532006 -207.846905) (xy 21.561947 -207.648895) (xy 21.583943 -207.449847)
			(xy 21.597957 -207.250078) (xy 21.603967 -207.049908) (xy 21.601963 -206.849657) (xy 21.591949 -206.649648)
			(xy 21.573941 -206.450199) (xy 21.547967 -206.25163) (xy 21.51407 -206.05426) (xy 21.472303 -205.858403)
			(xy 21.422733 -205.664375) (xy 21.36544 -205.472485) (xy 21.300515 -205.283042) (xy 21.228063 -205.096347)
			(xy 21.148199 -204.912701) (xy 21.061052 -204.732397) (xy 20.96676 -204.555724) (xy 20.865475 -204.382966)
			(xy 20.75736 -204.214398) (xy 20.642587 -204.05029) (xy 20.521339 -203.890906) (xy 20.393812 -203.736501)
			(xy 20.260209 -203.587322) (xy 20.120745 -203.443607) (xy 19.975643 -203.305588) (xy 19.825134 -203.173484)
			(xy 19.669461 -203.047508) (xy 19.508872 -202.927862) (xy 19.343624 -202.814736) (xy 19.173983 -202.708312)
			(xy 19.000219 -202.608761) (xy 18.822612 -202.516242) (xy 18.641445 -202.430903) (xy 18.457009 -202.35288)
			(xy 18.269599 -202.2823) (xy 18.079516 -202.219274) (xy 17.887062 -202.163903) (xy 17.692548 -202.116277)
			(xy 17.496283 -202.076472) (xy 17.298584 -202.044551) (xy 17.099765 -202.020565) (xy 16.900146 -202.004553)
			(xy 16.700046 -201.996541)
		)
		(stroke
			(width 0)
			(type solid)
		)
		(fill yes)
		(layer "F.Cu")
		(net "GND")
	)
	(gr_poly
		(pts
			(xy 16.599916 -113.09604) (xy 16.499786 -113.096541) (xy 16.299686 -113.104553) (xy 16.100067 -113.120565)
			(xy 15.901248 -113.144551) (xy 15.703549 -113.176472) (xy 15.507284 -113.216277) (xy 15.31277 -113.263903)
			(xy 15.120316 -113.319274) (xy 14.930233 -113.3823) (xy 14.742823 -113.45288) (xy 14.558387 -113.530903)
			(xy 14.37722 -113.616242) (xy 14.199613 -113.708761) (xy 14.025849 -113.808312) (xy 13.856208 -113.914736)
			(xy 13.69096 -114.027862) (xy 13.530371 -114.147508) (xy 13.374698 -114.273484) (xy 13.224189 -114.405588)
			(xy 13.079087 -114.543607) (xy 12.939623 -114.687322) (xy 12.80602 -114.836501) (xy 12.678493 -114.990906)
			(xy 12.557245 -115.15029) (xy 12.442472 -115.314398) (xy 12.334357 -115.482966) (xy 12.233072 -115.655724)
			(xy 12.13878 -115.832397) (xy 12.051633 -116.012701) (xy 11.971769 -116.196347) (xy 11.899317 -116.383042)
			(xy 11.834392 -116.572485) (xy 11.777099 -116.764375) (xy 11.727529 -116.958403) (xy 11.685762 -117.15426)
			(xy 11.651865 -117.35163) (xy 11.625891 -117.550199) (xy 11.607883 -117.749648) (xy 11.597869 -117.949657)
			(xy 11.596722 -118.064249) (xy 14.085064 -118.064249) (xy 14.091106 -117.922028) (xy 14.105184 -117.780377)
			(xy 14.127253 -117.639749) (xy 14.157243 -117.500595) (xy 14.195058 -117.36336) (xy 14.240576 -117.228485)
			(xy 14.293652 -117.096401) (xy 14.354115 -116.967531) (xy 14.421772 -116.842288) (xy 14.496407 -116.721074)
			(xy 14.57778 -116.604276) (xy 14.66563 -116.492269) (xy 14.759677 -116.385411) (xy 14.859618 -116.284046)
			(xy 14.965134 -116.188497) (xy 15.075887 -116.09907) (xy 15.191521 -116.016052) (xy 15.311668 -115.93971)
			(xy 15.43594 -115.870287) (xy 15.563942 -115.808006) (xy 15.695262 -115.753066) (xy 15.829479 -115.705644)
			(xy 15.966165 -115.665891) (xy 16.104881 -115.633935) (xy 16.245182 -115.609878) (xy 16.38662 -115.593797)
			(xy 16.528741 -115.585744) (xy 16.599916 -115.58524) (xy 16.671091 -115.585744) (xy 16.813212 -115.593797)
			(xy 16.95465 -115.609878) (xy 17.094951 -115.633935) (xy 17.233667 -115.665891) (xy 17.370353 -115.705644)
			(xy 17.50457 -115.753066) (xy 17.63589 -115.808006) (xy 17.763892 -115.870287) (xy 17.888164 -115.93971)
			(xy 18.008311 -116.016052) (xy 18.123945 -116.09907) (xy 18.234698 -116.188497) (xy 18.340214 -116.284046)
			(xy 18.440155 -116.385411) (xy 18.534202 -116.492269) (xy 18.622052 -116.604276) (xy 18.703425 -116.721074)
			(xy 18.77806 -116.842288) (xy 18.845717 -116.967531) (xy 18.90618 -117.096401) (xy 18.959256 -117.228485)
			(xy 19.004774 -117.36336) (xy 19.042589 -117.500595) (xy 19.072579 -117.639749) (xy 19.094648 -117.780377)
			(xy 19.108726 -117.922028) (xy 19.114768 -118.064249) (xy 19.112753 -118.206584) (xy 19.10269 -118.348577)
			(xy 19.084609 -118.489773) (xy 19.058569 -118.62972) (xy 19.024653 -118.76797) (xy 18.98297 -118.904079)
			(xy 18.933653 -119.037613) (xy 18.876861 -119.168142) (xy 18.812774 -119.295249) (xy 18.7416 -119.418527)
			(xy 18.663565 -119.537581) (xy 18.578919 -119.652029) (xy 18.487935 -119.761505) (xy 18.390902 -119.865659)
			(xy 18.288132 -119.964156) (xy 18.179954 -120.05668) (xy 18.066715 -120.142937) (xy 17.948778 -120.222649)
			(xy 17.826519 -120.295561) (xy 17.700332 -120.361439) (xy 17.570619 -120.420073) (xy 17.437797 -120.471274)
			(xy 17.302291 -120.514879) (xy 17.164535 -120.550748) (xy 17.024971 -120.578766) (xy 16.884044 -120.598843)
			(xy 16.742208 -120.610915) (xy 16.599916 -120.614944) (xy 16.457624 -120.610915) (xy 16.315788 -120.598843)
			(xy 16.174861 -120.578766) (xy 16.035297 -120.550748) (xy 15.897541 -120.514879) (xy 15.762035 -120.471274)
			(xy 15.629213 -120.420073) (xy 15.4995 -120.361439) (xy 15.373313 -120.295561) (xy 15.251054 -120.222649)
			(xy 15.133117 -120.142937) (xy 15.019878 -120.05668) (xy 14.9117 -119.964156) (xy 14.80893 -119.865659)
			(xy 14.711897 -119.761505) (xy 14.620913 -119.652029) (xy 14.536267 -119.537581) (xy 14.458232 -119.418527)
			(xy 14.387058 -119.295249) (xy 14.322971 -119.168142) (xy 14.266179 -119.037613) (xy 14.216862 -118.904079)
			(xy 14.175179 -118.76797) (xy 14.141263 -118.62972) (xy 14.115223 -118.489773) (xy 14.097142 -118.348577)
			(xy 14.087079 -118.206584) (xy 14.085064 -118.064249) (xy 11.596722 -118.064249) (xy 11.595865 -118.149908)
			(xy 11.601875 -118.350078) (xy 11.615889 -118.549847) (xy 11.637885 -118.748895) (xy 11.667826 -118.946905)
			(xy 11.705666 -119.143557) (xy 11.751344 -119.338539) (xy 11.804786 -119.531536) (xy 11.865907 -119.722241)
			(xy 11.934609 -119.910348) (xy 12.010782 -120.095555) (xy 12.094305 -120.277567) (xy 12.185042 -120.456091)
			(xy 12.28285 -120.630842) (xy 12.387571 -120.801539) (xy 12.499038 -120.96791) (xy 12.617072 -121.129688)
			(xy 12.741484 -121.286614) (xy 12.872075 -121.438437) (xy 13.008636 -121.584913) (xy 13.150948 -121.725808)
			(xy 13.298783 -121.860897) (xy 13.451905 -121.989962) (xy 13.610067 -122.112798) (xy 13.773018 -122.229208)
			(xy 13.940496 -122.339004) (xy 14.112233 -122.442012) (xy 14.287953 -122.538067) (xy 14.467376 -122.627014)
			(xy 14.650214 -122.708711) (xy 14.836175 -122.783027) (xy 15.024959 -122.849844) (xy 15.216266 -122.909054)
			(xy 15.409789 -122.960563) (xy 15.605217 -123.004287) (xy 15.802239 -123.040158) (xy 16.000538 -123.068117)
			(xy 16.199796 -123.08812) (xy 16.399696 -123.100134) (xy 16.599916 -123.104141) (xy 16.800136 -123.100134)
			(xy 17.000036 -123.08812) (xy 17.199294 -123.068117) (xy 17.397593 -123.040158) (xy 17.594615 -123.004287)
			(xy 17.790043 -122.960563) (xy 17.983566 -122.909054) (xy 18.174873 -122.849844) (xy 18.363657 -122.783027)
			(xy 18.549618 -122.708711) (xy 18.732456 -122.627014) (xy 18.911879 -122.538067) (xy 19.087599 -122.442012)
			(xy 19.259336 -122.339004) (xy 19.426814 -122.229208) (xy 19.589765 -122.112798) (xy 19.747927 -121.989962)
			(xy 19.901049 -121.860897) (xy 20.048884 -121.725808) (xy 20.191196 -121.584913) (xy 20.327757 -121.438437)
			(xy 20.458348 -121.286614) (xy 20.58276 -121.129688) (xy 20.700794 -120.96791) (xy 20.812261 -120.801539)
			(xy 20.916982 -120.630842) (xy 21.01479 -120.456091) (xy 21.105527 -120.277567) (xy 21.18905 -120.095555)
			(xy 21.265223 -119.910348) (xy 21.333925 -119.722241) (xy 21.395046 -119.531536) (xy 21.448488 -119.338539)
			(xy 21.494166 -119.143557) (xy 21.532006 -118.946905) (xy 21.561947 -118.748895) (xy 21.583943 -118.549847)
			(xy 21.597957 -118.350078) (xy 21.603967 -118.149908) (xy 21.601963 -117.949657) (xy 21.591949 -117.749648)
			(xy 21.573941 -117.550199) (xy 21.547967 -117.35163) (xy 21.51407 -117.15426) (xy 21.472303 -116.958403)
			(xy 21.422733 -116.764375) (xy 21.36544 -116.572485) (xy 21.300515 -116.383042) (xy 21.228063 -116.196347)
			(xy 21.148199 -116.012701) (xy 21.061052 -115.832397) (xy 20.96676 -115.655724) (xy 20.865475 -115.482966)
			(xy 20.75736 -115.314398) (xy 20.642587 -115.15029) (xy 20.521339 -114.990906) (xy 20.393812 -114.836501)
			(xy 20.260209 -114.687322) (xy 20.120745 -114.543607) (xy 19.975643 -114.405588) (xy 19.825134 -114.273484)
			(xy 19.669461 -114.147508) (xy 19.508872 -114.027862) (xy 19.343624 -113.914736) (xy 19.173983 -113.808312)
			(xy 19.000219 -113.708761) (xy 18.822612 -113.616242) (xy 18.641445 -113.530903) (xy 18.457009 -113.45288)
			(xy 18.269599 -113.3823) (xy 18.079516 -113.319274) (xy 17.887062 -113.263903) (xy 17.692548 -113.216277)
			(xy 17.496283 -113.176472) (xy 17.298584 -113.144551) (xy 17.099765 -113.120565) (xy 16.900146 -113.104553)
			(xy 16.700046 -113.096541)
		)
		(stroke
			(width 0)
			(type solid)
		)
		(fill yes)
		(layer "F.Cu")
		(net "GND")
	)
	(gr_poly
		(pts
			(xy 16.599916 -24.19604) (xy 16.499786 -24.196541) (xy 16.299686 -24.204553) (xy 16.100067 -24.220565)
			(xy 15.901248 -24.244551) (xy 15.703549 -24.276472) (xy 15.507284 -24.316277) (xy 15.31277 -24.363903)
			(xy 15.120316 -24.419274) (xy 14.930233 -24.4823) (xy 14.742823 -24.55288) (xy 14.558387 -24.630903)
			(xy 14.37722 -24.716242) (xy 14.199613 -24.808761) (xy 14.025849 -24.908312) (xy 13.856208 -25.014736)
			(xy 13.69096 -25.127862) (xy 13.530371 -25.247508) (xy 13.374698 -25.373484) (xy 13.224189 -25.505588)
			(xy 13.079087 -25.643607) (xy 12.939623 -25.787322) (xy 12.80602 -25.936501) (xy 12.678493 -26.090906)
			(xy 12.557245 -26.25029) (xy 12.442472 -26.414398) (xy 12.334357 -26.582966) (xy 12.233072 -26.755724)
			(xy 12.13878 -26.932397) (xy 12.051633 -27.112701) (xy 11.971769 -27.296347) (xy 11.899317 -27.483042)
			(xy 11.834392 -27.672485) (xy 11.777099 -27.864375) (xy 11.727529 -28.058403) (xy 11.685762 -28.25426)
			(xy 11.651865 -28.45163) (xy 11.625891 -28.650199) (xy 11.607883 -28.849648) (xy 11.597869 -29.049657)
			(xy 11.596722 -29.164249) (xy 14.085064 -29.164249) (xy 14.091106 -29.022028) (xy 14.105184 -28.880377)
			(xy 14.127253 -28.739749) (xy 14.157243 -28.600595) (xy 14.195058 -28.46336) (xy 14.240576 -28.328485)
			(xy 14.293652 -28.196401) (xy 14.354115 -28.067531) (xy 14.421772 -27.942288) (xy 14.496407 -27.821074)
			(xy 14.57778 -27.704276) (xy 14.66563 -27.592269) (xy 14.759677 -27.485411) (xy 14.859618 -27.384046)
			(xy 14.965134 -27.288497) (xy 15.075887 -27.19907) (xy 15.191521 -27.116052) (xy 15.311668 -27.03971)
			(xy 15.43594 -26.970287) (xy 15.563942 -26.908006) (xy 15.695262 -26.853066) (xy 15.829479 -26.805644)
			(xy 15.966165 -26.765891) (xy 16.104881 -26.733935) (xy 16.245182 -26.709878) (xy 16.38662 -26.693797)
			(xy 16.528741 -26.685744) (xy 16.599916 -26.68524) (xy 16.671091 -26.685744) (xy 16.813212 -26.693797)
			(xy 16.95465 -26.709878) (xy 17.094951 -26.733935) (xy 17.233667 -26.765891) (xy 17.370353 -26.805644)
			(xy 17.50457 -26.853066) (xy 17.63589 -26.908006) (xy 17.763892 -26.970287) (xy 17.888164 -27.03971)
			(xy 18.008311 -27.116052) (xy 18.123945 -27.19907) (xy 18.234698 -27.288497) (xy 18.340214 -27.384046)
			(xy 18.440155 -27.485411) (xy 18.534202 -27.592269) (xy 18.622052 -27.704276) (xy 18.703425 -27.821074)
			(xy 18.77806 -27.942288) (xy 18.845717 -28.067531) (xy 18.90618 -28.196401) (xy 18.959256 -28.328485)
			(xy 19.004774 -28.46336) (xy 19.042589 -28.600595) (xy 19.072579 -28.739749) (xy 19.094648 -28.880377)
			(xy 19.108726 -29.022028) (xy 19.114768 -29.164249) (xy 19.112753 -29.306584) (xy 19.10269 -29.448577)
			(xy 19.084609 -29.589773) (xy 19.058569 -29.72972) (xy 19.024653 -29.86797) (xy 18.98297 -30.004079)
			(xy 18.933653 -30.137613) (xy 18.876861 -30.268142) (xy 18.812774 -30.395249) (xy 18.7416 -30.518527)
			(xy 18.663565 -30.637581) (xy 18.578919 -30.752029) (xy 18.487935 -30.861505) (xy 18.390902 -30.965659)
			(xy 18.288132 -31.064156) (xy 18.179954 -31.15668) (xy 18.066715 -31.242937) (xy 17.948778 -31.322649)
			(xy 17.826519 -31.395561) (xy 17.700332 -31.461439) (xy 17.570619 -31.520073) (xy 17.437797 -31.571274)
			(xy 17.302291 -31.614879) (xy 17.164535 -31.650748) (xy 17.024971 -31.678766) (xy 16.884044 -31.698843)
			(xy 16.742208 -31.710915) (xy 16.599916 -31.714944) (xy 16.457624 -31.710915) (xy 16.315788 -31.698843)
			(xy 16.174861 -31.678766) (xy 16.035297 -31.650748) (xy 15.897541 -31.614879) (xy 15.762035 -31.571274)
			(xy 15.629213 -31.520073) (xy 15.4995 -31.461439) (xy 15.373313 -31.395561) (xy 15.251054 -31.322649)
			(xy 15.133117 -31.242937) (xy 15.019878 -31.15668) (xy 14.9117 -31.064156) (xy 14.80893 -30.965659)
			(xy 14.711897 -30.861505) (xy 14.620913 -30.752029) (xy 14.536267 -30.637581) (xy 14.458232 -30.518527)
			(xy 14.387058 -30.395249) (xy 14.322971 -30.268142) (xy 14.266179 -30.137613) (xy 14.216862 -30.004079)
			(xy 14.175179 -29.86797) (xy 14.141263 -29.72972) (xy 14.115223 -29.589773) (xy 14.097142 -29.448577)
			(xy 14.087079 -29.306584) (xy 14.085064 -29.164249) (xy 11.596722 -29.164249) (xy 11.595865 -29.249908)
			(xy 11.601875 -29.450078) (xy 11.615889 -29.649847) (xy 11.637885 -29.848895) (xy 11.667826 -30.046905)
			(xy 11.705666 -30.243557) (xy 11.751344 -30.438539) (xy 11.804786 -30.631536) (xy 11.865907 -30.822241)
			(xy 11.934609 -31.010348) (xy 12.010782 -31.195555) (xy 12.094305 -31.377567) (xy 12.185042 -31.556091)
			(xy 12.28285 -31.730842) (xy 12.387571 -31.901539) (xy 12.499038 -32.06791) (xy 12.617072 -32.229688)
			(xy 12.741484 -32.386614) (xy 12.872075 -32.538437) (xy 13.008636 -32.684913) (xy 13.150948 -32.825808)
			(xy 13.298783 -32.960897) (xy 13.451905 -33.089962) (xy 13.610067 -33.212798) (xy 13.773018 -33.329208)
			(xy 13.940496 -33.439004) (xy 14.112233 -33.542012) (xy 14.287953 -33.638067) (xy 14.467376 -33.727014)
			(xy 14.650214 -33.808711) (xy 14.836175 -33.883027) (xy 15.024959 -33.949844) (xy 15.216266 -34.009054)
			(xy 15.409789 -34.060563) (xy 15.605217 -34.104287) (xy 15.802239 -34.140158) (xy 16.000538 -34.168117)
			(xy 16.199796 -34.18812) (xy 16.399696 -34.200134) (xy 16.599916 -34.204141) (xy 16.800136 -34.200134)
			(xy 17.000036 -34.18812) (xy 17.199294 -34.168117) (xy 17.397593 -34.140158) (xy 17.594615 -34.104287)
			(xy 17.790043 -34.060563) (xy 17.983566 -34.009054) (xy 18.174873 -33.949844) (xy 18.363657 -33.883027)
			(xy 18.549618 -33.808711) (xy 18.732456 -33.727014) (xy 18.911879 -33.638067) (xy 19.087599 -33.542012)
			(xy 19.259336 -33.439004) (xy 19.426814 -33.329208) (xy 19.589765 -33.212798) (xy 19.747927 -33.089962)
			(xy 19.901049 -32.960897) (xy 20.048884 -32.825808) (xy 20.191196 -32.684913) (xy 20.327757 -32.538437)
			(xy 20.458348 -32.386614) (xy 20.58276 -32.229688) (xy 20.700794 -32.06791) (xy 20.812261 -31.901539)
			(xy 20.916982 -31.730842) (xy 21.01479 -31.556091) (xy 21.105527 -31.377567) (xy 21.18905 -31.195555)
			(xy 21.265223 -31.010348) (xy 21.333925 -30.822241) (xy 21.395046 -30.631536) (xy 21.448488 -30.438539)
			(xy 21.494166 -30.243557) (xy 21.532006 -30.046905) (xy 21.561947 -29.848895) (xy 21.583943 -29.649847)
			(xy 21.597957 -29.450078) (xy 21.603967 -29.249908) (xy 21.601963 -29.049657) (xy 21.591949 -28.849648)
			(xy 21.573941 -28.650199) (xy 21.547967 -28.45163) (xy 21.51407 -28.25426) (xy 21.472303 -28.058403)
			(xy 21.422733 -27.864375) (xy 21.36544 -27.672485) (xy 21.300515 -27.483042) (xy 21.228063 -27.296347)
			(xy 21.148199 -27.112701) (xy 21.061052 -26.932397) (xy 20.96676 -26.755724) (xy 20.865475 -26.582966)
			(xy 20.75736 -26.414398) (xy 20.642587 -26.25029) (xy 20.521339 -26.090906) (xy 20.393812 -25.936501)
			(xy 20.260209 -25.787322) (xy 20.120745 -25.643607) (xy 19.975643 -25.505588) (xy 19.825134 -25.373484)
			(xy 19.669461 -25.247508) (xy 19.508872 -25.127862) (xy 19.343624 -25.014736) (xy 19.173983 -24.908312)
			(xy 19.000219 -24.808761) (xy 18.822612 -24.716242) (xy 18.641445 -24.630903) (xy 18.457009 -24.55288)
			(xy 18.269599 -24.4823) (xy 18.079516 -24.419274) (xy 17.887062 -24.363903) (xy 17.692548 -24.316277)
			(xy 17.496283 -24.276472) (xy 17.298584 -24.244551) (xy 17.099765 -24.220565) (xy 16.900146 -24.204553)
			(xy 16.700046 -24.196541)
		)
		(stroke
			(width 0)
			(type solid)
		)
		(fill yes)
		(layer "F.Cu")
		(net "GND")
	)
	(gr_poly
		(pts
			(arc
				(start 101.000052 -529.49094)
				(mid 102.054334 -529.054242)
				(end 102.491032 -527.99996)
			)
			(arc
				(start 102.491032 -1.999996)
				(mid 102.054334 -0.945714)
				(end 101.000052 -0.509016)
			)
			(arc
				(start 26.500074 -0.509016)
				(mid 25.799255 -0.799305)
				(end 25.508966 -1.500124)
			)
			(arc
				(start 25.508966 -2.500122)
				(mid 24.920577 -3.920619)
				(end 23.50008 -4.509008)
			)
			(arc
				(start 1.500124 -4.509008)
				(mid 0.799305 -4.799297)
				(end 0.509016 -5.500116)
			)
			(xy 0.509016 -132.686298) (xy 1.015492 -132.686298)
			(arc
				(start 1.015492 -5.514594)
				(mid 1.152021 -5.162357)
				(end 1.49987 -5.01523)
			)
			(xy 1.500124 -5.01523) (xy 1.500124 -5.015484) (xy 23.266908 -5.015484) (xy 23.266908 -5.01523)
			(arc
				(start 23.50008 -5.01523)
				(mid 25.278456 -4.278498)
				(end 26.015188 -2.500122)
			)
			(arc
				(start 26.015188 -1.500124)
				(mid 26.157044 -1.157273)
				(end 26.49982 -1.015238)
			)
			(xy 26.500074 -1.015238) (xy 26.500074 -1.015492)
			(arc
				(start 101.000052 -1.015492)
				(mid 101.696201 -1.303847)
				(end 101.984556 -1.999996)
			)
			(xy 101.984556 -486.544366) (xy 101.98481 -486.544366) (xy 101.98481 -486.547414) (xy 101.984556 -486.549954)
			(arc
				(start 101.984556 -527.99996)
				(mid 101.696201 -528.696109)
				(end 101.000052 -528.984464)
			)
			(xy 26.500074 -528.984464) (xy 26.500074 -528.984718)
			(arc
				(start 26.49982 -528.984718)
				(mid 26.157133 -528.842773)
				(end 26.015188 -528.500086)
			)
			(arc
				(start 26.015188 -527.500088)
				(mid 25.8238 -526.537447)
				(end 25.278588 -525.721326)
			)
			(arc
				(start 25.278588 -525.721326)
				(mid 24.462617 -525.176018)
				(end 23.50008 -524.984472)
			)
			(arc
				(start 1.514856 -524.984472)
				(mid 1.321364 -524.950629)
				(end 1.157224 -524.84274)
			)
			(arc
				(start 1.157224 -524.84274)
				(mid 1.052318 -524.685503)
				(end 1.015492 -524.500094)
			)
			(arc
				(start 1.015492 -408.683206)
				(mid 0.978295 -408.593403)
				(end 0.888492 -408.556206)
			)
			(arc
				(start 0.636016 -408.556206)
				(mid 0.546213 -408.593403)
				(end 0.509016 -408.683206)
			)
			(arc
				(start 0.509016 -524.500094)
				(mid 0.79923 -525.200734)
				(end 1.49987 -525.490948)
			)
			(arc
				(start 23.50008 -525.490948)
				(mid 24.920667 -526.079427)
				(end 25.508966 -527.500088)
			)
			(arc
				(start 25.508966 -528.500086)
				(mid 25.799345 -529.200741)
				(end 26.500074 -529.49094)
			)
		)
		(stroke
			(width 0)
			(type solid)
		)
		(fill yes)
		(layer "F.Cu")
		(net "GND")
	)
	(gr_poly
		(pts
			(xy 7.438644 -202.378564) (xy 8.008112 -201.809096) (xy 9.609328 -201.809096) (xy 13.27404 -198.144384)
			(xy 20.531582 -198.144384) (xy 21.171408 -197.504558) (xy 21.171408 -184.488582) (xy 16.955262 -180.272436)
			(xy 8.193024 -180.272436) (xy 7.281672 -181.183788) (xy 3.824732 -181.183788) (xy 3.425444 -180.7845)
			(xy 3.408804 -180.768537) (xy 3.370883 -180.742312) (xy 3.328853 -180.723356) (xy 3.284093 -180.712293)
			(xy 3.238072 -180.709485) (xy 3.192299 -180.715023) (xy 3.148276 -180.728727) (xy 3.107447 -180.750147)
			(xy 3.071151 -180.778579) (xy 3.040579 -180.813093) (xy 3.016734 -180.852554) (xy 3.000397 -180.89567)
			(xy 2.992105 -180.941024) (xy 2.991612 -180.964078) (xy 2.991612 -182.09514) (xy 2.592578 -182.494174)
			(xy 2.573782 -182.550816) (xy 2.5781 -182.580534) (xy 2.582604 -182.615389) (xy 2.584809 -182.685637)
			(xy 2.57925 -182.7557) (xy 2.565995 -182.824721) (xy 2.545206 -182.891859) (xy 2.517138 -182.956294)
			(xy 2.482132 -183.017239) (xy 2.440616 -183.07395) (xy 2.393097 -183.125734) (xy 2.340155 -183.17196)
			(xy 2.282436 -183.212063) (xy 2.220646 -183.245553) (xy 2.155538 -183.272022) (xy 2.087907 -183.291146)
			(xy 2.018579 -183.302693) (xy 1.9484 -183.30652) (xy 1.878228 -183.302582) (xy 1.808918 -183.290926)
			(xy 1.741318 -183.271695) (xy 1.676252 -183.245123) (xy 1.645158 -183.228742) (xy 1.625698 -183.218703)
			(xy 1.584205 -183.204724) (xy 1.540931 -183.198064) (xy 1.497155 -183.19892) (xy 1.454174 -183.207267)
			(xy 1.413259 -183.222857) (xy 1.375623 -183.245229) (xy 1.342377 -183.273721) (xy 1.314508 -183.30749)
			(xy 1.292839 -183.345536) (xy 1.278012 -183.386734) (xy 1.270465 -183.429862) (xy 1.27 -183.451754)
			(xy 1.27 -183.706109) (xy 3.31393 -183.706109) (xy 3.31393 -183.634787) (xy 3.321916 -183.563913)
			(xy 3.337786 -183.494378) (xy 3.361343 -183.427058) (xy 3.392288 -183.362799) (xy 3.430234 -183.302408)
			(xy 3.474703 -183.246646) (xy 3.525136 -183.196213) (xy 3.580898 -183.151744) (xy 3.641289 -183.113798)
			(xy 3.705548 -183.082853) (xy 3.772868 -183.059296) (xy 3.842403 -183.043426) (xy 3.913277 -183.03544)
			(xy 3.984599 -183.03544) (xy 4.055473 -183.043426) (xy 4.125008 -183.059296) (xy 4.192328 -183.082853)
			(xy 4.256587 -183.113798) (xy 4.316978 -183.151744) (xy 4.37274 -183.196213) (xy 4.423173 -183.246646)
			(xy 4.467642 -183.302408) (xy 4.505588 -183.362799) (xy 4.536533 -183.427058) (xy 4.56009 -183.494378)
			(xy 4.57596 -183.563913) (xy 4.583946 -183.634787) (xy 4.584446 -183.670448) (xy 4.583946 -183.706109)
			(xy 5.813798 -183.706109) (xy 5.813798 -183.634787) (xy 5.821784 -183.563913) (xy 5.837654 -183.494378)
			(xy 5.861211 -183.427058) (xy 5.892156 -183.362799) (xy 5.930102 -183.302408) (xy 5.974571 -183.246646)
			(xy 6.025004 -183.196213) (xy 6.080766 -183.151744) (xy 6.141157 -183.113798) (xy 6.205416 -183.082853)
			(xy 6.272736 -183.059296) (xy 6.342271 -183.043426) (xy 6.413145 -183.03544) (xy 6.484467 -183.03544)
			(xy 6.555341 -183.043426) (xy 6.624876 -183.059296) (xy 6.692196 -183.082853) (xy 6.756455 -183.113798)
			(xy 6.816846 -183.151744) (xy 6.872608 -183.196213) (xy 6.923041 -183.246646) (xy 6.96751 -183.302408)
			(xy 7.005456 -183.362799) (xy 7.036401 -183.427058) (xy 7.059958 -183.494378) (xy 7.075828 -183.563913)
			(xy 7.083814 -183.634787) (xy 7.084314 -183.670448) (xy 7.083814 -183.706109) (xy 7.075828 -183.776983)
			(xy 7.059958 -183.846518) (xy 7.036401 -183.913838) (xy 7.005456 -183.978097) (xy 6.96751 -184.038488)
			(xy 6.923041 -184.09425) (xy 6.872608 -184.144683) (xy 6.816846 -184.189152) (xy 6.756455 -184.227098)
			(xy 6.692196 -184.258043) (xy 6.624876 -184.2816) (xy 6.555341 -184.29747) (xy 6.484467 -184.305456)
			(xy 6.413145 -184.305456) (xy 6.342271 -184.29747) (xy 6.272736 -184.2816) (xy 6.205416 -184.258043)
			(xy 6.141157 -184.227098) (xy 6.080766 -184.189152) (xy 6.025004 -184.144683) (xy 5.974571 -184.09425)
			(xy 5.930102 -184.038488) (xy 5.892156 -183.978097) (xy 5.861211 -183.913838) (xy 5.837654 -183.846518)
			(xy 5.821784 -183.776983) (xy 5.813798 -183.706109) (xy 4.583946 -183.706109) (xy 4.57596 -183.776983)
			(xy 4.56009 -183.846518) (xy 4.536533 -183.913838) (xy 4.505588 -183.978097) (xy 4.467642 -184.038488)
			(xy 4.423173 -184.09425) (xy 4.37274 -184.144683) (xy 4.316978 -184.189152) (xy 4.256587 -184.227098)
			(xy 4.192328 -184.258043) (xy 4.125008 -184.2816) (xy 4.055473 -184.29747) (xy 3.984599 -184.305456)
			(xy 3.913277 -184.305456) (xy 3.842403 -184.29747) (xy 3.772868 -184.2816) (xy 3.705548 -184.258043)
			(xy 3.641289 -184.227098) (xy 3.580898 -184.189152) (xy 3.525136 -184.144683) (xy 3.474703 -184.09425)
			(xy 3.430234 -184.038488) (xy 3.392288 -183.978097) (xy 3.361343 -183.913838) (xy 3.337786 -183.846518)
			(xy 3.321916 -183.776983) (xy 3.31393 -183.706109) (xy 1.27 -183.706109) (xy 1.27 -183.889142) (xy 1.27045 -183.911045)
			(xy 1.277949 -183.954204) (xy 1.292744 -183.995435) (xy 1.314396 -184.033515) (xy 1.342263 -184.067314)
			(xy 1.375517 -184.095829) (xy 1.413172 -184.118212) (xy 1.45411 -184.133801) (xy 1.497116 -184.142132)
			(xy 1.540913 -184.142957) (xy 1.584203 -184.136254) (xy 1.625699 -184.122219) (xy 1.645158 -184.112154)
			(xy 1.676623 -184.095595) (xy 1.742485 -184.068793) (xy 1.810926 -184.049509) (xy 1.881092 -184.037985)
			(xy 1.952106 -184.034363) (xy 2.02308 -184.038691) (xy 2.093128 -184.050913) (xy 2.161374 -184.070876)
			(xy 2.226966 -184.098332) (xy 2.289083 -184.132938) (xy 2.34695 -184.17426) (xy 2.399843 -184.221782)
			(xy 2.447102 -184.274911) (xy 2.488136 -184.332983) (xy 2.522431 -184.395271) (xy 2.549561 -184.460999)
			(xy 2.569185 -184.529343) (xy 2.581058 -184.599451) (xy 2.585033 -184.670446) (xy 2.583036 -184.706107)
			(xy 7.813794 -184.706107) (xy 7.813794 -184.634785) (xy 7.82178 -184.563911) (xy 7.83765 -184.494376)
			(xy 7.861207 -184.427056) (xy 7.892152 -184.362797) (xy 7.930098 -184.302406) (xy 7.974567 -184.246644)
			(xy 8.025 -184.196211) (xy 8.080762 -184.151742) (xy 8.141153 -184.113796) (xy 8.205412 -184.082851)
			(xy 8.272732 -184.059294) (xy 8.342267 -184.043424) (xy 8.413141 -184.035438) (xy 8.484463 -184.035438)
			(xy 8.555337 -184.043424) (xy 8.624872 -184.059294) (xy 8.692192 -184.082851) (xy 8.756451 -184.113796)
			(xy 8.816842 -184.151742) (xy 8.872604 -184.196211) (xy 8.923037 -184.246644) (xy 8.967506 -184.302406)
			(xy 9.005452 -184.362797) (xy 9.036397 -184.427056) (xy 9.059954 -184.494376) (xy 9.075824 -184.563911)
			(xy 9.08381 -184.634785) (xy 9.08431 -184.670446) (xy 9.08381 -184.706107) (xy 9.075824 -184.776981)
			(xy 9.059954 -184.846516) (xy 9.036397 -184.913836) (xy 9.005452 -184.978095) (xy 8.967506 -185.038486)
			(xy 8.923037 -185.094248) (xy 8.872604 -185.144681) (xy 8.816842 -185.18915) (xy 8.756451 -185.227096)
			(xy 8.692192 -185.258041) (xy 8.624872 -185.281598) (xy 8.555337 -185.297468) (xy 8.484463 -185.305454)
			(xy 8.413141 -185.305454) (xy 8.342267 -185.297468) (xy 8.272732 -185.281598) (xy 8.205412 -185.258041)
			(xy 8.141153 -185.227096) (xy 8.080762 -185.18915) (xy 8.025 -185.144681) (xy 7.974567 -185.094248)
			(xy 7.930098 -185.038486) (xy 7.892152 -184.978095) (xy 7.861207 -184.913836) (xy 7.83765 -184.846516)
			(xy 7.82178 -184.776981) (xy 7.813794 -184.706107) (xy 2.583036 -184.706107) (xy 2.581058 -184.741441)
			(xy 2.569185 -184.811549) (xy 2.549561 -184.879893) (xy 2.522431 -184.945621) (xy 2.488136 -185.007909)
			(xy 2.447102 -185.065981) (xy 2.399843 -185.11911) (xy 2.34695 -185.166632) (xy 2.289083 -185.207954)
			(xy 2.226966 -185.24256) (xy 2.161374 -185.270016) (xy 2.093128 -185.289979) (xy 2.02308 -185.302201)
			(xy 1.952106 -185.306529) (xy 1.881092 -185.302907) (xy 1.810926 -185.291383) (xy 1.742485 -185.272099)
			(xy 1.676623 -185.245297) (xy 1.645158 -185.228738) (xy 1.625698 -185.218699) (xy 1.584205 -185.20472)
			(xy 1.54093 -185.198061) (xy 1.497154 -185.198917) (xy 1.454173 -185.207263) (xy 1.413259 -185.222853)
			(xy 1.375622 -185.245226) (xy 1.342376 -185.273718) (xy 1.314506 -185.307486) (xy 1.292837 -185.345532)
			(xy 1.278009 -185.386729) (xy 1.270462 -185.429858) (xy 1.27 -185.45175) (xy 1.27 -185.706105) (xy 3.31393 -185.706105)
			(xy 3.31393 -185.634783) (xy 3.321916 -185.563909) (xy 3.337786 -185.494374) (xy 3.361343 -185.427054)
			(xy 3.392288 -185.362795) (xy 3.430234 -185.302404) (xy 3.474703 -185.246642) (xy 3.525136 -185.196209)
			(xy 3.580898 -185.15174) (xy 3.641289 -185.113794) (xy 3.705548 -185.082849) (xy 3.772868 -185.059292)
			(xy 3.842403 -185.043422) (xy 3.913277 -185.035436) (xy 3.984599 -185.035436) (xy 4.055473 -185.043422)
			(xy 4.125008 -185.059292) (xy 4.192328 -185.082849) (xy 4.256587 -185.113794) (xy 4.316978 -185.15174)
			(xy 4.37274 -185.196209) (xy 4.423173 -185.246642) (xy 4.467642 -185.302404) (xy 4.505588 -185.362795)
			(xy 4.536533 -185.427054) (xy 4.56009 -185.494374) (xy 4.57596 -185.563909) (xy 4.583946 -185.634783)
			(xy 4.584446 -185.670444) (xy 4.583946 -185.706105) (xy 5.813798 -185.706105) (xy 5.813798 -185.634783)
			(xy 5.821784 -185.563909) (xy 5.837654 -185.494374) (xy 5.861211 -185.427054) (xy 5.892156 -185.362795)
			(xy 5.930102 -185.302404) (xy 5.974571 -185.246642) (xy 6.025004 -185.196209) (xy 6.080766 -185.15174)
			(xy 6.141157 -185.113794) (xy 6.205416 -185.082849) (xy 6.272736 -185.059292) (xy 6.342271 -185.043422)
			(xy 6.413145 -185.035436) (xy 6.484467 -185.035436) (xy 6.555341 -185.043422) (xy 6.624876 -185.059292)
			(xy 6.692196 -185.082849) (xy 6.756455 -185.113794) (xy 6.816846 -185.15174) (xy 6.872608 -185.196209)
			(xy 6.923041 -185.246642) (xy 6.96751 -185.302404) (xy 7.005456 -185.362795) (xy 7.036401 -185.427054)
			(xy 7.059958 -185.494374) (xy 7.075828 -185.563909) (xy 7.083814 -185.634783) (xy 7.084314 -185.670444)
			(xy 7.083814 -185.706105) (xy 7.075828 -185.776979) (xy 7.059958 -185.846514) (xy 7.036401 -185.913834)
			(xy 7.005456 -185.978093) (xy 6.96751 -186.038484) (xy 6.923041 -186.094246) (xy 6.872608 -186.144679)
			(xy 6.816846 -186.189148) (xy 6.756455 -186.227094) (xy 6.692196 -186.258039) (xy 6.624876 -186.281596)
			(xy 6.555341 -186.297466) (xy 6.484467 -186.305452) (xy 6.413145 -186.305452) (xy 6.342271 -186.297466)
			(xy 6.272736 -186.281596) (xy 6.205416 -186.258039) (xy 6.141157 -186.227094) (xy 6.080766 -186.189148)
			(xy 6.025004 -186.144679) (xy 5.974571 -186.094246) (xy 5.930102 -186.038484) (xy 5.892156 -185.978093)
			(xy 5.861211 -185.913834) (xy 5.837654 -185.846514) (xy 5.821784 -185.776979) (xy 5.813798 -185.706105)
			(xy 4.583946 -185.706105) (xy 4.57596 -185.776979) (xy 4.56009 -185.846514) (xy 4.536533 -185.913834)
			(xy 4.505588 -185.978093) (xy 4.467642 -186.038484) (xy 4.423173 -186.094246) (xy 4.37274 -186.144679)
			(xy 4.316978 -186.189148) (xy 4.256587 -186.227094) (xy 4.192328 -186.258039) (xy 4.125008 -186.281596)
			(xy 4.055473 -186.297466) (xy 3.984599 -186.305452) (xy 3.913277 -186.305452) (xy 3.842403 -186.297466)
			(xy 3.772868 -186.281596) (xy 3.705548 -186.258039) (xy 3.641289 -186.227094) (xy 3.580898 -186.189148)
			(xy 3.525136 -186.144679) (xy 3.474703 -186.094246) (xy 3.430234 -186.038484) (xy 3.392288 -185.978093)
			(xy 3.361343 -185.913834) (xy 3.337786 -185.846514) (xy 3.321916 -185.776979) (xy 3.31393 -185.706105)
			(xy 1.27 -185.706105) (xy 1.27 -185.889138) (xy 1.270451 -185.911041) (xy 1.27795 -185.954199) (xy 1.292746 -185.995429)
			(xy 1.314398 -186.033508) (xy 1.342265 -186.067306) (xy 1.375519 -186.09582) (xy 1.413173 -186.118203)
			(xy 1.45411 -186.133791) (xy 1.497116 -186.142122) (xy 1.540912 -186.142947) (xy 1.584201 -186.136244)
			(xy 1.625697 -186.12221) (xy 1.645158 -186.11215) (xy 1.676623 -186.095591) (xy 1.742484 -186.068789)
			(xy 1.810925 -186.049506) (xy 1.881091 -186.037981) (xy 1.952104 -186.03436) (xy 2.023078 -186.038687)
			(xy 2.093126 -186.050909) (xy 2.161371 -186.070873) (xy 2.226963 -186.098329) (xy 2.289079 -186.132934)
			(xy 2.346946 -186.174256) (xy 2.399839 -186.221778) (xy 2.447098 -186.274906) (xy 2.488131 -186.332978)
			(xy 2.522427 -186.395266) (xy 2.549556 -186.460993) (xy 2.56918 -186.529337) (xy 2.581053 -186.599444)
			(xy 2.585028 -186.670439) (xy 2.583032 -186.706103) (xy 7.813794 -186.706103) (xy 7.813794 -186.634781)
			(xy 7.82178 -186.563907) (xy 7.83765 -186.494372) (xy 7.861207 -186.427052) (xy 7.892152 -186.362793)
			(xy 7.930098 -186.302402) (xy 7.974567 -186.24664) (xy 8.025 -186.196207) (xy 8.080762 -186.151738)
			(xy 8.141153 -186.113792) (xy 8.205412 -186.082847) (xy 8.272732 -186.05929) (xy 8.342267 -186.04342)
			(xy 8.413141 -186.035434) (xy 8.484463 -186.035434) (xy 8.555337 -186.04342) (xy 8.624872 -186.05929)
			(xy 8.692192 -186.082847) (xy 8.756451 -186.113792) (xy 8.816842 -186.151738) (xy 8.872604 -186.196207)
			(xy 8.923037 -186.24664) (xy 8.967506 -186.302402) (xy 9.005452 -186.362793) (xy 9.036397 -186.427052)
			(xy 9.059954 -186.494372) (xy 9.075824 -186.563907) (xy 9.08381 -186.634781) (xy 9.08431 -186.670442)
			(xy 9.08381 -186.706103) (xy 9.075824 -186.776977) (xy 9.059954 -186.846512) (xy 9.036397 -186.913832)
			(xy 9.005452 -186.978091) (xy 8.967506 -187.038482) (xy 8.923037 -187.094244) (xy 8.872604 -187.144677)
			(xy 8.816842 -187.189146) (xy 8.756451 -187.227092) (xy 8.692192 -187.258037) (xy 8.624872 -187.281594)
			(xy 8.555337 -187.297464) (xy 8.484463 -187.30545) (xy 8.413141 -187.30545) (xy 8.342267 -187.297464)
			(xy 8.272732 -187.281594) (xy 8.205412 -187.258037) (xy 8.141153 -187.227092) (xy 8.080762 -187.189146)
			(xy 8.025 -187.144677) (xy 7.974567 -187.094244) (xy 7.930098 -187.038482) (xy 7.892152 -186.978091)
			(xy 7.861207 -186.913832) (xy 7.83765 -186.846512) (xy 7.82178 -186.776977) (xy 7.813794 -186.706103)
			(xy 2.583032 -186.706103) (xy 2.581054 -186.741434) (xy 2.56918 -186.811541) (xy 2.549557 -186.879885)
			(xy 2.522428 -186.945612) (xy 2.488132 -187.007901) (xy 2.447099 -187.065972) (xy 2.39984 -187.119101)
			(xy 2.346947 -187.166623) (xy 2.289081 -187.207945) (xy 2.226964 -187.24255) (xy 2.161373 -187.270006)
			(xy 2.093127 -187.28997) (xy 2.02308 -187.302192) (xy 1.952106 -187.30652) (xy 1.881093 -187.302899)
			(xy 1.810927 -187.291375) (xy 1.742486 -187.272091) (xy 1.676625 -187.24529) (xy 1.645158 -187.228734)
			(xy 1.625698 -187.218695) (xy 1.584205 -187.204717) (xy 1.54093 -187.198057) (xy 1.497154 -187.198913)
			(xy 1.454172 -187.20726) (xy 1.413258 -187.22285) (xy 1.375621 -187.245222) (xy 1.342375 -187.273714)
			(xy 1.314505 -187.307483) (xy 1.292835 -187.345528) (xy 1.278006 -187.386725) (xy 1.270459 -187.429854)
			(xy 1.27 -187.451746) (xy 1.27 -187.706101) (xy 3.31393 -187.706101) (xy 3.31393 -187.634779) (xy 3.321916 -187.563905)
			(xy 3.337786 -187.49437) (xy 3.361343 -187.42705) (xy 3.392288 -187.362791) (xy 3.430234 -187.3024)
			(xy 3.474703 -187.246638) (xy 3.525136 -187.196205) (xy 3.580898 -187.151736) (xy 3.641289 -187.11379)
			(xy 3.705548 -187.082845) (xy 3.772868 -187.059288) (xy 3.842403 -187.043418) (xy 3.913277 -187.035432)
			(xy 3.984599 -187.035432) (xy 4.055473 -187.043418) (xy 4.125008 -187.059288) (xy 4.192328 -187.082845)
			(xy 4.256587 -187.11379) (xy 4.316978 -187.151736) (xy 4.37274 -187.196205) (xy 4.423173 -187.246638)
			(xy 4.467642 -187.3024) (xy 4.505588 -187.362791) (xy 4.536533 -187.42705) (xy 4.56009 -187.49437)
			(xy 4.57596 -187.563905) (xy 4.583946 -187.634779) (xy 4.584446 -187.67044) (xy 4.583946 -187.706101)
			(xy 5.813798 -187.706101) (xy 5.813798 -187.634779) (xy 5.821784 -187.563905) (xy 5.837654 -187.49437)
			(xy 5.861211 -187.42705) (xy 5.892156 -187.362791) (xy 5.930102 -187.3024) (xy 5.974571 -187.246638)
			(xy 6.025004 -187.196205) (xy 6.080766 -187.151736) (xy 6.141157 -187.11379) (xy 6.205416 -187.082845)
			(xy 6.272736 -187.059288) (xy 6.342271 -187.043418) (xy 6.413145 -187.035432) (xy 6.484467 -187.035432)
			(xy 6.555341 -187.043418) (xy 6.624876 -187.059288) (xy 6.692196 -187.082845) (xy 6.756455 -187.11379)
			(xy 6.816846 -187.151736) (xy 6.872608 -187.196205) (xy 6.923041 -187.246638) (xy 6.96751 -187.3024)
			(xy 7.005456 -187.362791) (xy 7.036401 -187.42705) (xy 7.059958 -187.49437) (xy 7.075828 -187.563905)
			(xy 7.083814 -187.634779) (xy 7.084314 -187.67044) (xy 7.083814 -187.706101) (xy 7.075828 -187.776975)
			(xy 7.059958 -187.84651) (xy 7.036401 -187.91383) (xy 7.005456 -187.978089) (xy 6.96751 -188.03848)
			(xy 6.923041 -188.094242) (xy 6.872608 -188.144675) (xy 6.816846 -188.189144) (xy 6.756455 -188.22709)
			(xy 6.692196 -188.258035) (xy 6.624876 -188.281592) (xy 6.555341 -188.297462) (xy 6.484467 -188.305448)
			(xy 6.413145 -188.305448) (xy 6.342271 -188.297462) (xy 6.272736 -188.281592) (xy 6.205416 -188.258035)
			(xy 6.141157 -188.22709) (xy 6.080766 -188.189144) (xy 6.025004 -188.144675) (xy 5.974571 -188.094242)
			(xy 5.930102 -188.03848) (xy 5.892156 -187.978089) (xy 5.861211 -187.91383) (xy 5.837654 -187.84651)
			(xy 5.821784 -187.776975) (xy 5.813798 -187.706101) (xy 4.583946 -187.706101) (xy 4.57596 -187.776975)
			(xy 4.56009 -187.84651) (xy 4.536533 -187.91383) (xy 4.505588 -187.978089) (xy 4.467642 -188.03848)
			(xy 4.423173 -188.094242) (xy 4.37274 -188.144675) (xy 4.316978 -188.189144) (xy 4.256587 -188.22709)
			(xy 4.192328 -188.258035) (xy 4.125008 -188.281592) (xy 4.055473 -188.297462) (xy 3.984599 -188.305448)
			(xy 3.913277 -188.305448) (xy 3.842403 -188.297462) (xy 3.772868 -188.281592) (xy 3.705548 -188.258035)
			(xy 3.641289 -188.22709) (xy 3.580898 -188.189144) (xy 3.525136 -188.144675) (xy 3.474703 -188.094242)
			(xy 3.430234 -188.03848) (xy 3.392288 -187.978089) (xy 3.361343 -187.91383) (xy 3.337786 -187.84651)
			(xy 3.321916 -187.776975) (xy 3.31393 -187.706101) (xy 1.27 -187.706101) (xy 1.27 -187.889134) (xy 1.270451 -187.911037)
			(xy 1.277949 -187.954195) (xy 1.292744 -187.995427) (xy 1.314397 -188.033506) (xy 1.342263 -188.067305)
			(xy 1.375517 -188.095819) (xy 1.413172 -188.118202) (xy 1.45411 -188.133791) (xy 1.497116 -188.142122)
			(xy 1.540913 -188.142947) (xy 1.584202 -188.136244) (xy 1.625699 -188.12221) (xy 1.645158 -188.112146)
			(xy 1.676623 -188.095587) (xy 1.742485 -188.068785) (xy 1.810926 -188.049502) (xy 1.881092 -188.037977)
			(xy 1.952106 -188.034357) (xy 2.02308 -188.038684) (xy 2.093128 -188.050906) (xy 2.161374 -188.07087)
			(xy 2.226966 -188.098327) (xy 2.289083 -188.132932) (xy 2.34695 -188.174254) (xy 2.399843 -188.221777)
			(xy 2.447101 -188.274906) (xy 2.488135 -188.332978) (xy 2.522431 -188.395266) (xy 2.54956 -188.460994)
			(xy 2.569184 -188.529338) (xy 2.581057 -188.599446) (xy 2.585031 -188.670441) (xy 2.583035 -188.706099)
			(xy 7.813794 -188.706099) (xy 7.813794 -188.634777) (xy 7.82178 -188.563903) (xy 7.83765 -188.494368)
			(xy 7.861207 -188.427048) (xy 7.892152 -188.362789) (xy 7.930098 -188.302398) (xy 7.974567 -188.246636)
			(xy 8.025 -188.196203) (xy 8.080762 -188.151734) (xy 8.141153 -188.113788) (xy 8.205412 -188.082843)
			(xy 8.272732 -188.059286) (xy 8.342267 -188.043416) (xy 8.413141 -188.03543) (xy 8.484463 -188.03543)
			(xy 8.555337 -188.043416) (xy 8.624872 -188.059286) (xy 8.692192 -188.082843) (xy 8.756451 -188.113788)
			(xy 8.816842 -188.151734) (xy 8.872604 -188.196203) (xy 8.923037 -188.246636) (xy 8.967506 -188.302398)
			(xy 9.005452 -188.362789) (xy 9.036397 -188.427048) (xy 9.059954 -188.494368) (xy 9.075824 -188.563903)
			(xy 9.08381 -188.634777) (xy 9.08431 -188.670438) (xy 9.08381 -188.706099) (xy 9.075824 -188.776973)
			(xy 9.059954 -188.846508) (xy 9.036397 -188.913828) (xy 9.005452 -188.978087) (xy 8.967506 -189.038478)
			(xy 8.923037 -189.09424) (xy 8.872604 -189.144673) (xy 8.816842 -189.189142) (xy 8.756451 -189.227088)
			(xy 8.692192 -189.258033) (xy 8.624872 -189.28159) (xy 8.555337 -189.29746) (xy 8.484463 -189.305446)
			(xy 8.413141 -189.305446) (xy 8.342267 -189.29746) (xy 8.272732 -189.28159) (xy 8.205412 -189.258033)
			(xy 8.141153 -189.227088) (xy 8.080762 -189.189142) (xy 8.025 -189.144673) (xy 7.974567 -189.09424)
			(xy 7.930098 -189.038478) (xy 7.892152 -188.978087) (xy 7.861207 -188.913828) (xy 7.83765 -188.846508)
			(xy 7.82178 -188.776973) (xy 7.813794 -188.706099) (xy 2.583035 -188.706099) (xy 2.581057 -188.741436)
			(xy 2.569183 -188.811544) (xy 2.549559 -188.879888) (xy 2.52243 -188.945615) (xy 2.488134 -189.007904)
			(xy 2.4471 -189.065976) (xy 2.399841 -189.119105) (xy 2.346948 -189.166627) (xy 2.289081 -189.207949)
			(xy 2.226964 -189.242554) (xy 2.161373 -189.27001) (xy 2.093126 -189.289974) (xy 2.023079 -189.302196)
			(xy 1.952104 -189.306523) (xy 1.88109 -189.302902) (xy 1.810924 -189.291378) (xy 1.742483 -189.272094)
			(xy 1.676622 -189.245292) (xy 1.645158 -189.22873) (xy 1.625698 -189.218691) (xy 1.584204 -189.204713)
			(xy 1.540929 -189.198054) (xy 1.497153 -189.19891) (xy 1.454172 -189.207256) (xy 1.413257 -189.222846)
			(xy 1.37562 -189.245218) (xy 1.342374 -189.27371) (xy 1.314503 -189.307479) (xy 1.292833 -189.345524)
			(xy 1.278004 -189.386721) (xy 1.270456 -189.42985) (xy 1.27 -189.451742) (xy 1.27 -189.706097) (xy 3.31393 -189.706097)
			(xy 3.31393 -189.634775) (xy 3.321916 -189.563901) (xy 3.337786 -189.494366) (xy 3.361343 -189.427046)
			(xy 3.392288 -189.362787) (xy 3.430234 -189.302396) (xy 3.474703 -189.246634) (xy 3.525136 -189.196201)
			(xy 3.580898 -189.151732) (xy 3.641289 -189.113786) (xy 3.705548 -189.082841) (xy 3.772868 -189.059284)
			(xy 3.842403 -189.043414) (xy 3.913277 -189.035428) (xy 3.984599 -189.035428) (xy 4.055473 -189.043414)
			(xy 4.125008 -189.059284) (xy 4.192328 -189.082841) (xy 4.256587 -189.113786) (xy 4.316978 -189.151732)
			(xy 4.37274 -189.196201) (xy 4.423173 -189.246634) (xy 4.467642 -189.302396) (xy 4.505588 -189.362787)
			(xy 4.536533 -189.427046) (xy 4.56009 -189.494366) (xy 4.57596 -189.563901) (xy 4.583946 -189.634775)
			(xy 4.584446 -189.670436) (xy 4.583946 -189.706097) (xy 5.813798 -189.706097) (xy 5.813798 -189.634775)
			(xy 5.821784 -189.563901) (xy 5.837654 -189.494366) (xy 5.861211 -189.427046) (xy 5.892156 -189.362787)
			(xy 5.930102 -189.302396) (xy 5.974571 -189.246634) (xy 6.025004 -189.196201) (xy 6.080766 -189.151732)
			(xy 6.141157 -189.113786) (xy 6.205416 -189.082841) (xy 6.272736 -189.059284) (xy 6.342271 -189.043414)
			(xy 6.413145 -189.035428) (xy 6.484467 -189.035428) (xy 6.555341 -189.043414) (xy 6.624876 -189.059284)
			(xy 6.692196 -189.082841) (xy 6.756455 -189.113786) (xy 6.816846 -189.151732) (xy 6.872608 -189.196201)
			(xy 6.923041 -189.246634) (xy 6.96751 -189.302396) (xy 7.005456 -189.362787) (xy 7.036401 -189.427046)
			(xy 7.059958 -189.494366) (xy 7.075828 -189.563901) (xy 7.083814 -189.634775) (xy 7.084314 -189.670436)
			(xy 7.083814 -189.706097) (xy 7.075828 -189.776971) (xy 7.059958 -189.846506) (xy 7.036401 -189.913826)
			(xy 7.005456 -189.978085) (xy 6.96751 -190.038476) (xy 6.923041 -190.094238) (xy 6.872608 -190.144671)
			(xy 6.816846 -190.18914) (xy 6.756455 -190.227086) (xy 6.692196 -190.258031) (xy 6.624876 -190.281588)
			(xy 6.555341 -190.297458) (xy 6.484467 -190.305444) (xy 6.413145 -190.305444) (xy 6.342271 -190.297458)
			(xy 6.272736 -190.281588) (xy 6.205416 -190.258031) (xy 6.141157 -190.227086) (xy 6.080766 -190.18914)
			(xy 6.025004 -190.144671) (xy 5.974571 -190.094238) (xy 5.930102 -190.038476) (xy 5.892156 -189.978085)
			(xy 5.861211 -189.913826) (xy 5.837654 -189.846506) (xy 5.821784 -189.776971) (xy 5.813798 -189.706097)
			(xy 4.583946 -189.706097) (xy 4.57596 -189.776971) (xy 4.56009 -189.846506) (xy 4.536533 -189.913826)
			(xy 4.505588 -189.978085) (xy 4.467642 -190.038476) (xy 4.423173 -190.094238) (xy 4.37274 -190.144671)
			(xy 4.316978 -190.18914) (xy 4.256587 -190.227086) (xy 4.192328 -190.258031) (xy 4.125008 -190.281588)
			(xy 4.055473 -190.297458) (xy 3.984599 -190.305444) (xy 3.913277 -190.305444) (xy 3.842403 -190.297458)
			(xy 3.772868 -190.281588) (xy 3.705548 -190.258031) (xy 3.641289 -190.227086) (xy 3.580898 -190.18914)
			(xy 3.525136 -190.144671) (xy 3.474703 -190.094238) (xy 3.430234 -190.038476) (xy 3.392288 -189.978085)
			(xy 3.361343 -189.913826) (xy 3.337786 -189.846506) (xy 3.321916 -189.776971) (xy 3.31393 -189.706097)
			(xy 1.27 -189.706097) (xy 1.27 -189.88913) (xy 1.27045 -189.911033) (xy 1.277949 -189.954192) (xy 1.292743 -189.995424)
			(xy 1.314395 -190.033505) (xy 1.342262 -190.067304) (xy 1.375516 -190.095818) (xy 1.413171 -190.118202)
			(xy 1.45411 -190.133791) (xy 1.497116 -190.142122) (xy 1.540914 -190.142947) (xy 1.584204 -190.136243)
			(xy 1.6257 -190.122209) (xy 1.645158 -190.112142) (xy 1.676623 -190.095583) (xy 1.742485 -190.068781)
			(xy 1.810926 -190.049497) (xy 1.881092 -190.037973) (xy 1.952106 -190.034351) (xy 2.02308 -190.038679)
			(xy 2.093128 -190.050901) (xy 2.161374 -190.070864) (xy 2.226966 -190.09832) (xy 2.289083 -190.132926)
			(xy 2.34695 -190.174248) (xy 2.399843 -190.22177) (xy 2.447102 -190.274899) (xy 2.488136 -190.332971)
			(xy 2.522431 -190.395259) (xy 2.549561 -190.460987) (xy 2.569185 -190.529331) (xy 2.581058 -190.599439)
			(xy 2.585033 -190.670434) (xy 2.583036 -190.706095) (xy 7.813794 -190.706095) (xy 7.813794 -190.634773)
			(xy 7.82178 -190.563899) (xy 7.83765 -190.494364) (xy 7.861207 -190.427044) (xy 7.892152 -190.362785)
			(xy 7.930098 -190.302394) (xy 7.974567 -190.246632) (xy 8.025 -190.196199) (xy 8.080762 -190.15173)
			(xy 8.141153 -190.113784) (xy 8.205412 -190.082839) (xy 8.272732 -190.059282) (xy 8.342267 -190.043412)
			(xy 8.413141 -190.035426) (xy 8.484463 -190.035426) (xy 8.555337 -190.043412) (xy 8.624872 -190.059282)
			(xy 8.692192 -190.082839) (xy 8.756451 -190.113784) (xy 8.816842 -190.15173) (xy 8.872604 -190.196199)
			(xy 8.923037 -190.246632) (xy 8.967506 -190.302394) (xy 9.005452 -190.362785) (xy 9.036397 -190.427044)
			(xy 9.059954 -190.494364) (xy 9.075824 -190.563899) (xy 9.08381 -190.634773) (xy 9.08431 -190.670434)
			(xy 9.08381 -190.706095) (xy 9.075824 -190.776969) (xy 9.059954 -190.846504) (xy 9.036397 -190.913824)
			(xy 9.005452 -190.978083) (xy 8.967506 -191.038474) (xy 8.923037 -191.094236) (xy 8.872604 -191.144669)
			(xy 8.816842 -191.189138) (xy 8.756451 -191.227084) (xy 8.692192 -191.258029) (xy 8.624872 -191.281586)
			(xy 8.555337 -191.297456) (xy 8.484463 -191.305442) (xy 8.413141 -191.305442) (xy 8.342267 -191.297456)
			(xy 8.272732 -191.281586) (xy 8.205412 -191.258029) (xy 8.141153 -191.227084) (xy 8.080762 -191.189138)
			(xy 8.025 -191.144669) (xy 7.974567 -191.094236) (xy 7.930098 -191.038474) (xy 7.892152 -190.978083)
			(xy 7.861207 -190.913824) (xy 7.83765 -190.846504) (xy 7.82178 -190.776969) (xy 7.813794 -190.706095)
			(xy 2.583036 -190.706095) (xy 2.581058 -190.741429) (xy 2.569185 -190.811537) (xy 2.549561 -190.879881)
			(xy 2.522431 -190.945609) (xy 2.488136 -191.007897) (xy 2.447102 -191.065969) (xy 2.399843 -191.119098)
			(xy 2.34695 -191.16662) (xy 2.289083 -191.207942) (xy 2.226966 -191.242548) (xy 2.161374 -191.270004)
			(xy 2.093128 -191.289967) (xy 2.02308 -191.302189) (xy 1.952106 -191.306517) (xy 1.881092 -191.302895)
			(xy 1.810926 -191.291371) (xy 1.742485 -191.272087) (xy 1.676623 -191.245285) (xy 1.645158 -191.228726)
			(xy 1.625698 -191.218687) (xy 1.584204 -191.204709) (xy 1.540929 -191.19805) (xy 1.497153 -191.198906)
			(xy 1.454171 -191.207253) (xy 1.413256 -191.222843) (xy 1.375619 -191.245215) (xy 1.342372 -191.273707)
			(xy 1.314501 -191.307475) (xy 1.292831 -191.34552) (xy 1.278001 -191.386717) (xy 1.270452 -191.429846)
			(xy 1.27 -191.451738) (xy 1.27 -191.706093) (xy 3.31393 -191.706093) (xy 3.31393 -191.634771) (xy 3.321916 -191.563897)
			(xy 3.337786 -191.494362) (xy 3.361343 -191.427042) (xy 3.392288 -191.362783) (xy 3.430234 -191.302392)
			(xy 3.474703 -191.24663) (xy 3.525136 -191.196197) (xy 3.580898 -191.151728) (xy 3.641289 -191.113782)
			(xy 3.705548 -191.082837) (xy 3.772868 -191.05928) (xy 3.842403 -191.04341) (xy 3.913277 -191.035424)
			(xy 3.984599 -191.035424) (xy 4.055473 -191.04341) (xy 4.125008 -191.05928) (xy 4.192328 -191.082837)
			(xy 4.256587 -191.113782) (xy 4.316978 -191.151728) (xy 4.37274 -191.196197) (xy 4.423173 -191.24663)
			(xy 4.467642 -191.302392) (xy 4.505588 -191.362783) (xy 4.536533 -191.427042) (xy 4.56009 -191.494362)
			(xy 4.57596 -191.563897) (xy 4.583946 -191.634771) (xy 4.584446 -191.670432) (xy 4.583946 -191.706093)
			(xy 5.813798 -191.706093) (xy 5.813798 -191.634771) (xy 5.821784 -191.563897) (xy 5.837654 -191.494362)
			(xy 5.861211 -191.427042) (xy 5.892156 -191.362783) (xy 5.930102 -191.302392) (xy 5.974571 -191.24663)
			(xy 6.025004 -191.196197) (xy 6.080766 -191.151728) (xy 6.141157 -191.113782) (xy 6.205416 -191.082837)
			(xy 6.272736 -191.05928) (xy 6.342271 -191.04341) (xy 6.413145 -191.035424) (xy 6.484467 -191.035424)
			(xy 6.555341 -191.04341) (xy 6.624876 -191.05928) (xy 6.692196 -191.082837) (xy 6.756455 -191.113782)
			(xy 6.816846 -191.151728) (xy 6.872608 -191.196197) (xy 6.923041 -191.24663) (xy 6.96751 -191.302392)
			(xy 7.005456 -191.362783) (xy 7.036401 -191.427042) (xy 7.059958 -191.494362) (xy 7.075828 -191.563897)
			(xy 7.083814 -191.634771) (xy 7.084314 -191.670432) (xy 7.083814 -191.706093) (xy 7.075828 -191.776967)
			(xy 7.059958 -191.846502) (xy 7.036401 -191.913822) (xy 7.005456 -191.978081) (xy 6.96751 -192.038472)
			(xy 6.923041 -192.094234) (xy 6.872608 -192.144667) (xy 6.816846 -192.189136) (xy 6.756455 -192.227082)
			(xy 6.692196 -192.258027) (xy 6.624876 -192.281584) (xy 6.555341 -192.297454) (xy 6.484467 -192.30544)
			(xy 6.413145 -192.30544) (xy 6.342271 -192.297454) (xy 6.272736 -192.281584) (xy 6.205416 -192.258027)
			(xy 6.141157 -192.227082) (xy 6.080766 -192.189136) (xy 6.025004 -192.144667) (xy 5.974571 -192.094234)
			(xy 5.930102 -192.038472) (xy 5.892156 -191.978081) (xy 5.861211 -191.913822) (xy 5.837654 -191.846502)
			(xy 5.821784 -191.776967) (xy 5.813798 -191.706093) (xy 4.583946 -191.706093) (xy 4.57596 -191.776967)
			(xy 4.56009 -191.846502) (xy 4.536533 -191.913822) (xy 4.505588 -191.978081) (xy 4.467642 -192.038472)
			(xy 4.423173 -192.094234) (xy 4.37274 -192.144667) (xy 4.316978 -192.189136) (xy 4.256587 -192.227082)
			(xy 4.192328 -192.258027) (xy 4.125008 -192.281584) (xy 4.055473 -192.297454) (xy 3.984599 -192.30544)
			(xy 3.913277 -192.30544) (xy 3.842403 -192.297454) (xy 3.772868 -192.281584) (xy 3.705548 -192.258027)
			(xy 3.641289 -192.227082) (xy 3.580898 -192.189136) (xy 3.525136 -192.144667) (xy 3.474703 -192.094234)
			(xy 3.430234 -192.038472) (xy 3.392288 -191.978081) (xy 3.361343 -191.913822) (xy 3.337786 -191.846502)
			(xy 3.321916 -191.776967) (xy 3.31393 -191.706093) (xy 1.27 -191.706093) (xy 1.27 -191.889126) (xy 1.270451 -191.911029)
			(xy 1.27795 -191.954187) (xy 1.292745 -191.995418) (xy 1.314397 -192.033497) (xy 1.342264 -192.067296)
			(xy 1.375518 -192.095809) (xy 1.413173 -192.118193) (xy 1.45411 -192.133781) (xy 1.497116 -192.142112)
			(xy 1.540913 -192.142937) (xy 1.584202 -192.136234) (xy 1.625698 -192.1222) (xy 1.645158 -192.112138)
			(xy 1.676623 -192.095579) (xy 1.742485 -192.068777) (xy 1.810926 -192.049494) (xy 1.881092 -192.037969)
			(xy 1.952105 -192.034348) (xy 2.023079 -192.038676) (xy 2.093127 -192.050898) (xy 2.161373 -192.070862)
			(xy 2.226964 -192.098318) (xy 2.289081 -192.132923) (xy 2.346948 -192.174245) (xy 2.399841 -192.221767)
			(xy 2.447099 -192.274896) (xy 2.488133 -192.332968) (xy 2.522429 -192.395256) (xy 2.549558 -192.460983)
			(xy 2.569182 -192.529328) (xy 2.581055 -192.599435) (xy 2.58503 -192.67043) (xy 2.583033 -192.706091)
			(xy 7.813794 -192.706091) (xy 7.813794 -192.634769) (xy 7.82178 -192.563895) (xy 7.83765 -192.49436)
			(xy 7.861207 -192.42704) (xy 7.892152 -192.362781) (xy 7.930098 -192.30239) (xy 7.974567 -192.246628)
			(xy 8.025 -192.196195) (xy 8.080762 -192.151726) (xy 8.141153 -192.11378) (xy 8.205412 -192.082835)
			(xy 8.272732 -192.059278) (xy 8.342267 -192.043408) (xy 8.413141 -192.035422) (xy 8.484463 -192.035422)
			(xy 8.555337 -192.043408) (xy 8.624872 -192.059278) (xy 8.692192 -192.082835) (xy 8.756451 -192.11378)
			(xy 8.816842 -192.151726) (xy 8.872604 -192.196195) (xy 8.923037 -192.246628) (xy 8.967506 -192.30239)
			(xy 9.005452 -192.362781) (xy 9.036397 -192.42704) (xy 9.059954 -192.49436) (xy 9.075824 -192.563895)
			(xy 9.08381 -192.634769) (xy 9.08431 -192.67043) (xy 9.08381 -192.706091) (xy 9.075824 -192.776965)
			(xy 9.059954 -192.8465) (xy 9.036397 -192.91382) (xy 9.005452 -192.978079) (xy 8.967506 -193.03847)
			(xy 8.923037 -193.094232) (xy 8.872604 -193.144665) (xy 8.816842 -193.189134) (xy 8.756451 -193.22708)
			(xy 8.692192 -193.258025) (xy 8.624872 -193.281582) (xy 8.555337 -193.297452) (xy 8.484463 -193.305438)
			(xy 8.413141 -193.305438) (xy 8.342267 -193.297452) (xy 8.272732 -193.281582) (xy 8.205412 -193.258025)
			(xy 8.141153 -193.22708) (xy 8.080762 -193.189134) (xy 8.025 -193.144665) (xy 7.974567 -193.094232)
			(xy 7.930098 -193.03847) (xy 7.892152 -192.978079) (xy 7.861207 -192.91382) (xy 7.83765 -192.8465)
			(xy 7.82178 -192.776965) (xy 7.813794 -192.706091) (xy 2.583033 -192.706091) (xy 2.581055 -192.741425)
			(xy 2.569182 -192.811532) (xy 2.549558 -192.879877) (xy 2.522429 -192.945604) (xy 2.488133 -193.007892)
			(xy 2.447099 -193.065964) (xy 2.399841 -193.119093) (xy 2.346948 -193.166615) (xy 2.289081 -193.207937)
			(xy 2.226964 -193.242542) (xy 2.161373 -193.269998) (xy 2.093127 -193.289962) (xy 2.023079 -193.302184)
			(xy 1.952105 -193.306512) (xy 1.881092 -193.302891) (xy 1.810926 -193.291366) (xy 1.742485 -193.272083)
			(xy 1.676623 -193.245281) (xy 1.645158 -193.228722) (xy 1.625697 -193.218683) (xy 1.584204 -193.204706)
			(xy 1.540929 -193.198046) (xy 1.497152 -193.198903) (xy 1.45417 -193.207249) (xy 1.413255 -193.222839)
			(xy 1.375618 -193.245211) (xy 1.342371 -193.273703) (xy 1.3145 -193.307471) (xy 1.292829 -193.345516)
			(xy 1.277999 -193.386713) (xy 1.270449 -193.429842) (xy 1.27 -193.451734) (xy 1.27 -193.706343) (xy 3.31393 -193.706343)
			(xy 3.31393 -193.635021) (xy 3.321916 -193.564147) (xy 3.337786 -193.494612) (xy 3.361343 -193.427292)
			(xy 3.392288 -193.363033) (xy 3.430234 -193.302642) (xy 3.474703 -193.24688) (xy 3.525136 -193.196447)
			(xy 3.580898 -193.151978) (xy 3.641289 -193.114032) (xy 3.705548 -193.083087) (xy 3.772868 -193.05953)
			(xy 3.842403 -193.04366) (xy 3.913277 -193.035674) (xy 3.984599 -193.035674) (xy 4.055473 -193.04366)
			(xy 4.125008 -193.05953) (xy 4.192328 -193.083087) (xy 4.256587 -193.114032) (xy 4.316978 -193.151978)
			(xy 4.37274 -193.196447) (xy 4.423173 -193.24688) (xy 4.467642 -193.302642) (xy 4.505588 -193.363033)
			(xy 4.536533 -193.427292) (xy 4.56009 -193.494612) (xy 4.57596 -193.564147) (xy 4.583946 -193.635021)
			(xy 4.584446 -193.670682) (xy 4.583946 -193.706343) (xy 5.813798 -193.706343) (xy 5.813798 -193.635021)
			(xy 5.821784 -193.564147) (xy 5.837654 -193.494612) (xy 5.861211 -193.427292) (xy 5.892156 -193.363033)
			(xy 5.930102 -193.302642) (xy 5.974571 -193.24688) (xy 6.025004 -193.196447) (xy 6.080766 -193.151978)
			(xy 6.141157 -193.114032) (xy 6.205416 -193.083087) (xy 6.272736 -193.05953) (xy 6.342271 -193.04366)
			(xy 6.413145 -193.035674) (xy 6.484467 -193.035674) (xy 6.555341 -193.04366) (xy 6.624876 -193.05953)
			(xy 6.692196 -193.083087) (xy 6.756455 -193.114032) (xy 6.816846 -193.151978) (xy 6.872608 -193.196447)
			(xy 6.923041 -193.24688) (xy 6.96751 -193.302642) (xy 7.005456 -193.363033) (xy 7.036401 -193.427292)
			(xy 7.059958 -193.494612) (xy 7.075828 -193.564147) (xy 7.083814 -193.635021) (xy 7.084314 -193.670682)
			(xy 7.083814 -193.706343) (xy 7.075828 -193.777217) (xy 7.059958 -193.846752) (xy 7.036401 -193.914072)
			(xy 7.005456 -193.978331) (xy 6.96751 -194.038722) (xy 6.923041 -194.094484) (xy 6.872608 -194.144917)
			(xy 6.816846 -194.189386) (xy 6.756455 -194.227332) (xy 6.692196 -194.258277) (xy 6.624876 -194.281834)
			(xy 6.555341 -194.297704) (xy 6.484467 -194.30569) (xy 6.413145 -194.30569) (xy 6.342271 -194.297704)
			(xy 6.272736 -194.281834) (xy 6.205416 -194.258277) (xy 6.141157 -194.227332) (xy 6.080766 -194.189386)
			(xy 6.025004 -194.144917) (xy 5.974571 -194.094484) (xy 5.930102 -194.038722) (xy 5.892156 -193.978331)
			(xy 5.861211 -193.914072) (xy 5.837654 -193.846752) (xy 5.821784 -193.777217) (xy 5.813798 -193.706343)
			(xy 4.583946 -193.706343) (xy 4.57596 -193.777217) (xy 4.56009 -193.846752) (xy 4.536533 -193.914072)
			(xy 4.505588 -193.978331) (xy 4.467642 -194.038722) (xy 4.423173 -194.094484) (xy 4.37274 -194.144917)
			(xy 4.316978 -194.189386) (xy 4.256587 -194.227332) (xy 4.192328 -194.258277) (xy 4.125008 -194.281834)
			(xy 4.055473 -194.297704) (xy 3.984599 -194.30569) (xy 3.913277 -194.30569) (xy 3.842403 -194.297704)
			(xy 3.772868 -194.281834) (xy 3.705548 -194.258277) (xy 3.641289 -194.227332) (xy 3.580898 -194.189386)
			(xy 3.525136 -194.144917) (xy 3.474703 -194.094484) (xy 3.430234 -194.038722) (xy 3.392288 -193.978331)
			(xy 3.361343 -193.914072) (xy 3.337786 -193.846752) (xy 3.321916 -193.777217) (xy 3.31393 -193.706343)
			(xy 1.27 -193.706343) (xy 1.27 -193.889122) (xy 1.27045 -193.911025) (xy 1.277949 -193.954184) (xy 1.292744 -193.995415)
			(xy 1.314396 -194.033495) (xy 1.342263 -194.067294) (xy 1.375517 -194.095809) (xy 1.413172 -194.118192)
			(xy 1.45411 -194.133781) (xy 1.497116 -194.142112) (xy 1.540913 -194.142937) (xy 1.584203 -194.136234)
			(xy 1.625699 -194.122199) (xy 1.645158 -194.112134) (xy 1.676623 -194.095575) (xy 1.742485 -194.068773)
			(xy 1.810926 -194.049489) (xy 1.881092 -194.037965) (xy 1.952106 -194.034343) (xy 2.02308 -194.038671)
			(xy 2.093128 -194.050893) (xy 2.161374 -194.070856) (xy 2.226966 -194.098312) (xy 2.289083 -194.132918)
			(xy 2.34695 -194.17424) (xy 2.399843 -194.221762) (xy 2.447102 -194.274891) (xy 2.488136 -194.332963)
			(xy 2.522431 -194.395251) (xy 2.549561 -194.460979) (xy 2.569185 -194.529323) (xy 2.581058 -194.599431)
			(xy 2.585033 -194.670426) (xy 2.583036 -194.706087) (xy 7.813794 -194.706087) (xy 7.813794 -194.634765)
			(xy 7.82178 -194.563891) (xy 7.83765 -194.494356) (xy 7.861207 -194.427036) (xy 7.892152 -194.362777)
			(xy 7.930098 -194.302386) (xy 7.974567 -194.246624) (xy 8.025 -194.196191) (xy 8.080762 -194.151722)
			(xy 8.141153 -194.113776) (xy 8.205412 -194.082831) (xy 8.272732 -194.059274) (xy 8.342267 -194.043404)
			(xy 8.413141 -194.035418) (xy 8.484463 -194.035418) (xy 8.555337 -194.043404) (xy 8.624872 -194.059274)
			(xy 8.692192 -194.082831) (xy 8.756451 -194.113776) (xy 8.816842 -194.151722) (xy 8.872604 -194.196191)
			(xy 8.923037 -194.246624) (xy 8.967506 -194.302386) (xy 9.005452 -194.362777) (xy 9.036397 -194.427036)
			(xy 9.059954 -194.494356) (xy 9.075824 -194.563891) (xy 9.08381 -194.634765) (xy 9.08431 -194.670426)
			(xy 9.08381 -194.706087) (xy 9.075824 -194.776961) (xy 9.059954 -194.846496) (xy 9.036397 -194.913816)
			(xy 9.005452 -194.978075) (xy 8.967506 -195.038466) (xy 8.923037 -195.094228) (xy 8.872604 -195.144661)
			(xy 8.816842 -195.18913) (xy 8.756451 -195.227076) (xy 8.692192 -195.258021) (xy 8.624872 -195.281578)
			(xy 8.555337 -195.297448) (xy 8.484463 -195.305434) (xy 8.413141 -195.305434) (xy 8.342267 -195.297448)
			(xy 8.272732 -195.281578) (xy 8.205412 -195.258021) (xy 8.141153 -195.227076) (xy 8.080762 -195.18913)
			(xy 8.025 -195.144661) (xy 7.974567 -195.094228) (xy 7.930098 -195.038466) (xy 7.892152 -194.978075)
			(xy 7.861207 -194.913816) (xy 7.83765 -194.846496) (xy 7.82178 -194.776961) (xy 7.813794 -194.706087)
			(xy 2.583036 -194.706087) (xy 2.581058 -194.741421) (xy 2.569185 -194.811529) (xy 2.549561 -194.879873)
			(xy 2.522431 -194.945601) (xy 2.488136 -195.007889) (xy 2.447102 -195.065961) (xy 2.399843 -195.11909)
			(xy 2.34695 -195.166612) (xy 2.289083 -195.207934) (xy 2.226966 -195.24254) (xy 2.161374 -195.269996)
			(xy 2.093128 -195.289959) (xy 2.02308 -195.302181) (xy 1.952106 -195.306509) (xy 1.881092 -195.302887)
			(xy 1.810926 -195.291363) (xy 1.742485 -195.272079) (xy 1.676623 -195.245277) (xy 1.645158 -195.228718)
			(xy 1.625697 -195.21868) (xy 1.584204 -195.204702) (xy 1.540928 -195.198043) (xy 1.497152 -195.198899)
			(xy 1.45417 -195.207246) (xy 1.413254 -195.222836) (xy 1.375617 -195.245208) (xy 1.34237 -195.273699)
			(xy 1.314498 -195.307467) (xy 1.292827 -195.345512) (xy 1.277996 -195.386709) (xy 1.270446 -195.429838)
			(xy 1.27 -195.45173) (xy 1.27 -195.706339) (xy 3.31393 -195.706339) (xy 3.31393 -195.635017) (xy 3.321916 -195.564143)
			(xy 3.337786 -195.494608) (xy 3.361343 -195.427288) (xy 3.392288 -195.363029) (xy 3.430234 -195.302638)
			(xy 3.474703 -195.246876) (xy 3.525136 -195.196443) (xy 3.580898 -195.151974) (xy 3.641289 -195.114028)
			(xy 3.705548 -195.083083) (xy 3.772868 -195.059526) (xy 3.842403 -195.043656) (xy 3.913277 -195.03567)
			(xy 3.984599 -195.03567) (xy 4.055473 -195.043656) (xy 4.125008 -195.059526) (xy 4.192328 -195.083083)
			(xy 4.256587 -195.114028) (xy 4.316978 -195.151974) (xy 4.37274 -195.196443) (xy 4.423173 -195.246876)
			(xy 4.467642 -195.302638) (xy 4.505588 -195.363029) (xy 4.536533 -195.427288) (xy 4.56009 -195.494608)
			(xy 4.57596 -195.564143) (xy 4.583946 -195.635017) (xy 4.584446 -195.670678) (xy 4.583946 -195.706339)
			(xy 5.813798 -195.706339) (xy 5.813798 -195.635017) (xy 5.821784 -195.564143) (xy 5.837654 -195.494608)
			(xy 5.861211 -195.427288) (xy 5.892156 -195.363029) (xy 5.930102 -195.302638) (xy 5.974571 -195.246876)
			(xy 6.025004 -195.196443) (xy 6.080766 -195.151974) (xy 6.141157 -195.114028) (xy 6.205416 -195.083083)
			(xy 6.272736 -195.059526) (xy 6.342271 -195.043656) (xy 6.413145 -195.03567) (xy 6.484467 -195.03567)
			(xy 6.555341 -195.043656) (xy 6.624876 -195.059526) (xy 6.692196 -195.083083) (xy 6.756455 -195.114028)
			(xy 6.816846 -195.151974) (xy 6.872608 -195.196443) (xy 6.923041 -195.246876) (xy 6.96751 -195.302638)
			(xy 7.005456 -195.363029) (xy 7.036401 -195.427288) (xy 7.059958 -195.494608) (xy 7.075828 -195.564143)
			(xy 7.083814 -195.635017) (xy 7.084314 -195.670678) (xy 7.083814 -195.706339) (xy 7.075828 -195.777213)
			(xy 7.059958 -195.846748) (xy 7.036401 -195.914068) (xy 7.005456 -195.978327) (xy 6.96751 -196.038718)
			(xy 6.923041 -196.09448) (xy 6.872608 -196.144913) (xy 6.816846 -196.189382) (xy 6.756455 -196.227328)
			(xy 6.692196 -196.258273) (xy 6.624876 -196.28183) (xy 6.555341 -196.2977) (xy 6.484467 -196.305686)
			(xy 6.413145 -196.305686) (xy 6.342271 -196.2977) (xy 6.272736 -196.28183) (xy 6.205416 -196.258273)
			(xy 6.141157 -196.227328) (xy 6.080766 -196.189382) (xy 6.025004 -196.144913) (xy 5.974571 -196.09448)
			(xy 5.930102 -196.038718) (xy 5.892156 -195.978327) (xy 5.861211 -195.914068) (xy 5.837654 -195.846748)
			(xy 5.821784 -195.777213) (xy 5.813798 -195.706339) (xy 4.583946 -195.706339) (xy 4.57596 -195.777213)
			(xy 4.56009 -195.846748) (xy 4.536533 -195.914068) (xy 4.505588 -195.978327) (xy 4.467642 -196.038718)
			(xy 4.423173 -196.09448) (xy 4.37274 -196.144913) (xy 4.316978 -196.189382) (xy 4.256587 -196.227328)
			(xy 4.192328 -196.258273) (xy 4.125008 -196.28183) (xy 4.055473 -196.2977) (xy 3.984599 -196.305686)
			(xy 3.913277 -196.305686) (xy 3.842403 -196.2977) (xy 3.772868 -196.28183) (xy 3.705548 -196.258273)
			(xy 3.641289 -196.227328) (xy 3.580898 -196.189382) (xy 3.525136 -196.144913) (xy 3.474703 -196.09448)
			(xy 3.430234 -196.038718) (xy 3.392288 -195.978327) (xy 3.361343 -195.914068) (xy 3.337786 -195.846748)
			(xy 3.321916 -195.777213) (xy 3.31393 -195.706339) (xy 1.27 -195.706339) (xy 1.27 -195.889118) (xy 1.270451 -195.911021)
			(xy 1.27795 -195.954179) (xy 1.292746 -195.995409) (xy 1.314398 -196.033488) (xy 1.342265 -196.067286)
			(xy 1.375519 -196.0958) (xy 1.413173 -196.118183) (xy 1.45411 -196.133771) (xy 1.497116 -196.142102)
			(xy 1.540912 -196.142927) (xy 1.584201 -196.136224) (xy 1.625697 -196.12219) (xy 1.645158 -196.11213)
			(xy 1.676623 -196.095571) (xy 1.742484 -196.068769) (xy 1.810925 -196.049486) (xy 1.881091 -196.037961)
			(xy 1.952104 -196.03434) (xy 2.023078 -196.038667) (xy 2.093126 -196.050889) (xy 2.161371 -196.070853)
			(xy 2.226963 -196.098309) (xy 2.289079 -196.132914) (xy 2.346946 -196.174236) (xy 2.399839 -196.221758)
			(xy 2.447098 -196.274886) (xy 2.488131 -196.332958) (xy 2.522427 -196.395246) (xy 2.549556 -196.460973)
			(xy 2.56918 -196.529317) (xy 2.581053 -196.599424) (xy 2.585028 -196.670419) (xy 2.583032 -196.706083)
			(xy 7.813794 -196.706083) (xy 7.813794 -196.634761) (xy 7.82178 -196.563887) (xy 7.83765 -196.494352)
			(xy 7.861207 -196.427032) (xy 7.892152 -196.362773) (xy 7.930098 -196.302382) (xy 7.974567 -196.24662)
			(xy 8.025 -196.196187) (xy 8.080762 -196.151718) (xy 8.141153 -196.113772) (xy 8.205412 -196.082827)
			(xy 8.272732 -196.05927) (xy 8.342267 -196.0434) (xy 8.413141 -196.035414) (xy 8.484463 -196.035414)
			(xy 8.555337 -196.0434) (xy 8.624872 -196.05927) (xy 8.692192 -196.082827) (xy 8.756451 -196.113772)
			(xy 8.816842 -196.151718) (xy 8.872604 -196.196187) (xy 8.923037 -196.24662) (xy 8.967506 -196.302382)
			(xy 9.005452 -196.362773) (xy 9.036397 -196.427032) (xy 9.059954 -196.494352) (xy 9.075824 -196.563887)
			(xy 9.08381 -196.634761) (xy 9.08431 -196.670422) (xy 9.08381 -196.706083) (xy 9.075824 -196.776957)
			(xy 9.059954 -196.846492) (xy 9.036397 -196.913812) (xy 9.005452 -196.978071) (xy 8.967506 -197.038462)
			(xy 8.923037 -197.094224) (xy 8.872604 -197.144657) (xy 8.816842 -197.189126) (xy 8.756451 -197.227072)
			(xy 8.692192 -197.258017) (xy 8.624872 -197.281574) (xy 8.555337 -197.297444) (xy 8.484463 -197.30543)
			(xy 8.413141 -197.30543) (xy 8.342267 -197.297444) (xy 8.272732 -197.281574) (xy 8.205412 -197.258017)
			(xy 8.141153 -197.227072) (xy 8.080762 -197.189126) (xy 8.025 -197.144657) (xy 7.974567 -197.094224)
			(xy 7.930098 -197.038462) (xy 7.892152 -196.978071) (xy 7.861207 -196.913812) (xy 7.83765 -196.846492)
			(xy 7.82178 -196.776957) (xy 7.813794 -196.706083) (xy 2.583032 -196.706083) (xy 2.581054 -196.741414)
			(xy 2.56918 -196.811521) (xy 2.549557 -196.879865) (xy 2.522428 -196.945592) (xy 2.488132 -197.007881)
			(xy 2.447099 -197.065952) (xy 2.39984 -197.119081) (xy 2.346947 -197.166603) (xy 2.289081 -197.207925)
			(xy 2.226964 -197.24253) (xy 2.161373 -197.269986) (xy 2.093127 -197.28995) (xy 2.02308 -197.302172)
			(xy 1.952106 -197.3065) (xy 1.881093 -197.302879) (xy 1.810927 -197.291355) (xy 1.742486 -197.272071)
			(xy 1.676625 -197.24527) (xy 1.645158 -197.228714) (xy 1.625697 -197.218676) (xy 1.584203 -197.204698)
			(xy 1.540928 -197.198039) (xy 1.497151 -197.198896) (xy 1.454169 -197.207243) (xy 1.413254 -197.222832)
			(xy 1.375616 -197.245204) (xy 1.342369 -197.273695) (xy 1.314497 -197.307463) (xy 1.292825 -197.345508)
			(xy 1.277994 -197.386705) (xy 1.270443 -197.429834) (xy 1.27 -197.451726) (xy 1.27 -197.706335) (xy 3.31393 -197.706335)
			(xy 3.31393 -197.635013) (xy 3.321916 -197.564139) (xy 3.337786 -197.494604) (xy 3.361343 -197.427284)
			(xy 3.392288 -197.363025) (xy 3.430234 -197.302634) (xy 3.474703 -197.246872) (xy 3.525136 -197.196439)
			(xy 3.580898 -197.15197) (xy 3.641289 -197.114024) (xy 3.705548 -197.083079) (xy 3.772868 -197.059522)
			(xy 3.842403 -197.043652) (xy 3.913277 -197.035666) (xy 3.984599 -197.035666) (xy 4.055473 -197.043652)
			(xy 4.125008 -197.059522) (xy 4.192328 -197.083079) (xy 4.256587 -197.114024) (xy 4.316978 -197.15197)
			(xy 4.37274 -197.196439) (xy 4.423173 -197.246872) (xy 4.467642 -197.302634) (xy 4.505588 -197.363025)
			(xy 4.536533 -197.427284) (xy 4.56009 -197.494604) (xy 4.57596 -197.564139) (xy 4.583946 -197.635013)
			(xy 4.584446 -197.670674) (xy 4.583946 -197.706335) (xy 5.813798 -197.706335) (xy 5.813798 -197.635013)
			(xy 5.821784 -197.564139) (xy 5.837654 -197.494604) (xy 5.861211 -197.427284) (xy 5.892156 -197.363025)
			(xy 5.930102 -197.302634) (xy 5.974571 -197.246872) (xy 6.025004 -197.196439) (xy 6.080766 -197.15197)
			(xy 6.141157 -197.114024) (xy 6.205416 -197.083079) (xy 6.272736 -197.059522) (xy 6.342271 -197.043652)
			(xy 6.413145 -197.035666) (xy 6.484467 -197.035666) (xy 6.555341 -197.043652) (xy 6.624876 -197.059522)
			(xy 6.692196 -197.083079) (xy 6.756455 -197.114024) (xy 6.816846 -197.15197) (xy 6.872608 -197.196439)
			(xy 6.923041 -197.246872) (xy 6.96751 -197.302634) (xy 7.005456 -197.363025) (xy 7.036401 -197.427284)
			(xy 7.059958 -197.494604) (xy 7.075828 -197.564139) (xy 7.083814 -197.635013) (xy 7.084314 -197.670674)
			(xy 7.083814 -197.706335) (xy 7.075828 -197.777209) (xy 7.059958 -197.846744) (xy 7.036401 -197.914064)
			(xy 7.005456 -197.978323) (xy 6.96751 -198.038714) (xy 6.923041 -198.094476) (xy 6.872608 -198.144909)
			(xy 6.816846 -198.189378) (xy 6.756455 -198.227324) (xy 6.692196 -198.258269) (xy 6.624876 -198.281826)
			(xy 6.555341 -198.297696) (xy 6.484467 -198.305682) (xy 6.413145 -198.305682) (xy 6.342271 -198.297696)
			(xy 6.272736 -198.281826) (xy 6.205416 -198.258269) (xy 6.141157 -198.227324) (xy 6.080766 -198.189378)
			(xy 6.025004 -198.144909) (xy 5.974571 -198.094476) (xy 5.930102 -198.038714) (xy 5.892156 -197.978323)
			(xy 5.861211 -197.914064) (xy 5.837654 -197.846744) (xy 5.821784 -197.777209) (xy 5.813798 -197.706335)
			(xy 4.583946 -197.706335) (xy 4.57596 -197.777209) (xy 4.56009 -197.846744) (xy 4.536533 -197.914064)
			(xy 4.505588 -197.978323) (xy 4.467642 -198.038714) (xy 4.423173 -198.094476) (xy 4.37274 -198.144909)
			(xy 4.316978 -198.189378) (xy 4.256587 -198.227324) (xy 4.192328 -198.258269) (xy 4.125008 -198.281826)
			(xy 4.055473 -198.297696) (xy 3.984599 -198.305682) (xy 3.913277 -198.305682) (xy 3.842403 -198.297696)
			(xy 3.772868 -198.281826) (xy 3.705548 -198.258269) (xy 3.641289 -198.227324) (xy 3.580898 -198.189378)
			(xy 3.525136 -198.144909) (xy 3.474703 -198.094476) (xy 3.430234 -198.038714) (xy 3.392288 -197.978323)
			(xy 3.361343 -197.914064) (xy 3.337786 -197.846744) (xy 3.321916 -197.777209) (xy 3.31393 -197.706335)
			(xy 1.27 -197.706335) (xy 1.27 -197.889114) (xy 1.270451 -197.911017) (xy 1.277949 -197.954175) (xy 1.292744 -197.995407)
			(xy 1.314397 -198.033486) (xy 1.342263 -198.067285) (xy 1.375517 -198.095799) (xy 1.413172 -198.118182)
			(xy 1.45411 -198.133771) (xy 1.497116 -198.142102) (xy 1.540913 -198.142927) (xy 1.584202 -198.136224)
			(xy 1.625699 -198.12219) (xy 1.645158 -198.112126) (xy 1.676623 -198.095567) (xy 1.742485 -198.068765)
			(xy 1.810926 -198.049482) (xy 1.881092 -198.037957) (xy 1.952106 -198.034337) (xy 2.02308 -198.038664)
			(xy 2.093128 -198.050886) (xy 2.161374 -198.07085) (xy 2.226966 -198.098307) (xy 2.289083 -198.132912)
			(xy 2.34695 -198.174234) (xy 2.399843 -198.221757) (xy 2.447101 -198.274886) (xy 2.488135 -198.332958)
			(xy 2.522431 -198.395246) (xy 2.54956 -198.460974) (xy 2.569184 -198.529318) (xy 2.581057 -198.599426)
			(xy 2.585031 -198.670421) (xy 2.583035 -198.706079) (xy 7.813794 -198.706079) (xy 7.813794 -198.634757)
			(xy 7.82178 -198.563883) (xy 7.83765 -198.494348) (xy 7.861207 -198.427028) (xy 7.892152 -198.362769)
			(xy 7.930098 -198.302378) (xy 7.974567 -198.246616) (xy 8.025 -198.196183) (xy 8.080762 -198.151714)
			(xy 8.141153 -198.113768) (xy 8.205412 -198.082823) (xy 8.272732 -198.059266) (xy 8.342267 -198.043396)
			(xy 8.413141 -198.03541) (xy 8.484463 -198.03541) (xy 8.555337 -198.043396) (xy 8.624872 -198.059266)
			(xy 8.692192 -198.082823) (xy 8.756451 -198.113768) (xy 8.816842 -198.151714) (xy 8.872604 -198.196183)
			(xy 8.923037 -198.246616) (xy 8.967506 -198.302378) (xy 9.005452 -198.362769) (xy 9.036397 -198.427028)
			(xy 9.059954 -198.494348) (xy 9.075824 -198.563883) (xy 9.08381 -198.634757) (xy 9.08431 -198.670418)
			(xy 9.08381 -198.706079) (xy 9.075824 -198.776953) (xy 9.059954 -198.846488) (xy 9.036397 -198.913808)
			(xy 9.005452 -198.978067) (xy 8.967506 -199.038458) (xy 8.923037 -199.09422) (xy 8.872604 -199.144653)
			(xy 8.816842 -199.189122) (xy 8.756451 -199.227068) (xy 8.692192 -199.258013) (xy 8.624872 -199.28157)
			(xy 8.555337 -199.29744) (xy 8.484463 -199.305426) (xy 8.413141 -199.305426) (xy 8.342267 -199.29744)
			(xy 8.272732 -199.28157) (xy 8.205412 -199.258013) (xy 8.141153 -199.227068) (xy 8.080762 -199.189122)
			(xy 8.025 -199.144653) (xy 7.974567 -199.09422) (xy 7.930098 -199.038458) (xy 7.892152 -198.978067)
			(xy 7.861207 -198.913808) (xy 7.83765 -198.846488) (xy 7.82178 -198.776953) (xy 7.813794 -198.706079)
			(xy 2.583035 -198.706079) (xy 2.581057 -198.741416) (xy 2.569183 -198.811524) (xy 2.549559 -198.879868)
			(xy 2.52243 -198.945595) (xy 2.488134 -199.007884) (xy 2.4471 -199.065956) (xy 2.399841 -199.119085)
			(xy 2.346948 -199.166607) (xy 2.289081 -199.207929) (xy 2.226964 -199.242534) (xy 2.161373 -199.26999)
			(xy 2.093126 -199.289954) (xy 2.023079 -199.302176) (xy 1.952104 -199.306503) (xy 1.88109 -199.302882)
			(xy 1.810924 -199.291358) (xy 1.742483 -199.272074) (xy 1.676622 -199.245272) (xy 1.645158 -199.22871)
			(xy 1.625697 -199.218672) (xy 1.584203 -199.204695) (xy 1.540927 -199.198036) (xy 1.497151 -199.198892)
			(xy 1.454168 -199.207239) (xy 1.413253 -199.222829) (xy 1.375615 -199.2452) (xy 1.342367 -199.273692)
			(xy 1.314495 -199.307459) (xy 1.292822 -199.345504) (xy 1.277991 -199.386701) (xy 1.27044 -199.42983)
			(xy 1.27 -199.451722) (xy 1.27 -199.706331) (xy 3.31393 -199.706331) (xy 3.31393 -199.635009) (xy 3.321916 -199.564135)
			(xy 3.337786 -199.4946) (xy 3.361343 -199.42728) (xy 3.392288 -199.363021) (xy 3.430234 -199.30263)
			(xy 3.474703 -199.246868) (xy 3.525136 -199.196435) (xy 3.580898 -199.151966) (xy 3.641289 -199.11402)
			(xy 3.705548 -199.083075) (xy 3.772868 -199.059518) (xy 3.842403 -199.043648) (xy 3.913277 -199.035662)
			(xy 3.984599 -199.035662) (xy 4.055473 -199.043648) (xy 4.125008 -199.059518) (xy 4.192328 -199.083075)
			(xy 4.256587 -199.11402) (xy 4.316978 -199.151966) (xy 4.37274 -199.196435) (xy 4.423173 -199.246868)
			(xy 4.467642 -199.30263) (xy 4.505588 -199.363021) (xy 4.536533 -199.42728) (xy 4.56009 -199.4946)
			(xy 4.57596 -199.564135) (xy 4.583946 -199.635009) (xy 4.584446 -199.67067) (xy 4.583946 -199.706331)
			(xy 5.813798 -199.706331) (xy 5.813798 -199.635009) (xy 5.821784 -199.564135) (xy 5.837654 -199.4946)
			(xy 5.861211 -199.42728) (xy 5.892156 -199.363021) (xy 5.930102 -199.30263) (xy 5.974571 -199.246868)
			(xy 6.025004 -199.196435) (xy 6.080766 -199.151966) (xy 6.141157 -199.11402) (xy 6.205416 -199.083075)
			(xy 6.272736 -199.059518) (xy 6.342271 -199.043648) (xy 6.413145 -199.035662) (xy 6.484467 -199.035662)
			(xy 6.555341 -199.043648) (xy 6.624876 -199.059518) (xy 6.692196 -199.083075) (xy 6.756455 -199.11402)
			(xy 6.816846 -199.151966) (xy 6.872608 -199.196435) (xy 6.923041 -199.246868) (xy 6.96751 -199.30263)
			(xy 7.005456 -199.363021) (xy 7.036401 -199.42728) (xy 7.059958 -199.4946) (xy 7.075828 -199.564135)
			(xy 7.083814 -199.635009) (xy 7.084314 -199.67067) (xy 7.083814 -199.706331) (xy 7.075828 -199.777205)
			(xy 7.059958 -199.84674) (xy 7.036401 -199.91406) (xy 7.005456 -199.978319) (xy 6.96751 -200.03871)
			(xy 6.923041 -200.094472) (xy 6.872608 -200.144905) (xy 6.816846 -200.189374) (xy 6.756455 -200.22732)
			(xy 6.692196 -200.258265) (xy 6.624876 -200.281822) (xy 6.555341 -200.297692) (xy 6.484467 -200.305678)
			(xy 6.413145 -200.305678) (xy 6.342271 -200.297692) (xy 6.272736 -200.281822) (xy 6.205416 -200.258265)
			(xy 6.141157 -200.22732) (xy 6.080766 -200.189374) (xy 6.025004 -200.144905) (xy 5.974571 -200.094472)
			(xy 5.930102 -200.03871) (xy 5.892156 -199.978319) (xy 5.861211 -199.91406) (xy 5.837654 -199.84674)
			(xy 5.821784 -199.777205) (xy 5.813798 -199.706331) (xy 4.583946 -199.706331) (xy 4.57596 -199.777205)
			(xy 4.56009 -199.84674) (xy 4.536533 -199.91406) (xy 4.505588 -199.978319) (xy 4.467642 -200.03871)
			(xy 4.423173 -200.094472) (xy 4.37274 -200.144905) (xy 4.316978 -200.189374) (xy 4.256587 -200.22732)
			(xy 4.192328 -200.258265) (xy 4.125008 -200.281822) (xy 4.055473 -200.297692) (xy 3.984599 -200.305678)
			(xy 3.913277 -200.305678) (xy 3.842403 -200.297692) (xy 3.772868 -200.281822) (xy 3.705548 -200.258265)
			(xy 3.641289 -200.22732) (xy 3.580898 -200.189374) (xy 3.525136 -200.144905) (xy 3.474703 -200.094472)
			(xy 3.430234 -200.03871) (xy 3.392288 -199.978319) (xy 3.361343 -199.91406) (xy 3.337786 -199.84674)
			(xy 3.321916 -199.777205) (xy 3.31393 -199.706331) (xy 1.27 -199.706331) (xy 1.27 -199.88911) (xy 1.27045 -199.911013)
			(xy 1.277949 -199.954172) (xy 1.292743 -199.995404) (xy 1.314395 -200.033485) (xy 1.342262 -200.067284)
			(xy 1.375516 -200.095798) (xy 1.413171 -200.118182) (xy 1.45411 -200.133771) (xy 1.497116 -200.142102)
			(xy 1.540914 -200.142927) (xy 1.584204 -200.136223) (xy 1.6257 -200.122189) (xy 1.645158 -200.112122)
			(xy 1.676279 -200.095729) (xy 1.741403 -200.069141) (xy 1.809065 -200.049905) (xy 1.878437 -200.038258)
			(xy 1.948671 -200.034342) (xy 2.018908 -200.038203) (xy 2.088289 -200.049796) (xy 2.155965 -200.068978)
			(xy 2.221111 -200.095515) (xy 2.282928 -200.129083) (xy 2.340661 -200.16927) (xy 2.393604 -200.215586)
			(xy 2.441109 -200.267464) (xy 2.482597 -200.32427) (xy 2.517558 -200.385309) (xy 2.545567 -200.449835)
			(xy 2.566281 -200.517059) (xy 2.579445 -200.586159) (xy 2.5849 -200.65629) (xy 2.583256 -200.706075)
			(xy 7.813794 -200.706075) (xy 7.813794 -200.634753) (xy 7.82178 -200.563879) (xy 7.83765 -200.494344)
			(xy 7.861207 -200.427024) (xy 7.892152 -200.362765) (xy 7.930098 -200.302374) (xy 7.974567 -200.246612)
			(xy 8.025 -200.196179) (xy 8.080762 -200.15171) (xy 8.141153 -200.113764) (xy 8.205412 -200.082819)
			(xy 8.272732 -200.059262) (xy 8.342267 -200.043392) (xy 8.413141 -200.035406) (xy 8.484463 -200.035406)
			(xy 8.555337 -200.043392) (xy 8.624872 -200.059262) (xy 8.692192 -200.082819) (xy 8.756451 -200.113764)
			(xy 8.816842 -200.15171) (xy 8.872604 -200.196179) (xy 8.923037 -200.246612) (xy 8.967506 -200.302374)
			(xy 9.005452 -200.362765) (xy 9.036397 -200.427024) (xy 9.059954 -200.494344) (xy 9.075824 -200.563879)
			(xy 9.08381 -200.634753) (xy 9.08431 -200.670414) (xy 9.08381 -200.706075) (xy 9.075824 -200.776949)
			(xy 9.059954 -200.846484) (xy 9.036397 -200.913804) (xy 9.005452 -200.978063) (xy 8.967506 -201.038454)
			(xy 8.923037 -201.094216) (xy 8.872604 -201.144649) (xy 8.816842 -201.189118) (xy 8.756451 -201.227064)
			(xy 8.692192 -201.258009) (xy 8.624872 -201.281566) (xy 8.555337 -201.297436) (xy 8.484463 -201.305422)
			(xy 8.413141 -201.305422) (xy 8.342267 -201.297436) (xy 8.272732 -201.281566) (xy 8.205412 -201.258009)
			(xy 8.141153 -201.227064) (xy 8.080762 -201.189118) (xy 8.025 -201.144649) (xy 7.974567 -201.094216)
			(xy 7.930098 -201.038454) (xy 7.892152 -200.978063) (xy 7.861207 -200.913804) (xy 7.83765 -200.846484)
			(xy 7.82178 -200.776949) (xy 7.813794 -200.706075) (xy 2.583256 -200.706075) (xy 2.582579 -200.726595)
			(xy 2.572509 -200.796213) (xy 2.554815 -200.864294) (xy 2.529712 -200.930005) (xy 2.497507 -200.992543)
			(xy 2.458594 -201.051143) (xy 2.41345 -201.105088) (xy 2.362625 -201.153719) (xy 2.306742 -201.196441)
			(xy 2.276856 -201.21499) (xy 2.286508 -201.224388) (xy 2.286508 -201.691494) (xy 2.301341 -201.706327)
			(xy 3.31393 -201.706327) (xy 3.31393 -201.635005) (xy 3.321916 -201.564131) (xy 3.337786 -201.494596)
			(xy 3.361343 -201.427276) (xy 3.392288 -201.363017) (xy 3.430234 -201.302626) (xy 3.474703 -201.246864)
			(xy 3.525136 -201.196431) (xy 3.580898 -201.151962) (xy 3.641289 -201.114016) (xy 3.705548 -201.083071)
			(xy 3.772868 -201.059514) (xy 3.842403 -201.043644) (xy 3.913277 -201.035658) (xy 3.984599 -201.035658)
			(xy 4.055473 -201.043644) (xy 4.125008 -201.059514) (xy 4.192328 -201.083071) (xy 4.256587 -201.114016)
			(xy 4.316978 -201.151962) (xy 4.37274 -201.196431) (xy 4.423173 -201.246864) (xy 4.467642 -201.302626)
			(xy 4.505588 -201.363017) (xy 4.536533 -201.427276) (xy 4.56009 -201.494596) (xy 4.57596 -201.564131)
			(xy 4.583946 -201.635005) (xy 4.584446 -201.670666) (xy 4.583946 -201.706327) (xy 5.813798 -201.706327)
			(xy 5.813798 -201.635005) (xy 5.821784 -201.564131) (xy 5.837654 -201.494596) (xy 5.861211 -201.427276)
			(xy 5.892156 -201.363017) (xy 5.930102 -201.302626) (xy 5.974571 -201.246864) (xy 6.025004 -201.196431)
			(xy 6.080766 -201.151962) (xy 6.141157 -201.114016) (xy 6.205416 -201.083071) (xy 6.272736 -201.059514)
			(xy 6.342271 -201.043644) (xy 6.413145 -201.035658) (xy 6.484467 -201.035658) (xy 6.555341 -201.043644)
			(xy 6.624876 -201.059514) (xy 6.692196 -201.083071) (xy 6.756455 -201.114016) (xy 6.816846 -201.151962)
			(xy 6.872608 -201.196431) (xy 6.923041 -201.246864) (xy 6.96751 -201.302626) (xy 7.005456 -201.363017)
			(xy 7.036401 -201.427276) (xy 7.059958 -201.494596) (xy 7.075828 -201.564131) (xy 7.083814 -201.635005)
			(xy 7.084314 -201.670666) (xy 7.083814 -201.706327) (xy 7.075828 -201.777201) (xy 7.059958 -201.846736)
			(xy 7.036401 -201.914056) (xy 7.005456 -201.978315) (xy 6.96751 -202.038706) (xy 6.923041 -202.094468)
			(xy 6.872608 -202.144901) (xy 6.816846 -202.18937) (xy 6.756455 -202.227316) (xy 6.692196 -202.258261)
			(xy 6.624876 -202.281818) (xy 6.555341 -202.297688) (xy 6.484467 -202.305674) (xy 6.413145 -202.305674)
			(xy 6.342271 -202.297688) (xy 6.272736 -202.281818) (xy 6.205416 -202.258261) (xy 6.141157 -202.227316)
			(xy 6.080766 -202.18937) (xy 6.025004 -202.144901) (xy 5.974571 -202.094468) (xy 5.930102 -202.038706)
			(xy 5.892156 -201.978315) (xy 5.861211 -201.914056) (xy 5.837654 -201.846736) (xy 5.821784 -201.777201)
			(xy 5.813798 -201.706327) (xy 4.583946 -201.706327) (xy 4.57596 -201.777201) (xy 4.56009 -201.846736)
			(xy 4.536533 -201.914056) (xy 4.505588 -201.978315) (xy 4.467642 -202.038706) (xy 4.423173 -202.094468)
			(xy 4.37274 -202.144901) (xy 4.316978 -202.18937) (xy 4.256587 -202.227316) (xy 4.192328 -202.258261)
			(xy 4.125008 -202.281818) (xy 4.055473 -202.297688) (xy 3.984599 -202.305674) (xy 3.913277 -202.305674)
			(xy 3.842403 -202.297688) (xy 3.772868 -202.281818) (xy 3.705548 -202.258261) (xy 3.641289 -202.227316)
			(xy 3.580898 -202.18937) (xy 3.525136 -202.144901) (xy 3.474703 -202.094468) (xy 3.430234 -202.038706)
			(xy 3.392288 -201.978315) (xy 3.361343 -201.914056) (xy 3.337786 -201.846736) (xy 3.321916 -201.777201)
			(xy 3.31393 -201.706327) (xy 2.301341 -201.706327) (xy 2.546604 -201.95159) (xy 3.436112 -202.841098)
			(xy 6.97611 -202.841098)
		)
		(stroke
			(width 0)
			(type solid)
		)
		(fill yes)
		(layer "F.Cu")
		(net "P12V")
	)
	(gr_poly
		(pts
			(xy 7.492492 -179.253388) (xy 19.860768 -179.253388) (xy 19.873214 -179.265834) (xy 23.635462 -179.265834)
			(xy 25.42667 -177.474626) (xy 26.755852 -177.474626) (xy 26.772512 -177.474137) (xy 26.8047 -177.465525)
			(xy 26.833561 -177.448874) (xy 26.857129 -177.42532) (xy 26.873796 -177.396468) (xy 26.882428 -177.364286)
			(xy 26.882852 -177.347626) (xy 26.882852 -113.440464) (xy 21.830792 -108.388404) (xy 21.830792 -104.693974)
			(xy 22.613112 -103.9114) (xy 22.613112 -98.858832) (xy 23.889462 -97.582736) (xy 23.949406 -97.582736)
			(xy 23.97245 -97.582226) (xy 24.017781 -97.573901) (xy 24.06087 -97.557542) (xy 24.100304 -97.533685)
			(xy 24.134793 -97.503112) (xy 24.163207 -97.466824) (xy 24.184616 -97.426009) (xy 24.198318 -97.382004)
			(xy 24.203866 -97.33625) (xy 24.201076 -97.290245) (xy 24.190041 -97.245497) (xy 24.171121 -97.20347)
			(xy 24.144937 -97.165541) (xy 24.128984 -97.148904) (xy 23.154132 -96.174052) (xy 23.154132 -93.83141)
			(xy 23.843234 -93.142308) (xy 27.045158 -93.142308) (xy 28.973018 -91.214448) (xy 28.984424 -91.202276)
			(xy 29.001101 -91.173402) (xy 29.009737 -91.141195) (xy 29.009743 -91.10785) (xy 29.001119 -91.07564)
			(xy 28.984452 -91.04676) (xy 28.973018 -91.034616) (xy 28.223972 -90.28557) (xy 28.223972 -22.808184)
			(xy 28.223475 -22.791532) (xy 28.214851 -22.759364) (xy 28.198194 -22.730524) (xy 28.174641 -22.706979)
			(xy 28.145795 -22.690332) (xy 28.113624 -22.681719) (xy 28.096972 -22.681184) (xy 26.846022 -22.681184)
			(xy 25.19172 -21.026882) (xy 25.19172 -19.007328) (xy 22.866096 -16.681704) (xy 22.862032 -16.677894)
			(xy 22.862032 -6.147816) (xy 21.984208 -5.269992) (xy 12.575794 -5.269992) (xy 12.568174 -5.269992)
			(xy 12.269978 -5.269992) (xy 12.25456 -5.271134) (xy 12.224932 -5.279936) (xy 12.19829 -5.295607)
			(xy 12.176201 -5.317225) (xy 12.15996 -5.343522) (xy 12.150521 -5.372954) (xy 12.14844 -5.403792)
			(xy 12.153837 -5.434226) (xy 12.166397 -5.462467) (xy 12.185381 -5.486858) (xy 12.209674 -5.505966)
			(xy 12.237851 -5.51867) (xy 12.25296 -5.52196) (xy 12.292569 -5.528667) (xy 12.37035 -5.548782) (xy 12.44581 -5.576353)
			(xy 12.518237 -5.61112) (xy 12.586947 -5.652754) (xy 12.651291 -5.700862) (xy 12.710659 -5.754989)
			(xy 12.764493 -5.814625) (xy 12.812282 -5.879205) (xy 12.853576 -5.94812) (xy 12.887985 -6.020719)
			(xy 12.915182 -6.096314) (xy 12.934912 -6.174194) (xy 12.946988 -6.25362) (xy 12.951296 -6.333844)
			(xy 12.947795 -6.414108) (xy 12.936519 -6.493652) (xy 12.917573 -6.571726) (xy 12.891136 -6.647591)
			(xy 12.85746 -6.720532) (xy 12.816861 -6.789858) (xy 12.769723 -6.854916) (xy 12.716492 -6.91509)
			(xy 12.65767 -6.969812) (xy 12.593814 -7.018564) (xy 12.525526 -7.060887) (xy 12.453452 -7.09638)
			(xy 12.416028 -7.110984) (xy 12.377392 -7.125019) (xy 12.297976 -7.146257) (xy 12.216843 -7.159501)
			(xy 12.134797 -7.164622) (xy 12.052647 -7.161567) (xy 11.971207 -7.150367) (xy 11.891282 -7.131133)
			(xy 11.813663 -7.104056) (xy 11.739117 -7.069402) (xy 11.668383 -7.027516) (xy 11.602158 -6.97881)
			(xy 11.541099 -6.923767) (xy 11.48581 -6.862932) (xy 11.436836 -6.796905) (xy 11.394663 -6.72634)
			(xy 11.359708 -6.651936) (xy 11.332317 -6.574427) (xy 11.31276 -6.494581) (xy 11.30123 -6.413187)
			(xy 11.297843 -6.33105) (xy 11.302631 -6.248983) (xy 11.315547 -6.167797) (xy 11.336463 -6.088296)
			(xy 11.365173 -6.011266) (xy 11.401392 -5.937469) (xy 11.444762 -5.867634) (xy 11.494855 -5.802452)
			(xy 11.551174 -5.742568) (xy 11.581892 -5.715254) (xy 11.598152 -5.700437) (xy 11.625808 -5.666233)
			(xy 11.647161 -5.627776) (xy 11.661571 -5.586217) (xy 11.668608 -5.542797) (xy 11.668063 -5.498814)
			(xy 11.65995 -5.455582) (xy 11.644513 -5.414393) (xy 11.622213 -5.376478) (xy 11.593717 -5.34297)
			(xy 11.559875 -5.314871) (xy 11.5217 -5.29302) (xy 11.480332 -5.27807) (xy 11.437007 -5.270468) (xy 11.415014 -5.269992)
			(xy 10.294366 -5.269992) (xy 10.272362 -5.270455) (xy 10.229012 -5.278028) (xy 10.187615 -5.292958)
			(xy 10.149411 -5.3148) (xy 10.115542 -5.342899) (xy 10.087023 -5.376414) (xy 10.064707 -5.414343)
			(xy 10.049261 -5.45555) (xy 10.041148 -5.498803) (xy 10.040611 -5.542807) (xy 10.047665 -5.586245)
			(xy 10.0621 -5.627817) (xy 10.083483 -5.66628) (xy 10.111175 -5.700482) (xy 10.127488 -5.715254)
			(xy 10.157987 -5.742495) (xy 10.214028 -5.802055) (xy 10.263909 -5.866861) (xy 10.307143 -5.936278)
			(xy 10.343307 -6.009628) (xy 10.372047 -6.086192) (xy 10.39308 -6.165221) (xy 10.406203 -6.245941)
			(xy 10.411285 -6.327563) (xy 10.408277 -6.409288) (xy 10.397209 -6.490316) (xy 10.37819 -6.569853)
			(xy 10.351404 -6.647123) (xy 10.317115 -6.721367) (xy 10.275658 -6.79186) (xy 10.227438 -6.857912)
			(xy 10.172928 -6.918876) (xy 10.112661 -6.974156) (xy 10.047227 -7.023211) (xy 9.977266 -7.06556)
			(xy 9.903463 -7.100789) (xy 9.82654 -7.128554) (xy 9.747251 -7.148582) (xy 9.66637 -7.160678) (xy 9.58469 -7.164723)
			(xy 9.50301 -7.160678) (xy 9.422129 -7.148582) (xy 9.34284 -7.128554) (xy 9.265917 -7.100789) (xy 9.192114 -7.06556)
			(xy 9.122153 -7.023211) (xy 9.056719 -6.974156) (xy 8.996452 -6.918876) (xy 8.941942 -6.857912) (xy 8.893722 -6.79186)
			(xy 8.852265 -6.721367) (xy 8.817976 -6.647123) (xy 8.79119 -6.569853) (xy 8.772171 -6.490316) (xy 8.761103 -6.409288)
			(xy 8.758095 -6.327563) (xy 8.763177 -6.245941) (xy 8.7763 -6.165221) (xy 8.797333 -6.086192) (xy 8.826073 -6.009628)
			(xy 8.862237 -5.936278) (xy 8.905471 -5.866861) (xy 8.955352 -5.802055) (xy 9.011393 -5.742495) (xy 9.041892 -5.715254)
			(xy 9.058152 -5.700437) (xy 9.085808 -5.666233) (xy 9.107161 -5.627776) (xy 9.121571 -5.586217) (xy 9.128608 -5.542797)
			(xy 9.128063 -5.498814) (xy 9.11995 -5.455582) (xy 9.104513 -5.414393) (xy 9.082213 -5.376478) (xy 9.053717 -5.34297)
			(xy 9.019875 -5.314871) (xy 8.9817 -5.29302) (xy 8.940332 -5.27807) (xy 8.897007 -5.270468) (xy 8.875014 -5.269992)
			(xy 7.754366 -5.269992) (xy 7.732362 -5.270455) (xy 7.689012 -5.278028) (xy 7.647615 -5.292958) (xy 7.609411 -5.3148)
			(xy 7.575542 -5.342899) (xy 7.547023 -5.376414) (xy 7.524707 -5.414343) (xy 7.509261 -5.45555) (xy 7.501148 -5.498803)
			(xy 7.500611 -5.542807) (xy 7.507665 -5.586245) (xy 7.5221 -5.627817) (xy 7.543483 -5.66628) (xy 7.571175 -5.700482)
			(xy 7.587488 -5.715254) (xy 7.617987 -5.742495) (xy 7.674028 -5.802055) (xy 7.723909 -5.866861) (xy 7.767143 -5.936278)
			(xy 7.803307 -6.009628) (xy 7.832047 -6.086192) (xy 7.85308 -6.165221) (xy 7.866203 -6.245941) (xy 7.871285 -6.327563)
			(xy 7.868277 -6.409288) (xy 7.857209 -6.490316) (xy 7.83819 -6.569853) (xy 7.811404 -6.647123) (xy 7.777115 -6.721367)
			(xy 7.735658 -6.79186) (xy 7.687438 -6.857912) (xy 7.632928 -6.918876) (xy 7.572661 -6.974156) (xy 7.507227 -7.023211)
			(xy 7.437266 -7.06556) (xy 7.363463 -7.100789) (xy 7.28654 -7.128554) (xy 7.207251 -7.148582) (xy 7.12637 -7.160678)
			(xy 7.04469 -7.164723) (xy 6.96301 -7.160678) (xy 6.882129 -7.148582) (xy 6.80284 -7.128554) (xy 6.725917 -7.100789)
			(xy 6.652114 -7.06556) (xy 6.582153 -7.023211) (xy 6.516719 -6.974156) (xy 6.456452 -6.918876) (xy 6.401942 -6.857912)
			(xy 6.353722 -6.79186) (xy 6.312265 -6.721367) (xy 6.277976 -6.647123) (xy 6.25119 -6.569853) (xy 6.232171 -6.490316)
			(xy 6.221103 -6.409288) (xy 6.218095 -6.327563) (xy 6.223177 -6.245941) (xy 6.2363 -6.165221) (xy 6.257333 -6.086192)
			(xy 6.286073 -6.009628) (xy 6.322237 -5.936278) (xy 6.365471 -5.866861) (xy 6.415352 -5.802055) (xy 6.471393 -5.742495)
			(xy 6.501892 -5.715254) (xy 6.518152 -5.700437) (xy 6.545808 -5.666233) (xy 6.567161 -5.627776) (xy 6.581571 -5.586217)
			(xy 6.588608 -5.542797) (xy 6.588063 -5.498814) (xy 6.57995 -5.455582) (xy 6.564513 -5.414393) (xy 6.542213 -5.376478)
			(xy 6.513717 -5.34297) (xy 6.479875 -5.314871) (xy 6.4417 -5.29302) (xy 6.400332 -5.27807) (xy 6.357007 -5.270468)
			(xy 6.335014 -5.269992) (xy 5.214366 -5.269992) (xy 5.192362 -5.270455) (xy 5.149012 -5.278028) (xy 5.107615 -5.292958)
			(xy 5.069411 -5.3148) (xy 5.035542 -5.342899) (xy 5.007023 -5.376414) (xy 4.984707 -5.414343) (xy 4.969261 -5.45555)
			(xy 4.961148 -5.498803) (xy 4.960611 -5.542807) (xy 4.967665 -5.586245) (xy 4.9821 -5.627817) (xy 5.003483 -5.66628)
			(xy 5.031175 -5.700482) (xy 5.047488 -5.715254) (xy 5.077987 -5.742495) (xy 5.134028 -5.802055) (xy 5.183909 -5.866861)
			(xy 5.227143 -5.936278) (xy 5.263307 -6.009628) (xy 5.292047 -6.086192) (xy 5.31308 -6.165221) (xy 5.326203 -6.245941)
			(xy 5.331285 -6.327563) (xy 5.328277 -6.409288) (xy 5.317209 -6.490316) (xy 5.29819 -6.569853) (xy 5.271404 -6.647123)
			(xy 5.237115 -6.721367) (xy 5.195658 -6.79186) (xy 5.147438 -6.857912) (xy 5.092928 -6.918876) (xy 5.032661 -6.974156)
			(xy 4.967227 -7.023211) (xy 4.897266 -7.06556) (xy 4.823463 -7.100789) (xy 4.74654 -7.128554) (xy 4.667251 -7.148582)
			(xy 4.58637 -7.160678) (xy 4.50469 -7.164723) (xy 4.42301 -7.160678) (xy 4.342129 -7.148582) (xy 4.26284 -7.128554)
			(xy 4.185917 -7.100789) (xy 4.112114 -7.06556) (xy 4.042153 -7.023211) (xy 3.976719 -6.974156) (xy 3.916452 -6.918876)
			(xy 3.861942 -6.857912) (xy 3.813722 -6.79186) (xy 3.772265 -6.721367) (xy 3.737976 -6.647123) (xy 3.71119 -6.569853)
			(xy 3.692171 -6.490316) (xy 3.681103 -6.409288) (xy 3.678095 -6.327563) (xy 3.683177 -6.245941) (xy 3.6963 -6.165221)
			(xy 3.717333 -6.086192) (xy 3.746073 -6.009628) (xy 3.782237 -5.936278) (xy 3.825471 -5.866861) (xy 3.875352 -5.802055)
			(xy 3.931393 -5.742495) (xy 3.961892 -5.715254) (xy 3.978152 -5.700437) (xy 4.005808 -5.666233) (xy 4.027161 -5.627776)
			(xy 4.041571 -5.586217) (xy 4.048608 -5.542797) (xy 4.048063 -5.498814) (xy 4.03995 -5.455582) (xy 4.024513 -5.414393)
			(xy 4.002213 -5.376478) (xy 3.973717 -5.34297) (xy 3.939875 -5.314871) (xy 3.9017 -5.29302) (xy 3.860332 -5.27807)
			(xy 3.817007 -5.270468) (xy 3.795014 -5.269992) (xy 1.510792 -5.269992) (xy 1.48827 -5.269458) (xy 1.443717 -5.276086)
			(xy 1.401302 -5.291246) (xy 1.362641 -5.31436) (xy 1.32921 -5.344547) (xy 1.302284 -5.380656) (xy 1.282888 -5.421309)
			(xy 1.271763 -5.464957) (xy 1.27 -5.487416) (xy 1.27 -8.052308) (xy 12.568936 -8.052308) (xy 14.220444 -8.052308)
			(xy 14.220444 -9.703816) (xy 12.568936 -9.703816) (xy 12.568936 -8.052308) (xy 1.27 -8.052308) (xy 1.27 -8.918617)
			(xy 4.94918 -8.918617) (xy 4.94918 -8.837507) (xy 4.95713 -8.756788) (xy 4.972953 -8.677237) (xy 4.996498 -8.599621)
			(xy 5.027537 -8.524685) (xy 5.065772 -8.453153) (xy 5.110834 -8.385713) (xy 5.162289 -8.323014) (xy 5.219642 -8.265661)
			(xy 5.282341 -8.214206) (xy 5.349781 -8.169144) (xy 5.421313 -8.130909) (xy 5.496249 -8.09987) (xy 5.573865 -8.076325)
			(xy 5.653416 -8.060502) (xy 5.734135 -8.052552) (xy 5.815245 -8.052552) (xy 5.895964 -8.060502) (xy 5.975515 -8.076325)
			(xy 6.053131 -8.09987) (xy 6.128067 -8.130909) (xy 6.199599 -8.169144) (xy 6.267039 -8.214206) (xy 6.329738 -8.265661)
			(xy 6.387091 -8.323014) (xy 6.438546 -8.385713) (xy 6.483608 -8.453153) (xy 6.521843 -8.524685) (xy 6.552882 -8.599621)
			(xy 6.576427 -8.677237) (xy 6.59225 -8.756788) (xy 6.6002 -8.837507) (xy 6.600698 -8.878062) (xy 6.6002 -8.918617)
			(xy 7.48918 -8.918617) (xy 7.48918 -8.837507) (xy 7.49713 -8.756788) (xy 7.512953 -8.677237) (xy 7.536498 -8.599621)
			(xy 7.567537 -8.524685) (xy 7.605772 -8.453153) (xy 7.650834 -8.385713) (xy 7.702289 -8.323014) (xy 7.759642 -8.265661)
			(xy 7.822341 -8.214206) (xy 7.889781 -8.169144) (xy 7.961313 -8.130909) (xy 8.036249 -8.09987) (xy 8.113865 -8.076325)
			(xy 8.193416 -8.060502) (xy 8.274135 -8.052552) (xy 8.355245 -8.052552) (xy 8.435964 -8.060502) (xy 8.515515 -8.076325)
			(xy 8.593131 -8.09987) (xy 8.668067 -8.130909) (xy 8.739599 -8.169144) (xy 8.807039 -8.214206) (xy 8.869738 -8.265661)
			(xy 8.927091 -8.323014) (xy 8.978546 -8.385713) (xy 9.023608 -8.453153) (xy 9.061843 -8.524685) (xy 9.092882 -8.599621)
			(xy 9.116427 -8.677237) (xy 9.13225 -8.756788) (xy 9.1402 -8.837507) (xy 9.140698 -8.878062) (xy 9.1402 -8.918617)
			(xy 10.02918 -8.918617) (xy 10.02918 -8.837507) (xy 10.03713 -8.756788) (xy 10.052953 -8.677237)
			(xy 10.076498 -8.599621) (xy 10.107537 -8.524685) (xy 10.145772 -8.453153) (xy 10.190834 -8.385713)
			(xy 10.242289 -8.323014) (xy 10.299642 -8.265661) (xy 10.362341 -8.214206) (xy 10.429781 -8.169144)
			(xy 10.501313 -8.130909) (xy 10.576249 -8.09987) (xy 10.653865 -8.076325) (xy 10.733416 -8.060502)
			(xy 10.814135 -8.052552) (xy 10.895245 -8.052552) (xy 10.975964 -8.060502) (xy 11.055515 -8.076325)
			(xy 11.133131 -8.09987) (xy 11.208067 -8.130909) (xy 11.279599 -8.169144) (xy 11.347039 -8.214206)
			(xy 11.409738 -8.265661) (xy 11.467091 -8.323014) (xy 11.518546 -8.385713) (xy 11.563608 -8.453153)
			(xy 11.601843 -8.524685) (xy 11.632882 -8.599621) (xy 11.656427 -8.677237) (xy 11.67225 -8.756788)
			(xy 11.6802 -8.837507) (xy 11.680698 -8.878062) (xy 11.6802 -8.918617) (xy 11.67225 -8.999336) (xy 11.656427 -9.078887)
			(xy 11.632882 -9.156503) (xy 11.601843 -9.231439) (xy 11.563608 -9.302971) (xy 11.518546 -9.370411)
			(xy 11.467091 -9.43311) (xy 11.409738 -9.490463) (xy 11.347039 -9.541918) (xy 11.279599 -9.58698)
			(xy 11.208067 -9.625215) (xy 11.133131 -9.656254) (xy 11.055515 -9.679799) (xy 10.975964 -9.695622)
			(xy 10.895245 -9.703572) (xy 10.814135 -9.703572) (xy 10.733416 -9.695622) (xy 10.653865 -9.679799)
			(xy 10.576249 -9.656254) (xy 10.501313 -9.625215) (xy 10.429781 -9.58698) (xy 10.362341 -9.541918)
			(xy 10.299642 -9.490463) (xy 10.242289 -9.43311) (xy 10.190834 -9.370411) (xy 10.145772 -9.302971)
			(xy 10.107537 -9.231439) (xy 10.076498 -9.156503) (xy 10.052953 -9.078887) (xy 10.03713 -8.999336)
			(xy 10.02918 -8.918617) (xy 9.1402 -8.918617) (xy 9.13225 -8.999336) (xy 9.116427 -9.078887) (xy 9.092882 -9.156503)
			(xy 9.061843 -9.231439) (xy 9.023608 -9.302971) (xy 8.978546 -9.370411) (xy 8.927091 -9.43311) (xy 8.869738 -9.490463)
			(xy 8.807039 -9.541918) (xy 8.739599 -9.58698) (xy 8.668067 -9.625215) (xy 8.593131 -9.656254) (xy 8.515515 -9.679799)
			(xy 8.435964 -9.695622) (xy 8.355245 -9.703572) (xy 8.274135 -9.703572) (xy 8.193416 -9.695622) (xy 8.113865 -9.679799)
			(xy 8.036249 -9.656254) (xy 7.961313 -9.625215) (xy 7.889781 -9.58698) (xy 7.822341 -9.541918) (xy 7.759642 -9.490463)
			(xy 7.702289 -9.43311) (xy 7.650834 -9.370411) (xy 7.605772 -9.302971) (xy 7.567537 -9.231439) (xy 7.536498 -9.156503)
			(xy 7.512953 -9.078887) (xy 7.49713 -8.999336) (xy 7.48918 -8.918617) (xy 6.6002 -8.918617) (xy 6.59225 -8.999336)
			(xy 6.576427 -9.078887) (xy 6.552882 -9.156503) (xy 6.521843 -9.231439) (xy 6.483608 -9.302971) (xy 6.438546 -9.370411)
			(xy 6.387091 -9.43311) (xy 6.329738 -9.490463) (xy 6.267039 -9.541918) (xy 6.199599 -9.58698) (xy 6.128067 -9.625215)
			(xy 6.053131 -9.656254) (xy 5.975515 -9.679799) (xy 5.895964 -9.695622) (xy 5.815245 -9.703572) (xy 5.734135 -9.703572)
			(xy 5.653416 -9.695622) (xy 5.573865 -9.679799) (xy 5.496249 -9.656254) (xy 5.421313 -9.625215) (xy 5.349781 -9.58698)
			(xy 5.282341 -9.541918) (xy 5.219642 -9.490463) (xy 5.162289 -9.43311) (xy 5.110834 -9.370411) (xy 5.065772 -9.302971)
			(xy 5.027537 -9.231439) (xy 4.996498 -9.156503) (xy 4.972953 -9.078887) (xy 4.95713 -8.999336) (xy 4.94918 -8.918617)
			(xy 1.27 -8.918617) (xy 1.27 -13.635482) (xy 1.270551 -13.658845) (xy 1.279134 -13.704775) (xy 1.29597 -13.748363)
			(xy 1.320491 -13.788138) (xy 1.351871 -13.822759) (xy 1.389051 -13.85106) (xy 1.430779 -13.872086)
			(xy 1.475648 -13.885128) (xy 1.522145 -13.889748) (xy 1.568703 -13.885788) (xy 1.613752 -13.873383)
			(xy 1.655774 -13.852951) (xy 1.693353 -13.825181) (xy 1.709674 -13.808456) (xy 1.754144 -13.76142)
			(xy 1.848063 -13.672323) (xy 1.947333 -13.58923) (xy 2.051571 -13.512461) (xy 2.160374 -13.442312)
			(xy 2.273323 -13.379054) (xy 2.389981 -13.322931) (xy 2.509899 -13.274159) (xy 2.632614 -13.232928)
			(xy 2.757652 -13.199394) (xy 2.88453 -13.17369) (xy 3.01276 -13.155912) (xy 3.141847 -13.146131)
			(xy 3.271292 -13.144383) (xy 3.400595 -13.150676) (xy 3.529258 -13.164985) (xy 3.656785 -13.187255)
			(xy 3.782683 -13.2174) (xy 3.906466 -13.255304) (xy 4.027657 -13.30082) (xy 4.145788 -13.353773)
			(xy 4.260403 -13.413959) (xy 4.37106 -13.481145) (xy 4.477332 -13.555072) (xy 4.57881 -13.635454)
			(xy 4.6751 -13.721983) (xy 4.765832 -13.814323) (xy 4.850656 -13.912118) (xy 4.929244 -14.014991)
			(xy 5.001293 -14.122545) (xy 5.066525 -14.234365) (xy 5.124689 -14.35002) (xy 5.175559 -14.469063)
			(xy 5.21894 -14.591034) (xy 5.254664 -14.715464) (xy 5.282593 -14.841872) (xy 5.30262 -14.96977)
			(xy 5.314668 -15.098665) (xy 5.318688 -15.228059) (xy 5.318688 -15.228062) (xy 12.580624 -15.228062)
			(xy 12.584655 -15.098496) (xy 12.596734 -14.969432) (xy 12.616813 -14.841368) (xy 12.644815 -14.714801)
			(xy 12.680632 -14.590218) (xy 12.724124 -14.468104) (xy 12.775124 -14.34893) (xy 12.833435 -14.233157)
			(xy 12.89883 -14.121233) (xy 12.971057 -14.013591) (xy 13.049837 -13.910648) (xy 13.134864 -13.812802)
			(xy 13.225809 -13.72043) (xy 13.322321 -13.633892) (xy 13.424027 -13.553521) (xy 13.530533 -13.479629)
			(xy 13.641426 -13.412501) (xy 13.756278 -13.352397) (xy 13.874645 -13.29955) (xy 13.996068 -13.254163)
			(xy 14.120078 -13.216414) (xy 14.246195 -13.186447) (xy 14.373931 -13.164378) (xy 14.502792 -13.150294)
			(xy 14.632279 -13.144248) (xy 14.761892 -13.146264) (xy 14.891128 -13.156334) (xy 15.019489 -13.174419)
			(xy 15.146477 -13.200449) (xy 15.271601 -13.234324) (xy 15.394377 -13.275912) (xy 15.51433 -13.325053)
			(xy 15.630995 -13.381556) (xy 15.743923 -13.445203) (xy 15.852675 -13.515747) (xy 15.956831 -13.592916)
			(xy 16.055988 -13.676411) (xy 16.149762 -13.765909) (xy 16.237791 -13.861064) (xy 16.319734 -13.961507)
			(xy 16.395273 -14.06685) (xy 16.464118 -14.176686) (xy 16.526001 -14.29059) (xy 16.580682 -14.40812)
			(xy 16.627952 -14.528823) (xy 16.667625 -14.652231) (xy 16.69955 -14.777867) (xy 16.723602 -14.905244)
			(xy 16.739689 -15.03387) (xy 16.747748 -15.163248) (xy 16.748252 -15.228062) (xy 16.747748 -15.292876)
			(xy 16.739689 -15.422254) (xy 16.723602 -15.55088) (xy 16.69955 -15.678257) (xy 16.667625 -15.803893)
			(xy 16.627952 -15.927301) (xy 16.580682 -16.048004) (xy 16.526001 -16.165534) (xy 16.464118 -16.279438)
			(xy 16.395273 -16.389274) (xy 16.319734 -16.494617) (xy 16.237791 -16.59506) (xy 16.149762 -16.690215)
			(xy 16.055988 -16.779713) (xy 15.956831 -16.863208) (xy 15.852675 -16.940377) (xy 15.743923 -17.010921)
			(xy 15.630995 -17.074568) (xy 15.51433 -17.131071) (xy 15.394377 -17.180212) (xy 15.271601 -17.2218)
			(xy 15.146477 -17.255675) (xy 15.019489 -17.281705) (xy 14.891128 -17.29979) (xy 14.761892 -17.30986)
			(xy 14.632279 -17.311876) (xy 14.502792 -17.30583) (xy 14.373931 -17.291746) (xy 14.246195 -17.269677)
			(xy 14.120078 -17.23971) (xy 13.996068 -17.201961) (xy 13.874645 -17.156574) (xy 13.756278 -17.103727)
			(xy 13.641426 -17.043623) (xy 13.530533 -16.976495) (xy 13.424027 -16.902603) (xy 13.322321 -16.822232)
			(xy 13.225809 -16.735694) (xy 13.134864 -16.643322) (xy 13.049837 -16.545476) (xy 12.971057 -16.442533)
			(xy 12.89883 -16.334891) (xy 12.833435 -16.222967) (xy 12.775124 -16.107194) (xy 12.724124 -15.98802)
			(xy 12.680632 -15.865906) (xy 12.644815 -15.741323) (xy 12.616813 -15.614756) (xy 12.596734 -15.486692)
			(xy 12.584655 -15.357628) (xy 12.580624 -15.228062) (xy 5.318688 -15.228062) (xy 5.314668 -15.357453)
			(xy 5.302621 -15.486347) (xy 5.282594 -15.614245) (xy 5.254665 -15.740653) (xy 5.218941 -15.865083)
			(xy 5.17556 -15.987055) (xy 5.12469 -16.106097) (xy 5.066527 -16.221752) (xy 5.001295 -16.333572)
			(xy 4.929246 -16.441127) (xy 4.850658 -16.544) (xy 4.765834 -16.641795) (xy 4.675102 -16.734135)
			(xy 4.578812 -16.820664) (xy 4.477335 -16.901046) (xy 4.371063 -16.974974) (xy 4.260405 -17.04216)
			(xy 4.14579 -17.102345) (xy 4.027659 -17.155299) (xy 3.906468 -17.200815) (xy 3.782685 -17.238719)
			(xy 3.656788 -17.268865) (xy 3.529261 -17.291135) (xy 3.400598 -17.305444) (xy 3.271294 -17.311737)
			(xy 3.14185 -17.309989) (xy 3.012763 -17.300208) (xy 2.884533 -17.282431) (xy 2.757654 -17.256726)
			(xy 2.632616 -17.223193) (xy 2.509902 -17.181962) (xy 2.389984 -17.13319) (xy 2.273325 -17.077067)
			(xy 2.160376 -17.013809) (xy 2.051573 -16.94366) (xy 1.947336 -16.866891) (xy 1.848066 -16.783798)
			(xy 1.754146 -16.694702) (xy 1.709674 -16.647668) (xy 1.693349 -16.630952) (xy 1.655768 -16.603199)
			(xy 1.613748 -16.582782) (xy 1.568705 -16.570389) (xy 1.522154 -16.566437) (xy 1.475666 -16.57106)
			(xy 1.430806 -16.584102) (xy 1.389084 -16.605123) (xy 1.351908 -16.633415) (xy 1.320529 -16.668026)
			(xy 1.296004 -16.707788) (xy 1.27916 -16.751364) (xy 1.270564 -16.797284) (xy 1.27 -16.820642) (xy 1.27 -29.19984)
			(xy 8.597656 -29.19984) (xy 8.601644 -28.94722) (xy 8.613605 -28.694852) (xy 8.633527 -28.442988)
			(xy 8.661391 -28.191878) (xy 8.697167 -27.941772) (xy 8.740821 -27.692921) (xy 8.79231 -27.445572)
			(xy 8.851581 -27.199971) (xy 8.918576 -26.956364) (xy 8.993227 -26.714994) (xy 9.075462 -26.4761)
			(xy 9.165196 -26.239922) (xy 9.262342 -26.006694) (xy 9.366802 -25.776648) (xy 9.478473 -25.550016)
			(xy 9.597242 -25.327021) (xy 9.722991 -25.107887) (xy 9.855596 -24.892832) (xy 9.994923 -24.68207)
			(xy 10.140835 -24.475812) (xy 10.293185 -24.274263) (xy 10.451821 -24.077623) (xy 10.616586 -23.88609)
			(xy 10.787316 -23.699853) (xy 10.96384 -23.519099) (xy 11.145982 -23.344008) (xy 11.33356 -23.174754)
			(xy 11.526388 -23.011505) (xy 11.724273 -22.854426) (xy 11.927019 -22.703671) (xy 12.134423 -22.559393)
			(xy 12.346278 -22.421733) (xy 12.562373 -22.29083) (xy 12.782493 -22.166814) (xy 13.006418 -22.049809)
			(xy 13.233925 -21.939931) (xy 13.464787 -21.83729) (xy 13.698775 -21.741988) (xy 13.935654 -21.654121)
			(xy 14.17519 -21.573774) (xy 14.417142 -21.50103) (xy 14.66127 -21.43596) (xy 14.907331 -21.37863)
			(xy 15.155079 -21.329096) (xy 15.404267 -21.287407) (xy 15.654647 -21.253606) (xy 15.905969 -21.227725)
			(xy 16.157983 -21.209792) (xy 16.410437 -21.199823) (xy 16.663081 -21.197829) (xy 16.915661 -21.203811)
			(xy 17.167927 -21.217764) (xy 17.419626 -21.239674) (xy 17.670509 -21.269518) (xy 17.920324 -21.307268)
			(xy 18.168823 -21.352885) (xy 18.415758 -21.406324) (xy 18.660883 -21.467532) (xy 18.903953 -21.536447)
			(xy 19.144727 -21.613002) (xy 19.382964 -21.697119) (xy 19.618427 -21.788716) (xy 19.850881 -21.8877)
			(xy 20.080095 -21.993972) (xy 20.305839 -22.107428) (xy 20.527889 -22.227953) (xy 20.746023 -22.355429)
			(xy 20.960025 -22.489727) (xy 21.169681 -22.630713) (xy 21.374781 -22.778248) (xy 21.575121 -22.932184)
			(xy 21.770502 -23.092368) (xy 21.960729 -23.25864) (xy 22.145612 -23.430835) (xy 22.324968 -23.608779)
			(xy 22.498616 -23.792298) (xy 22.666384 -23.981206) (xy 22.828105 -24.175317) (xy 22.983618 -24.374436)
			(xy 23.132767 -24.578365) (xy 23.275404 -24.786901) (xy 23.411387 -24.999836) (xy 23.54058 -25.216958)
			(xy 23.662855 -25.43805) (xy 23.778089 -25.662891) (xy 23.886168 -25.891259) (xy 23.986983 -26.122924)
			(xy 24.080435 -26.357657) (xy 24.16643 -26.595222) (xy 24.244883 -26.835384) (xy 24.315715 -27.077903)
			(xy 24.378856 -27.322538) (xy 24.434243 -27.569043) (xy 24.48182 -27.817174) (xy 24.52154 -28.066684)
			(xy 24.553364 -28.317323) (xy 24.57726 -28.568841) (xy 24.593204 -28.820989) (xy 24.601179 -29.073514)
			(xy 24.601678 -29.19984) (xy 24.601179 -29.326166) (xy 24.593204 -29.578691) (xy 24.57726 -29.830839)
			(xy 24.553364 -30.082357) (xy 24.52154 -30.332996) (xy 24.48182 -30.582506) (xy 24.434243 -30.830637)
			(xy 24.378856 -31.077142) (xy 24.315715 -31.321777) (xy 24.244883 -31.564296) (xy 24.16643 -31.804458)
			(xy 24.080435 -32.042023) (xy 23.986983 -32.276756) (xy 23.886168 -32.508421) (xy 23.778089 -32.736789)
			(xy 23.662855 -32.96163) (xy 23.54058 -33.182722) (xy 23.411387 -33.399844) (xy 23.275404 -33.612779)
			(xy 23.132767 -33.821315) (xy 22.983618 -34.025244) (xy 22.828105 -34.224363) (xy 22.666384 -34.418474)
			(xy 22.498616 -34.607382) (xy 22.324968 -34.790901) (xy 22.145612 -34.968845) (xy 21.960729 -35.14104)
			(xy 21.770502 -35.307312) (xy 21.575121 -35.467496) (xy 21.374781 -35.621432) (xy 21.169681 -35.768967)
			(xy 20.960025 -35.909953) (xy 20.746023 -36.044251) (xy 20.527889 -36.171727) (xy 20.305839 -36.292252)
			(xy 20.080095 -36.405708) (xy 19.850881 -36.51198) (xy 19.618427 -36.610964) (xy 19.382964 -36.702561)
			(xy 19.144727 -36.786678) (xy 18.903953 -36.863233) (xy 18.660883 -36.932148) (xy 18.415758 -36.993356)
			(xy 18.168823 -37.046795) (xy 17.920324 -37.092412) (xy 17.670509 -37.130162) (xy 17.419626 -37.160006)
			(xy 17.167927 -37.181916) (xy 16.915661 -37.195869) (xy 16.663081 -37.201851) (xy 16.410437 -37.199857)
			(xy 16.157983 -37.189888) (xy 15.905969 -37.171955) (xy 15.654647 -37.146074) (xy 15.404267 -37.112273)
			(xy 15.155079 -37.070584) (xy 14.907331 -37.02105) (xy 14.66127 -36.96372) (xy 14.417142 -36.89865)
			(xy 14.17519 -36.825906) (xy 13.935654 -36.745559) (xy 13.698775 -36.657692) (xy 13.464787 -36.56239)
			(xy 13.233925 -36.459749) (xy 13.006418 -36.349871) (xy 12.782493 -36.232866) (xy 12.562373 -36.10885)
			(xy 12.346278 -35.977947) (xy 12.134423 -35.840287) (xy 11.927019 -35.696009) (xy 11.724273 -35.545254)
			(xy 11.526388 -35.388175) (xy 11.33356 -35.224926) (xy 11.145982 -35.055672) (xy 10.96384 -34.880581)
			(xy 10.787316 -34.699827) (xy 10.616586 -34.51359) (xy 10.451821 -34.322057) (xy 10.293185 -34.125417)
			(xy 10.140835 -33.923868) (xy 9.994923 -33.71761) (xy 9.855596 -33.506848) (xy 9.722991 -33.291793)
			(xy 9.597242 -33.072659) (xy 9.478473 -32.849664) (xy 9.366802 -32.623032) (xy 9.262342 -32.392986)
			(xy 9.165196 -32.159758) (xy 9.075462 -31.92358) (xy 8.993227 -31.684686) (xy 8.918576 -31.443316)
			(xy 8.851581 -31.199709) (xy 8.79231 -30.954108) (xy 8.740821 -30.706759) (xy 8.697167 -30.457908)
			(xy 8.661391 -30.207802) (xy 8.633527 -29.956692) (xy 8.613605 -29.704828) (xy 8.601644 -29.45246)
			(xy 8.597656 -29.19984) (xy 1.27 -29.19984) (xy 1.27 -44.629324) (xy 1.270551 -44.652686) (xy 1.279134 -44.698617)
			(xy 1.29597 -44.742204) (xy 1.320492 -44.781979) (xy 1.351871 -44.8166) (xy 1.389052 -44.8449) (xy 1.430779 -44.865926)
			(xy 1.475648 -44.878968) (xy 1.522145 -44.883588) (xy 1.568703 -44.879628) (xy 1.613752 -44.867224)
			(xy 1.655774 -44.846792) (xy 1.693352 -44.819022) (xy 1.709674 -44.802298) (xy 1.754144 -44.755262)
			(xy 1.848064 -44.666165) (xy 1.947334 -44.583072) (xy 2.051571 -44.506303) (xy 2.160374 -44.436154)
			(xy 2.273323 -44.372896) (xy 2.389982 -44.316773) (xy 2.5099 -44.268002) (xy 2.632615 -44.22677)
			(xy 2.757653 -44.193237) (xy 2.884532 -44.167532) (xy 3.012762 -44.149755) (xy 3.141848 -44.139973)
			(xy 3.271293 -44.138226) (xy 3.400597 -44.144519) (xy 3.52926 -44.158828) (xy 3.656786 -44.181098)
			(xy 3.782684 -44.211243) (xy 3.906468 -44.249147) (xy 4.027658 -44.294663) (xy 4.14579 -44.347617)
			(xy 4.260405 -44.407802) (xy 4.371062 -44.474989) (xy 4.477334 -44.548916) (xy 4.578812 -44.629298)
			(xy 4.675102 -44.715827) (xy 4.765834 -44.808167) (xy 4.850658 -44.905962) (xy 4.929246 -45.008835)
			(xy 5.001295 -45.11639) (xy 5.066527 -45.22821) (xy 5.124691 -45.343865) (xy 5.175561 -45.462908)
			(xy 5.218942 -45.584879) (xy 5.254666 -45.709309) (xy 5.282595 -45.835717) (xy 5.302622 -45.963615)
			(xy 5.314669 -46.09251) (xy 5.31869 -46.221904) (xy 12.580624 -46.221904) (xy 12.584655 -46.092338)
			(xy 12.596734 -45.963274) (xy 12.616813 -45.83521) (xy 12.644815 -45.708643) (xy 12.680632 -45.58406)
			(xy 12.724124 -45.461946) (xy 12.775124 -45.342772) (xy 12.833435 -45.226999) (xy 12.89883 -45.115075)
			(xy 12.971057 -45.007433) (xy 13.049837 -44.90449) (xy 13.134864 -44.806644) (xy 13.225809 -44.714272)
			(xy 13.322321 -44.627734) (xy 13.424027 -44.547363) (xy 13.530533 -44.473471) (xy 13.641426 -44.406343)
			(xy 13.756278 -44.346239) (xy 13.874645 -44.293392) (xy 13.996068 -44.248005) (xy 14.120078 -44.210256)
			(xy 14.246195 -44.180289) (xy 14.373931 -44.15822) (xy 14.502792 -44.144136) (xy 14.632279 -44.13809)
			(xy 14.761892 -44.140106) (xy 14.891128 -44.150176) (xy 15.019489 -44.168261) (xy 15.146477 -44.194291)
			(xy 15.271601 -44.228166) (xy 15.394377 -44.269754) (xy 15.51433 -44.318895) (xy 15.630995 -44.375398)
			(xy 15.743923 -44.439045) (xy 15.852675 -44.509589) (xy 15.956831 -44.586758) (xy 16.055988 -44.670253)
			(xy 16.149762 -44.759751) (xy 16.237791 -44.854906) (xy 16.319734 -44.955349) (xy 16.395273 -45.060692)
			(xy 16.464118 -45.170528) (xy 16.526001 -45.284432) (xy 16.580682 -45.401962) (xy 16.627952 -45.522665)
			(xy 16.667625 -45.646073) (xy 16.69955 -45.771709) (xy 16.723602 -45.899086) (xy 16.739689 -46.027712)
			(xy 16.747748 -46.15709) (xy 16.748252 -46.221904) (xy 16.747748 -46.286718) (xy 16.739689 -46.416096)
			(xy 16.723602 -46.544722) (xy 16.69955 -46.672099) (xy 16.667625 -46.797735) (xy 16.627952 -46.921143)
			(xy 16.580682 -47.041846) (xy 16.526001 -47.159376) (xy 16.464118 -47.27328) (xy 16.395273 -47.383116)
			(xy 16.319734 -47.488459) (xy 16.237791 -47.588902) (xy 16.149762 -47.684057) (xy 16.055988 -47.773555)
			(xy 15.956831 -47.85705) (xy 15.852675 -47.934219) (xy 15.743923 -48.004763) (xy 15.630995 -48.06841)
			(xy 15.51433 -48.124913) (xy 15.394377 -48.174054) (xy 15.271601 -48.215642) (xy 15.146477 -48.249517)
			(xy 15.019489 -48.275547) (xy 14.891128 -48.293632) (xy 14.761892 -48.303702) (xy 14.632279 -48.305718)
			(xy 14.502792 -48.299672) (xy 14.373931 -48.285588) (xy 14.246195 -48.263519) (xy 14.120078 -48.233552)
			(xy 13.996068 -48.195803) (xy 13.874645 -48.150416) (xy 13.756278 -48.097569) (xy 13.641426 -48.037465)
			(xy 13.530533 -47.970337) (xy 13.424027 -47.896445) (xy 13.322321 -47.816074) (xy 13.225809 -47.729536)
			(xy 13.134864 -47.637164) (xy 13.049837 -47.539318) (xy 12.971057 -47.436375) (xy 12.89883 -47.328733)
			(xy 12.833435 -47.216809) (xy 12.775124 -47.101036) (xy 12.724124 -46.981862) (xy 12.680632 -46.859748)
			(xy 12.644815 -46.735165) (xy 12.616813 -46.608598) (xy 12.596734 -46.480534) (xy 12.584655 -46.35147)
			(xy 12.580624 -46.221904) (xy 5.31869 -46.221904) (xy 5.314669 -46.351298) (xy 5.302622 -46.480193)
			(xy 5.282595 -46.608091) (xy 5.254666 -46.734499) (xy 5.218942 -46.858929) (xy 5.175561 -46.9809)
			(xy 5.124691 -47.099943) (xy 5.066527 -47.215598) (xy 5.001295 -47.327418) (xy 4.929246 -47.434973)
			(xy 4.850658 -47.537846) (xy 4.765834 -47.635641) (xy 4.675102 -47.727981) (xy 4.578812 -47.81451)
			(xy 4.477334 -47.894892) (xy 4.371062 -47.968819) (xy 4.260405 -48.036006) (xy 4.14579 -48.096191)
			(xy 4.027658 -48.149145) (xy 3.906468 -48.194661) (xy 3.782684 -48.232565) (xy 3.656786 -48.26271)
			(xy 3.52926 -48.28498) (xy 3.400597 -48.299289) (xy 3.271293 -48.305582) (xy 3.141848 -48.303835)
			(xy 3.012762 -48.294053) (xy 2.884532 -48.276276) (xy 2.757653 -48.250571) (xy 2.632615 -48.217038)
			(xy 2.5099 -48.175806) (xy 2.389982 -48.127035) (xy 2.273323 -48.070912) (xy 2.160374 -48.007654)
			(xy 2.051571 -47.937505) (xy 1.947334 -47.860736) (xy 1.848064 -47.777643) (xy 1.754144 -47.688546)
			(xy 1.709674 -47.64151) (xy 1.693349 -47.624794) (xy 1.655769 -47.597041) (xy 1.613749 -47.576624)
			(xy 1.568705 -47.56423) (xy 1.522155 -47.560278) (xy 1.475666 -47.564901) (xy 1.430806 -47.577943)
			(xy 1.389085 -47.598964) (xy 1.351908 -47.627257) (xy 1.320529 -47.661867) (xy 1.296005 -47.70163)
			(xy 1.279161 -47.745206) (xy 1.270565 -47.791126) (xy 1.27 -47.814484) (xy 1.27 -51.745896) (xy 3.678936 -51.745896)
			(xy 5.330444 -51.745896) (xy 5.330444 -52.612459) (xy 6.21918 -52.612459) (xy 6.21918 -52.531349)
			(xy 6.22713 -52.45063) (xy 6.242953 -52.371079) (xy 6.266498 -52.293463) (xy 6.297537 -52.218527)
			(xy 6.335772 -52.146995) (xy 6.380834 -52.079555) (xy 6.432289 -52.016856) (xy 6.489642 -51.959503)
			(xy 6.552341 -51.908048) (xy 6.619781 -51.862986) (xy 6.691313 -51.824751) (xy 6.766249 -51.793712)
			(xy 6.843865 -51.770167) (xy 6.923416 -51.754344) (xy 7.004135 -51.746394) (xy 7.085245 -51.746394)
			(xy 7.165964 -51.754344) (xy 7.245515 -51.770167) (xy 7.323131 -51.793712) (xy 7.398067 -51.824751)
			(xy 7.469599 -51.862986) (xy 7.537039 -51.908048) (xy 7.599738 -51.959503) (xy 7.657091 -52.016856)
			(xy 7.708546 -52.079555) (xy 7.753608 -52.146995) (xy 7.791843 -52.218527) (xy 7.822882 -52.293463)
			(xy 7.846427 -52.371079) (xy 7.86225 -52.45063) (xy 7.8702 -52.531349) (xy 7.870698 -52.571904) (xy 7.8702 -52.612459)
			(xy 8.75918 -52.612459) (xy 8.75918 -52.531349) (xy 8.76713 -52.45063) (xy 8.782953 -52.371079) (xy 8.806498 -52.293463)
			(xy 8.837537 -52.218527) (xy 8.875772 -52.146995) (xy 8.920834 -52.079555) (xy 8.972289 -52.016856)
			(xy 9.029642 -51.959503) (xy 9.092341 -51.908048) (xy 9.159781 -51.862986) (xy 9.231313 -51.824751)
			(xy 9.306249 -51.793712) (xy 9.383865 -51.770167) (xy 9.463416 -51.754344) (xy 9.544135 -51.746394)
			(xy 9.625245 -51.746394) (xy 9.705964 -51.754344) (xy 9.785515 -51.770167) (xy 9.863131 -51.793712)
			(xy 9.938067 -51.824751) (xy 10.009599 -51.862986) (xy 10.077039 -51.908048) (xy 10.139738 -51.959503)
			(xy 10.197091 -52.016856) (xy 10.248546 -52.079555) (xy 10.293608 -52.146995) (xy 10.331843 -52.218527)
			(xy 10.362882 -52.293463) (xy 10.386427 -52.371079) (xy 10.40225 -52.45063) (xy 10.4102 -52.531349)
			(xy 10.410698 -52.571904) (xy 10.4102 -52.612459) (xy 11.29918 -52.612459) (xy 11.29918 -52.531349)
			(xy 11.30713 -52.45063) (xy 11.322953 -52.371079) (xy 11.346498 -52.293463) (xy 11.377537 -52.218527)
			(xy 11.415772 -52.146995) (xy 11.460834 -52.079555) (xy 11.512289 -52.016856) (xy 11.569642 -51.959503)
			(xy 11.632341 -51.908048) (xy 11.699781 -51.862986) (xy 11.771313 -51.824751) (xy 11.846249 -51.793712)
			(xy 11.923865 -51.770167) (xy 12.003416 -51.754344) (xy 12.084135 -51.746394) (xy 12.165245 -51.746394)
			(xy 12.245964 -51.754344) (xy 12.325515 -51.770167) (xy 12.403131 -51.793712) (xy 12.478067 -51.824751)
			(xy 12.549599 -51.862986) (xy 12.617039 -51.908048) (xy 12.679738 -51.959503) (xy 12.737091 -52.016856)
			(xy 12.788546 -52.079555) (xy 12.833608 -52.146995) (xy 12.871843 -52.218527) (xy 12.902882 -52.293463)
			(xy 12.926427 -52.371079) (xy 12.94225 -52.45063) (xy 12.9502 -52.531349) (xy 12.950698 -52.571904)
			(xy 12.9502 -52.612459) (xy 12.94225 -52.693178) (xy 12.926427 -52.772729) (xy 12.902882 -52.850345)
			(xy 12.871843 -52.925281) (xy 12.833608 -52.996813) (xy 12.788546 -53.064253) (xy 12.737091 -53.126952)
			(xy 12.679738 -53.184305) (xy 12.617039 -53.23576) (xy 12.549599 -53.280822) (xy 12.478067 -53.319057)
			(xy 12.403131 -53.350096) (xy 12.325515 -53.373641) (xy 12.245964 -53.389464) (xy 12.165245 -53.397414)
			(xy 12.084135 -53.397414) (xy 12.003416 -53.389464) (xy 11.923865 -53.373641) (xy 11.846249 -53.350096)
			(xy 11.771313 -53.319057) (xy 11.699781 -53.280822) (xy 11.632341 -53.23576) (xy 11.569642 -53.184305)
			(xy 11.512289 -53.126952) (xy 11.460834 -53.064253) (xy 11.415772 -52.996813) (xy 11.377537 -52.925281)
			(xy 11.346498 -52.850345) (xy 11.322953 -52.772729) (xy 11.30713 -52.693178) (xy 11.29918 -52.612459)
			(xy 10.4102 -52.612459) (xy 10.40225 -52.693178) (xy 10.386427 -52.772729) (xy 10.362882 -52.850345)
			(xy 10.331843 -52.925281) (xy 10.293608 -52.996813) (xy 10.248546 -53.064253) (xy 10.197091 -53.126952)
			(xy 10.139738 -53.184305) (xy 10.077039 -53.23576) (xy 10.009599 -53.280822) (xy 9.938067 -53.319057)
			(xy 9.863131 -53.350096) (xy 9.785515 -53.373641) (xy 9.705964 -53.389464) (xy 9.625245 -53.397414)
			(xy 9.544135 -53.397414) (xy 9.463416 -53.389464) (xy 9.383865 -53.373641) (xy 9.306249 -53.350096)
			(xy 9.231313 -53.319057) (xy 9.159781 -53.280822) (xy 9.092341 -53.23576) (xy 9.029642 -53.184305)
			(xy 8.972289 -53.126952) (xy 8.920834 -53.064253) (xy 8.875772 -52.996813) (xy 8.837537 -52.925281)
			(xy 8.806498 -52.850345) (xy 8.782953 -52.772729) (xy 8.76713 -52.693178) (xy 8.75918 -52.612459)
			(xy 7.8702 -52.612459) (xy 7.86225 -52.693178) (xy 7.846427 -52.772729) (xy 7.822882 -52.850345)
			(xy 7.791843 -52.925281) (xy 7.753608 -52.996813) (xy 7.708546 -53.064253) (xy 7.657091 -53.126952)
			(xy 7.599738 -53.184305) (xy 7.537039 -53.23576) (xy 7.469599 -53.280822) (xy 7.398067 -53.319057)
			(xy 7.323131 -53.350096) (xy 7.245515 -53.373641) (xy 7.165964 -53.389464) (xy 7.085245 -53.397414)
			(xy 7.004135 -53.397414) (xy 6.923416 -53.389464) (xy 6.843865 -53.373641) (xy 6.766249 -53.350096)
			(xy 6.691313 -53.319057) (xy 6.619781 -53.280822) (xy 6.552341 -53.23576) (xy 6.489642 -53.184305)
			(xy 6.432289 -53.126952) (xy 6.380834 -53.064253) (xy 6.335772 -52.996813) (xy 6.297537 -52.925281)
			(xy 6.266498 -52.850345) (xy 6.242953 -52.772729) (xy 6.22713 -52.693178) (xy 6.21918 -52.612459)
			(xy 5.330444 -52.612459) (xy 5.330444 -53.397912) (xy 3.678936 -53.397912) (xy 3.678936 -51.745896)
			(xy 1.27 -51.745896) (xy 1.27 -55.152459) (xy 4.94918 -55.152459) (xy 4.94918 -55.071349) (xy 4.95713 -54.99063)
			(xy 4.972953 -54.911079) (xy 4.996498 -54.833463) (xy 5.027537 -54.758527) (xy 5.065772 -54.686995)
			(xy 5.110834 -54.619555) (xy 5.162289 -54.556856) (xy 5.219642 -54.499503) (xy 5.282341 -54.448048)
			(xy 5.349781 -54.402986) (xy 5.421313 -54.364751) (xy 5.496249 -54.333712) (xy 5.573865 -54.310167)
			(xy 5.653416 -54.294344) (xy 5.734135 -54.286394) (xy 5.815245 -54.286394) (xy 5.895964 -54.294344)
			(xy 5.975515 -54.310167) (xy 6.053131 -54.333712) (xy 6.128067 -54.364751) (xy 6.199599 -54.402986)
			(xy 6.267039 -54.448048) (xy 6.329738 -54.499503) (xy 6.387091 -54.556856) (xy 6.438546 -54.619555)
			(xy 6.483608 -54.686995) (xy 6.521843 -54.758527) (xy 6.552882 -54.833463) (xy 6.576427 -54.911079)
			(xy 6.59225 -54.99063) (xy 6.6002 -55.071349) (xy 6.600698 -55.111904) (xy 6.6002 -55.152459) (xy 7.48918 -55.152459)
			(xy 7.48918 -55.071349) (xy 7.49713 -54.99063) (xy 7.512953 -54.911079) (xy 7.536498 -54.833463)
			(xy 7.567537 -54.758527) (xy 7.605772 -54.686995) (xy 7.650834 -54.619555) (xy 7.702289 -54.556856)
			(xy 7.759642 -54.499503) (xy 7.822341 -54.448048) (xy 7.889781 -54.402986) (xy 7.961313 -54.364751)
			(xy 8.036249 -54.333712) (xy 8.113865 -54.310167) (xy 8.193416 -54.294344) (xy 8.274135 -54.286394)
			(xy 8.355245 -54.286394) (xy 8.435964 -54.294344) (xy 8.515515 -54.310167) (xy 8.593131 -54.333712)
			(xy 8.668067 -54.364751) (xy 8.739599 -54.402986) (xy 8.807039 -54.448048) (xy 8.869738 -54.499503)
			(xy 8.927091 -54.556856) (xy 8.978546 -54.619555) (xy 9.023608 -54.686995) (xy 9.061843 -54.758527)
			(xy 9.092882 -54.833463) (xy 9.116427 -54.911079) (xy 9.13225 -54.99063) (xy 9.1402 -55.071349) (xy 9.140698 -55.111904)
			(xy 9.1402 -55.152459) (xy 10.02918 -55.152459) (xy 10.02918 -55.071349) (xy 10.03713 -54.99063)
			(xy 10.052953 -54.911079) (xy 10.076498 -54.833463) (xy 10.107537 -54.758527) (xy 10.145772 -54.686995)
			(xy 10.190834 -54.619555) (xy 10.242289 -54.556856) (xy 10.299642 -54.499503) (xy 10.362341 -54.448048)
			(xy 10.429781 -54.402986) (xy 10.501313 -54.364751) (xy 10.576249 -54.333712) (xy 10.653865 -54.310167)
			(xy 10.733416 -54.294344) (xy 10.814135 -54.286394) (xy 10.895245 -54.286394) (xy 10.975964 -54.294344)
			(xy 11.055515 -54.310167) (xy 11.133131 -54.333712) (xy 11.208067 -54.364751) (xy 11.279599 -54.402986)
			(xy 11.347039 -54.448048) (xy 11.409738 -54.499503) (xy 11.467091 -54.556856) (xy 11.518546 -54.619555)
			(xy 11.563608 -54.686995) (xy 11.601843 -54.758527) (xy 11.632882 -54.833463) (xy 11.656427 -54.911079)
			(xy 11.67225 -54.99063) (xy 11.6802 -55.071349) (xy 11.680698 -55.111904) (xy 11.6802 -55.152459)
			(xy 12.56918 -55.152459) (xy 12.56918 -55.071349) (xy 12.57713 -54.99063) (xy 12.592953 -54.911079)
			(xy 12.616498 -54.833463) (xy 12.647537 -54.758527) (xy 12.685772 -54.686995) (xy 12.730834 -54.619555)
			(xy 12.782289 -54.556856) (xy 12.839642 -54.499503) (xy 12.902341 -54.448048) (xy 12.969781 -54.402986)
			(xy 13.041313 -54.364751) (xy 13.116249 -54.333712) (xy 13.193865 -54.310167) (xy 13.273416 -54.294344)
			(xy 13.354135 -54.286394) (xy 13.435245 -54.286394) (xy 13.515964 -54.294344) (xy 13.595515 -54.310167)
			(xy 13.673131 -54.333712) (xy 13.748067 -54.364751) (xy 13.819599 -54.402986) (xy 13.887039 -54.448048)
			(xy 13.949738 -54.499503) (xy 14.007091 -54.556856) (xy 14.058546 -54.619555) (xy 14.103608 -54.686995)
			(xy 14.141843 -54.758527) (xy 14.172882 -54.833463) (xy 14.196427 -54.911079) (xy 14.21225 -54.99063)
			(xy 14.2202 -55.071349) (xy 14.220698 -55.111904) (xy 14.2202 -55.152459) (xy 14.21225 -55.233178)
			(xy 14.196427 -55.312729) (xy 14.172882 -55.390345) (xy 14.141843 -55.465281) (xy 14.103608 -55.536813)
			(xy 14.058546 -55.604253) (xy 14.007091 -55.666952) (xy 13.949738 -55.724305) (xy 13.887039 -55.77576)
			(xy 13.819599 -55.820822) (xy 13.748067 -55.859057) (xy 13.673131 -55.890096) (xy 13.595515 -55.913641)
			(xy 13.515964 -55.929464) (xy 13.435245 -55.937414) (xy 13.354135 -55.937414) (xy 13.273416 -55.929464)
			(xy 13.193865 -55.913641) (xy 13.116249 -55.890096) (xy 13.041313 -55.859057) (xy 12.969781 -55.820822)
			(xy 12.902341 -55.77576) (xy 12.839642 -55.724305) (xy 12.782289 -55.666952) (xy 12.730834 -55.604253)
			(xy 12.685772 -55.536813) (xy 12.647537 -55.465281) (xy 12.616498 -55.390345) (xy 12.592953 -55.312729)
			(xy 12.57713 -55.233178) (xy 12.56918 -55.152459) (xy 11.6802 -55.152459) (xy 11.67225 -55.233178)
			(xy 11.656427 -55.312729) (xy 11.632882 -55.390345) (xy 11.601843 -55.465281) (xy 11.563608 -55.536813)
			(xy 11.518546 -55.604253) (xy 11.467091 -55.666952) (xy 11.409738 -55.724305) (xy 11.347039 -55.77576)
			(xy 11.279599 -55.820822) (xy 11.208067 -55.859057) (xy 11.133131 -55.890096) (xy 11.055515 -55.913641)
			(xy 10.975964 -55.929464) (xy 10.895245 -55.937414) (xy 10.814135 -55.937414) (xy 10.733416 -55.929464)
			(xy 10.653865 -55.913641) (xy 10.576249 -55.890096) (xy 10.501313 -55.859057) (xy 10.429781 -55.820822)
			(xy 10.362341 -55.77576) (xy 10.299642 -55.724305) (xy 10.242289 -55.666952) (xy 10.190834 -55.604253)
			(xy 10.145772 -55.536813) (xy 10.107537 -55.465281) (xy 10.076498 -55.390345) (xy 10.052953 -55.312729)
			(xy 10.03713 -55.233178) (xy 10.02918 -55.152459) (xy 9.1402 -55.152459) (xy 9.13225 -55.233178)
			(xy 9.116427 -55.312729) (xy 9.092882 -55.390345) (xy 9.061843 -55.465281) (xy 9.023608 -55.536813)
			(xy 8.978546 -55.604253) (xy 8.927091 -55.666952) (xy 8.869738 -55.724305) (xy 8.807039 -55.77576)
			(xy 8.739599 -55.820822) (xy 8.668067 -55.859057) (xy 8.593131 -55.890096) (xy 8.515515 -55.913641)
			(xy 8.435964 -55.929464) (xy 8.355245 -55.937414) (xy 8.274135 -55.937414) (xy 8.193416 -55.929464)
			(xy 8.113865 -55.913641) (xy 8.036249 -55.890096) (xy 7.961313 -55.859057) (xy 7.889781 -55.820822)
			(xy 7.822341 -55.77576) (xy 7.759642 -55.724305) (xy 7.702289 -55.666952) (xy 7.650834 -55.604253)
			(xy 7.605772 -55.536813) (xy 7.567537 -55.465281) (xy 7.536498 -55.390345) (xy 7.512953 -55.312729)
			(xy 7.49713 -55.233178) (xy 7.48918 -55.152459) (xy 6.6002 -55.152459) (xy 6.59225 -55.233178) (xy 6.576427 -55.312729)
			(xy 6.552882 -55.390345) (xy 6.521843 -55.465281) (xy 6.483608 -55.536813) (xy 6.438546 -55.604253)
			(xy 6.387091 -55.666952) (xy 6.329738 -55.724305) (xy 6.267039 -55.77576) (xy 6.199599 -55.820822)
			(xy 6.128067 -55.859057) (xy 6.053131 -55.890096) (xy 5.975515 -55.913641) (xy 5.895964 -55.929464)
			(xy 5.815245 -55.937414) (xy 5.734135 -55.937414) (xy 5.653416 -55.929464) (xy 5.573865 -55.913641)
			(xy 5.496249 -55.890096) (xy 5.421313 -55.859057) (xy 5.349781 -55.820822) (xy 5.282341 -55.77576)
			(xy 5.219642 -55.724305) (xy 5.162289 -55.666952) (xy 5.110834 -55.604253) (xy 5.065772 -55.536813)
			(xy 5.027537 -55.465281) (xy 4.996498 -55.390345) (xy 4.972953 -55.312729) (xy 4.95713 -55.233178)
			(xy 4.94918 -55.152459) (xy 1.27 -55.152459) (xy 1.27 -59.428549) (xy 3.67918 -59.428549) (xy 3.67918 -59.347439)
			(xy 3.68713 -59.26672) (xy 3.702953 -59.187169) (xy 3.726498 -59.109553) (xy 3.757537 -59.034617)
			(xy 3.795772 -58.963085) (xy 3.840834 -58.895645) (xy 3.892289 -58.832946) (xy 3.949642 -58.775593)
			(xy 4.012341 -58.724138) (xy 4.079781 -58.679076) (xy 4.151313 -58.640841) (xy 4.226249 -58.609802)
			(xy 4.303865 -58.586257) (xy 4.383416 -58.570434) (xy 4.464135 -58.562484) (xy 4.545245 -58.562484)
			(xy 4.625964 -58.570434) (xy 4.705515 -58.586257) (xy 4.783131 -58.609802) (xy 4.858067 -58.640841)
			(xy 4.929599 -58.679076) (xy 4.997039 -58.724138) (xy 5.059738 -58.775593) (xy 5.117091 -58.832946)
			(xy 5.168546 -58.895645) (xy 5.213608 -58.963085) (xy 5.251843 -59.034617) (xy 5.282882 -59.109553)
			(xy 5.306427 -59.187169) (xy 5.32225 -59.26672) (xy 5.3302 -59.347439) (xy 5.330698 -59.387994) (xy 5.3302 -59.428549)
			(xy 6.21918 -59.428549) (xy 6.21918 -59.347439) (xy 6.22713 -59.26672) (xy 6.242953 -59.187169) (xy 6.266498 -59.109553)
			(xy 6.297537 -59.034617) (xy 6.335772 -58.963085) (xy 6.380834 -58.895645) (xy 6.432289 -58.832946)
			(xy 6.489642 -58.775593) (xy 6.552341 -58.724138) (xy 6.619781 -58.679076) (xy 6.691313 -58.640841)
			(xy 6.766249 -58.609802) (xy 6.843865 -58.586257) (xy 6.923416 -58.570434) (xy 7.004135 -58.562484)
			(xy 7.085245 -58.562484) (xy 7.165964 -58.570434) (xy 7.245515 -58.586257) (xy 7.323131 -58.609802)
			(xy 7.398067 -58.640841) (xy 7.469599 -58.679076) (xy 7.537039 -58.724138) (xy 7.599738 -58.775593)
			(xy 7.657091 -58.832946) (xy 7.708546 -58.895645) (xy 7.753608 -58.963085) (xy 7.791843 -59.034617)
			(xy 7.822882 -59.109553) (xy 7.846427 -59.187169) (xy 7.86225 -59.26672) (xy 7.8702 -59.347439) (xy 7.870698 -59.387994)
			(xy 7.8702 -59.428549) (xy 8.75918 -59.428549) (xy 8.75918 -59.347439) (xy 8.76713 -59.26672) (xy 8.782953 -59.187169)
			(xy 8.806498 -59.109553) (xy 8.837537 -59.034617) (xy 8.875772 -58.963085) (xy 8.920834 -58.895645)
			(xy 8.972289 -58.832946) (xy 9.029642 -58.775593) (xy 9.092341 -58.724138) (xy 9.159781 -58.679076)
			(xy 9.231313 -58.640841) (xy 9.306249 -58.609802) (xy 9.383865 -58.586257) (xy 9.463416 -58.570434)
			(xy 9.544135 -58.562484) (xy 9.625245 -58.562484) (xy 9.705964 -58.570434) (xy 9.785515 -58.586257)
			(xy 9.863131 -58.609802) (xy 9.938067 -58.640841) (xy 10.009599 -58.679076) (xy 10.077039 -58.724138)
			(xy 10.139738 -58.775593) (xy 10.197091 -58.832946) (xy 10.248546 -58.895645) (xy 10.293608 -58.963085)
			(xy 10.331843 -59.034617) (xy 10.362882 -59.109553) (xy 10.386427 -59.187169) (xy 10.40225 -59.26672)
			(xy 10.4102 -59.347439) (xy 10.410698 -59.387994) (xy 10.4102 -59.428549) (xy 11.29918 -59.428549)
			(xy 11.29918 -59.347439) (xy 11.30713 -59.26672) (xy 11.322953 -59.187169) (xy 11.346498 -59.109553)
			(xy 11.377537 -59.034617) (xy 11.415772 -58.963085) (xy 11.460834 -58.895645) (xy 11.512289 -58.832946)
			(xy 11.569642 -58.775593) (xy 11.632341 -58.724138) (xy 11.699781 -58.679076) (xy 11.771313 -58.640841)
			(xy 11.846249 -58.609802) (xy 11.923865 -58.586257) (xy 12.003416 -58.570434) (xy 12.084135 -58.562484)
			(xy 12.165245 -58.562484) (xy 12.245964 -58.570434) (xy 12.325515 -58.586257) (xy 12.403131 -58.609802)
			(xy 12.478067 -58.640841) (xy 12.549599 -58.679076) (xy 12.617039 -58.724138) (xy 12.679738 -58.775593)
			(xy 12.737091 -58.832946) (xy 12.788546 -58.895645) (xy 12.833608 -58.963085) (xy 12.871843 -59.034617)
			(xy 12.902882 -59.109553) (xy 12.926427 -59.187169) (xy 12.94225 -59.26672) (xy 12.9502 -59.347439)
			(xy 12.950698 -59.387994) (xy 12.9502 -59.428549) (xy 12.94225 -59.509268) (xy 12.926427 -59.588819)
			(xy 12.902882 -59.666435) (xy 12.871843 -59.741371) (xy 12.833608 -59.812903) (xy 12.788546 -59.880343)
			(xy 12.737091 -59.943042) (xy 12.679738 -60.000395) (xy 12.617039 -60.05185) (xy 12.549599 -60.096912)
			(xy 12.478067 -60.135147) (xy 12.403131 -60.166186) (xy 12.325515 -60.189731) (xy 12.245964 -60.205554)
			(xy 12.165245 -60.213504) (xy 12.084135 -60.213504) (xy 12.003416 -60.205554) (xy 11.923865 -60.189731)
			(xy 11.846249 -60.166186) (xy 11.771313 -60.135147) (xy 11.699781 -60.096912) (xy 11.632341 -60.05185)
			(xy 11.569642 -60.000395) (xy 11.512289 -59.943042) (xy 11.460834 -59.880343) (xy 11.415772 -59.812903)
			(xy 11.377537 -59.741371) (xy 11.346498 -59.666435) (xy 11.322953 -59.588819) (xy 11.30713 -59.509268)
			(xy 11.29918 -59.428549) (xy 10.4102 -59.428549) (xy 10.40225 -59.509268) (xy 10.386427 -59.588819)
			(xy 10.362882 -59.666435) (xy 10.331843 -59.741371) (xy 10.293608 -59.812903) (xy 10.248546 -59.880343)
			(xy 10.197091 -59.943042) (xy 10.139738 -60.000395) (xy 10.077039 -60.05185) (xy 10.009599 -60.096912)
			(xy 9.938067 -60.135147) (xy 9.863131 -60.166186) (xy 9.785515 -60.189731) (xy 9.705964 -60.205554)
			(xy 9.625245 -60.213504) (xy 9.544135 -60.213504) (xy 9.463416 -60.205554) (xy 9.383865 -60.189731)
			(xy 9.306249 -60.166186) (xy 9.231313 -60.135147) (xy 9.159781 -60.096912) (xy 9.092341 -60.05185)
			(xy 9.029642 -60.000395) (xy 8.972289 -59.943042) (xy 8.920834 -59.880343) (xy 8.875772 -59.812903)
			(xy 8.837537 -59.741371) (xy 8.806498 -59.666435) (xy 8.782953 -59.588819) (xy 8.76713 -59.509268)
			(xy 8.75918 -59.428549) (xy 7.8702 -59.428549) (xy 7.86225 -59.509268) (xy 7.846427 -59.588819) (xy 7.822882 -59.666435)
			(xy 7.791843 -59.741371) (xy 7.753608 -59.812903) (xy 7.708546 -59.880343) (xy 7.657091 -59.943042)
			(xy 7.599738 -60.000395) (xy 7.537039 -60.05185) (xy 7.469599 -60.096912) (xy 7.398067 -60.135147)
			(xy 7.323131 -60.166186) (xy 7.245515 -60.189731) (xy 7.165964 -60.205554) (xy 7.085245 -60.213504)
			(xy 7.004135 -60.213504) (xy 6.923416 -60.205554) (xy 6.843865 -60.189731) (xy 6.766249 -60.166186)
			(xy 6.691313 -60.135147) (xy 6.619781 -60.096912) (xy 6.552341 -60.05185) (xy 6.489642 -60.000395)
			(xy 6.432289 -59.943042) (xy 6.380834 -59.880343) (xy 6.335772 -59.812903) (xy 6.297537 -59.741371)
			(xy 6.266498 -59.666435) (xy 6.242953 -59.588819) (xy 6.22713 -59.509268) (xy 6.21918 -59.428549)
			(xy 5.3302 -59.428549) (xy 5.32225 -59.509268) (xy 5.306427 -59.588819) (xy 5.282882 -59.666435)
			(xy 5.251843 -59.741371) (xy 5.213608 -59.812903) (xy 5.168546 -59.880343) (xy 5.117091 -59.943042)
			(xy 5.059738 -60.000395) (xy 4.997039 -60.05185) (xy 4.929599 -60.096912) (xy 4.858067 -60.135147)
			(xy 4.783131 -60.166186) (xy 4.705515 -60.189731) (xy 4.625964 -60.205554) (xy 4.545245 -60.213504)
			(xy 4.464135 -60.213504) (xy 4.383416 -60.205554) (xy 4.303865 -60.189731) (xy 4.226249 -60.166186)
			(xy 4.151313 -60.135147) (xy 4.079781 -60.096912) (xy 4.012341 -60.05185) (xy 3.949642 -60.000395)
			(xy 3.892289 -59.943042) (xy 3.840834 -59.880343) (xy 3.795772 -59.812903) (xy 3.757537 -59.741371)
			(xy 3.726498 -59.666435) (xy 3.702953 -59.588819) (xy 3.68713 -59.509268) (xy 3.67918 -59.428549)
			(xy 1.27 -59.428549) (xy 1.27 -61.10224) (xy 12.568936 -61.10224) (xy 14.220444 -61.10224) (xy 14.220444 -62.753748)
			(xy 12.568936 -62.753748) (xy 12.568936 -61.10224) (xy 1.27 -61.10224) (xy 1.27 -61.968549) (xy 4.94918 -61.968549)
			(xy 4.94918 -61.887439) (xy 4.95713 -61.80672) (xy 4.972953 -61.727169) (xy 4.996498 -61.649553)
			(xy 5.027537 -61.574617) (xy 5.065772 -61.503085) (xy 5.110834 -61.435645) (xy 5.162289 -61.372946)
			(xy 5.219642 -61.315593) (xy 5.282341 -61.264138) (xy 5.349781 -61.219076) (xy 5.421313 -61.180841)
			(xy 5.496249 -61.149802) (xy 5.573865 -61.126257) (xy 5.653416 -61.110434) (xy 5.734135 -61.102484)
			(xy 5.815245 -61.102484) (xy 5.895964 -61.110434) (xy 5.975515 -61.126257) (xy 6.053131 -61.149802)
			(xy 6.128067 -61.180841) (xy 6.199599 -61.219076) (xy 6.267039 -61.264138) (xy 6.329738 -61.315593)
			(xy 6.387091 -61.372946) (xy 6.438546 -61.435645) (xy 6.483608 -61.503085) (xy 6.521843 -61.574617)
			(xy 6.552882 -61.649553) (xy 6.576427 -61.727169) (xy 6.59225 -61.80672) (xy 6.6002 -61.887439) (xy 6.600698 -61.927994)
			(xy 6.6002 -61.968549) (xy 7.48918 -61.968549) (xy 7.48918 -61.887439) (xy 7.49713 -61.80672) (xy 7.512953 -61.727169)
			(xy 7.536498 -61.649553) (xy 7.567537 -61.574617) (xy 7.605772 -61.503085) (xy 7.650834 -61.435645)
			(xy 7.702289 -61.372946) (xy 7.759642 -61.315593) (xy 7.822341 -61.264138) (xy 7.889781 -61.219076)
			(xy 7.961313 -61.180841) (xy 8.036249 -61.149802) (xy 8.113865 -61.126257) (xy 8.193416 -61.110434)
			(xy 8.274135 -61.102484) (xy 8.355245 -61.102484) (xy 8.435964 -61.110434) (xy 8.515515 -61.126257)
			(xy 8.593131 -61.149802) (xy 8.668067 -61.180841) (xy 8.739599 -61.219076) (xy 8.807039 -61.264138)
			(xy 8.869738 -61.315593) (xy 8.927091 -61.372946) (xy 8.978546 -61.435645) (xy 9.023608 -61.503085)
			(xy 9.061843 -61.574617) (xy 9.092882 -61.649553) (xy 9.116427 -61.727169) (xy 9.13225 -61.80672)
			(xy 9.1402 -61.887439) (xy 9.140698 -61.927994) (xy 9.1402 -61.968549) (xy 10.02918 -61.968549) (xy 10.02918 -61.887439)
			(xy 10.03713 -61.80672) (xy 10.052953 -61.727169) (xy 10.076498 -61.649553) (xy 10.107537 -61.574617)
			(xy 10.145772 -61.503085) (xy 10.190834 -61.435645) (xy 10.242289 -61.372946) (xy 10.299642 -61.315593)
			(xy 10.362341 -61.264138) (xy 10.429781 -61.219076) (xy 10.501313 -61.180841) (xy 10.576249 -61.149802)
			(xy 10.653865 -61.126257) (xy 10.733416 -61.110434) (xy 10.814135 -61.102484) (xy 10.895245 -61.102484)
			(xy 10.975964 -61.110434) (xy 11.055515 -61.126257) (xy 11.133131 -61.149802) (xy 11.208067 -61.180841)
			(xy 11.279599 -61.219076) (xy 11.347039 -61.264138) (xy 11.409738 -61.315593) (xy 11.467091 -61.372946)
			(xy 11.518546 -61.435645) (xy 11.563608 -61.503085) (xy 11.601843 -61.574617) (xy 11.632882 -61.649553)
			(xy 11.656427 -61.727169) (xy 11.67225 -61.80672) (xy 11.6802 -61.887439) (xy 11.680698 -61.927994)
			(xy 11.6802 -61.968549) (xy 11.67225 -62.049268) (xy 11.656427 -62.128819) (xy 11.632882 -62.206435)
			(xy 11.601843 -62.281371) (xy 11.563608 -62.352903) (xy 11.518546 -62.420343) (xy 11.467091 -62.483042)
			(xy 11.409738 -62.540395) (xy 11.347039 -62.59185) (xy 11.279599 -62.636912) (xy 11.208067 -62.675147)
			(xy 11.133131 -62.706186) (xy 11.055515 -62.729731) (xy 10.975964 -62.745554) (xy 10.895245 -62.753504)
			(xy 10.814135 -62.753504) (xy 10.733416 -62.745554) (xy 10.653865 -62.729731) (xy 10.576249 -62.706186)
			(xy 10.501313 -62.675147) (xy 10.429781 -62.636912) (xy 10.362341 -62.59185) (xy 10.299642 -62.540395)
			(xy 10.242289 -62.483042) (xy 10.190834 -62.420343) (xy 10.145772 -62.352903) (xy 10.107537 -62.281371)
			(xy 10.076498 -62.206435) (xy 10.052953 -62.128819) (xy 10.03713 -62.049268) (xy 10.02918 -61.968549)
			(xy 9.1402 -61.968549) (xy 9.13225 -62.049268) (xy 9.116427 -62.128819) (xy 9.092882 -62.206435)
			(xy 9.061843 -62.281371) (xy 9.023608 -62.352903) (xy 8.978546 -62.420343) (xy 8.927091 -62.483042)
			(xy 8.869738 -62.540395) (xy 8.807039 -62.59185) (xy 8.739599 -62.636912) (xy 8.668067 -62.675147)
			(xy 8.593131 -62.706186) (xy 8.515515 -62.729731) (xy 8.435964 -62.745554) (xy 8.355245 -62.753504)
			(xy 8.274135 -62.753504) (xy 8.193416 -62.745554) (xy 8.113865 -62.729731) (xy 8.036249 -62.706186)
			(xy 7.961313 -62.675147) (xy 7.889781 -62.636912) (xy 7.822341 -62.59185) (xy 7.759642 -62.540395)
			(xy 7.702289 -62.483042) (xy 7.650834 -62.420343) (xy 7.605772 -62.352903) (xy 7.567537 -62.281371)
			(xy 7.536498 -62.206435) (xy 7.512953 -62.128819) (xy 7.49713 -62.049268) (xy 7.48918 -61.968549)
			(xy 6.6002 -61.968549) (xy 6.59225 -62.049268) (xy 6.576427 -62.128819) (xy 6.552882 -62.206435)
			(xy 6.521843 -62.281371) (xy 6.483608 -62.352903) (xy 6.438546 -62.420343) (xy 6.387091 -62.483042)
			(xy 6.329738 -62.540395) (xy 6.267039 -62.59185) (xy 6.199599 -62.636912) (xy 6.128067 -62.675147)
			(xy 6.053131 -62.706186) (xy 5.975515 -62.729731) (xy 5.895964 -62.745554) (xy 5.815245 -62.753504)
			(xy 5.734135 -62.753504) (xy 5.653416 -62.745554) (xy 5.573865 -62.729731) (xy 5.496249 -62.706186)
			(xy 5.421313 -62.675147) (xy 5.349781 -62.636912) (xy 5.282341 -62.59185) (xy 5.219642 -62.540395)
			(xy 5.162289 -62.483042) (xy 5.110834 -62.420343) (xy 5.065772 -62.352903) (xy 5.027537 -62.281371)
			(xy 4.996498 -62.206435) (xy 4.972953 -62.128819) (xy 4.95713 -62.049268) (xy 4.94918 -61.968549)
			(xy 1.27 -61.968549) (xy 1.27 -66.685414) (xy 1.270551 -66.708776) (xy 1.279134 -66.754707) (xy 1.29597 -66.798294)
			(xy 1.320492 -66.838069) (xy 1.351871 -66.87269) (xy 1.389052 -66.90099) (xy 1.430779 -66.922016)
			(xy 1.475648 -66.935058) (xy 1.522145 -66.939678) (xy 1.568703 -66.935718) (xy 1.613752 -66.923314)
			(xy 1.655774 -66.902882) (xy 1.693352 -66.875112) (xy 1.709674 -66.858388) (xy 1.754144 -66.811352)
			(xy 1.848064 -66.722255) (xy 1.947334 -66.639162) (xy 2.051571 -66.562393) (xy 2.160374 -66.492244)
			(xy 2.273323 -66.428986) (xy 2.389982 -66.372863) (xy 2.5099 -66.324092) (xy 2.632615 -66.28286)
			(xy 2.757653 -66.249327) (xy 2.884532 -66.223622) (xy 3.012762 -66.205845) (xy 3.141848 -66.196063)
			(xy 3.271293 -66.194316) (xy 3.400597 -66.200609) (xy 3.52926 -66.214918) (xy 3.656786 -66.237188)
			(xy 3.782684 -66.267333) (xy 3.906468 -66.305237) (xy 4.027658 -66.350753) (xy 4.14579 -66.403707)
			(xy 4.260405 -66.463892) (xy 4.371062 -66.531079) (xy 4.477334 -66.605006) (xy 4.578812 -66.685388)
			(xy 4.675102 -66.771917) (xy 4.765834 -66.864257) (xy 4.850658 -66.962052) (xy 4.929246 -67.064925)
			(xy 5.001295 -67.17248) (xy 5.066527 -67.2843) (xy 5.124691 -67.399955) (xy 5.175561 -67.518998)
			(xy 5.218942 -67.640969) (xy 5.254666 -67.765399) (xy 5.282595 -67.891807) (xy 5.302622 -68.019705)
			(xy 5.314669 -68.1486) (xy 5.31869 -68.277994) (xy 12.580624 -68.277994) (xy 12.584655 -68.148428)
			(xy 12.596734 -68.019364) (xy 12.616813 -67.8913) (xy 12.644815 -67.764733) (xy 12.680632 -67.64015)
			(xy 12.724124 -67.518036) (xy 12.775124 -67.398862) (xy 12.833435 -67.283089) (xy 12.89883 -67.171165)
			(xy 12.971057 -67.063523) (xy 13.049837 -66.96058) (xy 13.134864 -66.862734) (xy 13.225809 -66.770362)
			(xy 13.322321 -66.683824) (xy 13.424027 -66.603453) (xy 13.530533 -66.529561) (xy 13.641426 -66.462433)
			(xy 13.756278 -66.402329) (xy 13.874645 -66.349482) (xy 13.996068 -66.304095) (xy 14.120078 -66.266346)
			(xy 14.246195 -66.236379) (xy 14.373931 -66.21431) (xy 14.502792 -66.200226) (xy 14.632279 -66.19418)
			(xy 14.761892 -66.196196) (xy 14.891128 -66.206266) (xy 15.019489 -66.224351) (xy 15.146477 -66.250381)
			(xy 15.271601 -66.284256) (xy 15.394377 -66.325844) (xy 15.51433 -66.374985) (xy 15.630995 -66.431488)
			(xy 15.743923 -66.495135) (xy 15.852675 -66.565679) (xy 15.956831 -66.642848) (xy 16.055988 -66.726343)
			(xy 16.149762 -66.815841) (xy 16.237791 -66.910996) (xy 16.319734 -67.011439) (xy 16.395273 -67.116782)
			(xy 16.464118 -67.226618) (xy 16.526001 -67.340522) (xy 16.580682 -67.458052) (xy 16.627952 -67.578755)
			(xy 16.667625 -67.702163) (xy 16.69955 -67.827799) (xy 16.723602 -67.955176) (xy 16.739689 -68.083802)
			(xy 16.747748 -68.21318) (xy 16.748252 -68.277994) (xy 16.747748 -68.342808) (xy 16.739689 -68.472186)
			(xy 16.723602 -68.600812) (xy 16.69955 -68.728189) (xy 16.667625 -68.853825) (xy 16.627952 -68.977233)
			(xy 16.580682 -69.097936) (xy 16.526001 -69.215466) (xy 16.464118 -69.32937) (xy 16.395273 -69.439206)
			(xy 16.319734 -69.544549) (xy 16.237791 -69.644992) (xy 16.149762 -69.740147) (xy 16.055988 -69.829645)
			(xy 15.956831 -69.91314) (xy 15.852675 -69.990309) (xy 15.743923 -70.060853) (xy 15.630995 -70.1245)
			(xy 15.51433 -70.181003) (xy 15.394377 -70.230144) (xy 15.271601 -70.271732) (xy 15.146477 -70.305607)
			(xy 15.019489 -70.331637) (xy 14.891128 -70.349722) (xy 14.761892 -70.359792) (xy 14.632279 -70.361808)
			(xy 14.502792 -70.355762) (xy 14.373931 -70.341678) (xy 14.246195 -70.319609) (xy 14.120078 -70.289642)
			(xy 13.996068 -70.251893) (xy 13.874645 -70.206506) (xy 13.756278 -70.153659) (xy 13.641426 -70.093555)
			(xy 13.530533 -70.026427) (xy 13.424027 -69.952535) (xy 13.322321 -69.872164) (xy 13.225809 -69.785626)
			(xy 13.134864 -69.693254) (xy 13.049837 -69.595408) (xy 12.971057 -69.492465) (xy 12.89883 -69.384823)
			(xy 12.833435 -69.272899) (xy 12.775124 -69.157126) (xy 12.724124 -69.037952) (xy 12.680632 -68.915838)
			(xy 12.644815 -68.791255) (xy 12.616813 -68.664688) (xy 12.596734 -68.536624) (xy 12.584655 -68.40756)
			(xy 12.580624 -68.277994) (xy 5.31869 -68.277994) (xy 5.314669 -68.407388) (xy 5.302622 -68.536283)
			(xy 5.282595 -68.664181) (xy 5.254666 -68.790589) (xy 5.218942 -68.915019) (xy 5.175561 -69.03699)
			(xy 5.124691 -69.156033) (xy 5.066527 -69.271688) (xy 5.001295 -69.383508) (xy 4.929246 -69.491063)
			(xy 4.850658 -69.593936) (xy 4.765834 -69.691731) (xy 4.675102 -69.784071) (xy 4.578812 -69.8706)
			(xy 4.477334 -69.950982) (xy 4.371062 -70.024909) (xy 4.260405 -70.092096) (xy 4.14579 -70.152281)
			(xy 4.027658 -70.205235) (xy 3.906468 -70.250751) (xy 3.782684 -70.288655) (xy 3.656786 -70.3188)
			(xy 3.52926 -70.34107) (xy 3.400597 -70.355379) (xy 3.271293 -70.361672) (xy 3.141848 -70.359925)
			(xy 3.012762 -70.350143) (xy 2.884532 -70.332366) (xy 2.757653 -70.306661) (xy 2.632615 -70.273128)
			(xy 2.5099 -70.231896) (xy 2.389982 -70.183125) (xy 2.273323 -70.127002) (xy 2.160374 -70.063744)
			(xy 2.051571 -69.993595) (xy 1.947334 -69.916826) (xy 1.848064 -69.833733) (xy 1.754144 -69.744636)
			(xy 1.709674 -69.6976) (xy 1.693349 -69.680884) (xy 1.655769 -69.653131) (xy 1.613749 -69.632714)
			(xy 1.568705 -69.62032) (xy 1.522155 -69.616368) (xy 1.475666 -69.620991) (xy 1.430806 -69.634033)
			(xy 1.389085 -69.655054) (xy 1.351908 -69.683347) (xy 1.320529 -69.717957) (xy 1.296005 -69.75772)
			(xy 1.279161 -69.801296) (xy 1.270565 -69.847216) (xy 1.27 -69.870574) (xy 1.27 -97.679256) (xy 1.270551 -97.702619)
			(xy 1.279133 -97.748551) (xy 1.295968 -97.792139) (xy 1.320489 -97.831915) (xy 1.351869 -97.866538)
			(xy 1.38905 -97.894839) (xy 1.430778 -97.915865) (xy 1.475648 -97.928908) (xy 1.522146 -97.933528)
			(xy 1.568705 -97.929568) (xy 1.613755 -97.917163) (xy 1.655777 -97.89673) (xy 1.693356 -97.868958)
			(xy 1.709674 -97.85223) (xy 1.754144 -97.805194) (xy 1.848064 -97.716097) (xy 1.947334 -97.633004)
			(xy 2.051571 -97.556235) (xy 2.160374 -97.486086) (xy 2.273323 -97.422828) (xy 2.389982 -97.366705)
			(xy 2.5099 -97.317934) (xy 2.632615 -97.276702) (xy 2.757653 -97.243169) (xy 2.884532 -97.217464)
			(xy 3.012762 -97.199687) (xy 3.141848 -97.189905) (xy 3.271293 -97.188158) (xy 3.400597 -97.194451)
			(xy 3.52926 -97.20876) (xy 3.656786 -97.23103) (xy 3.782684 -97.261175) (xy 3.906468 -97.299079)
			(xy 4.027658 -97.344595) (xy 4.14579 -97.397549) (xy 4.260405 -97.457734) (xy 4.371062 -97.524921)
			(xy 4.477334 -97.598848) (xy 4.578812 -97.67923) (xy 4.675102 -97.765759) (xy 4.765834 -97.858099)
			(xy 4.850658 -97.955894) (xy 4.929246 -98.058767) (xy 5.001295 -98.166322) (xy 5.066527 -98.278142)
			(xy 5.124691 -98.393797) (xy 5.175561 -98.51284) (xy 5.218942 -98.634811) (xy 5.254666 -98.759241)
			(xy 5.282595 -98.885649) (xy 5.302622 -99.013547) (xy 5.314669 -99.142442) (xy 5.31869 -99.271836)
			(xy 12.580624 -99.271836) (xy 12.584655 -99.14227) (xy 12.596734 -99.013206) (xy 12.616813 -98.885142)
			(xy 12.644815 -98.758575) (xy 12.680632 -98.633992) (xy 12.724124 -98.511878) (xy 12.775124 -98.392704)
			(xy 12.833435 -98.276931) (xy 12.89883 -98.165007) (xy 12.971057 -98.057365) (xy 13.049837 -97.954422)
			(xy 13.134864 -97.856576) (xy 13.225809 -97.764204) (xy 13.322321 -97.677666) (xy 13.424027 -97.597295)
			(xy 13.530533 -97.523403) (xy 13.641426 -97.456275) (xy 13.756278 -97.396171) (xy 13.874645 -97.343324)
			(xy 13.996068 -97.297937) (xy 14.120078 -97.260188) (xy 14.246195 -97.230221) (xy 14.373931 -97.208152)
			(xy 14.502792 -97.194068) (xy 14.632279 -97.188022) (xy 14.761892 -97.190038) (xy 14.891128 -97.200108)
			(xy 15.019489 -97.218193) (xy 15.146477 -97.244223) (xy 15.271601 -97.278098) (xy 15.394377 -97.319686)
			(xy 15.51433 -97.368827) (xy 15.630995 -97.42533) (xy 15.743923 -97.488977) (xy 15.852675 -97.559521)
			(xy 15.956831 -97.63669) (xy 16.055988 -97.720185) (xy 16.149762 -97.809683) (xy 16.237791 -97.904838)
			(xy 16.319734 -98.005281) (xy 16.395273 -98.110624) (xy 16.464118 -98.22046) (xy 16.526001 -98.334364)
			(xy 16.580682 -98.451894) (xy 16.627952 -98.572597) (xy 16.667625 -98.696005) (xy 16.69955 -98.821641)
			(xy 16.723602 -98.949018) (xy 16.739689 -99.077644) (xy 16.747748 -99.207022) (xy 16.748252 -99.271836)
			(xy 16.747748 -99.33665) (xy 16.739689 -99.466028) (xy 16.723602 -99.594654) (xy 16.69955 -99.722031)
			(xy 16.667625 -99.847667) (xy 16.627952 -99.971075) (xy 16.580682 -100.091778) (xy 16.526001 -100.209308)
			(xy 16.464118 -100.323212) (xy 16.395273 -100.433048) (xy 16.319734 -100.538391) (xy 16.237791 -100.638834)
			(xy 16.149762 -100.733989) (xy 16.055988 -100.823487) (xy 15.956831 -100.906982) (xy 15.852675 -100.984151)
			(xy 15.743923 -101.054695) (xy 15.630995 -101.118342) (xy 15.51433 -101.174845) (xy 15.394377 -101.223986)
			(xy 15.271601 -101.265574) (xy 15.146477 -101.299449) (xy 15.019489 -101.325479) (xy 14.891128 -101.343564)
			(xy 14.761892 -101.353634) (xy 14.632279 -101.35565) (xy 14.502792 -101.349604) (xy 14.373931 -101.33552)
			(xy 14.246195 -101.313451) (xy 14.120078 -101.283484) (xy 13.996068 -101.245735) (xy 13.874645 -101.200348)
			(xy 13.756278 -101.147501) (xy 13.641426 -101.087397) (xy 13.530533 -101.020269) (xy 13.424027 -100.946377)
			(xy 13.322321 -100.866006) (xy 13.225809 -100.779468) (xy 13.134864 -100.687096) (xy 13.049837 -100.58925)
			(xy 12.971057 -100.486307) (xy 12.89883 -100.378665) (xy 12.833435 -100.266741) (xy 12.775124 -100.150968)
			(xy 12.724124 -100.031794) (xy 12.680632 -99.90968) (xy 12.644815 -99.785097) (xy 12.616813 -99.65853)
			(xy 12.596734 -99.530466) (xy 12.584655 -99.401402) (xy 12.580624 -99.271836) (xy 5.31869 -99.271836)
			(xy 5.314669 -99.40123) (xy 5.302622 -99.530125) (xy 5.282595 -99.658023) (xy 5.254666 -99.784431)
			(xy 5.218942 -99.908861) (xy 5.175561 -100.030832) (xy 5.124691 -100.149875) (xy 5.066527 -100.26553)
			(xy 5.001295 -100.37735) (xy 4.929246 -100.484905) (xy 4.850658 -100.587778) (xy 4.765834 -100.685573)
			(xy 4.675102 -100.777913) (xy 4.578812 -100.864442) (xy 4.477334 -100.944824) (xy 4.371062 -101.018751)
			(xy 4.260405 -101.085938) (xy 4.14579 -101.146123) (xy 4.027658 -101.199077) (xy 3.906468 -101.244593)
			(xy 3.782684 -101.282497) (xy 3.656786 -101.312642) (xy 3.52926 -101.334912) (xy 3.400597 -101.349221)
			(xy 3.271293 -101.355514) (xy 3.141848 -101.353767) (xy 3.012762 -101.343985) (xy 2.884532 -101.326208)
			(xy 2.757653 -101.300503) (xy 2.632615 -101.26697) (xy 2.5099 -101.225738) (xy 2.389982 -101.176967)
			(xy 2.273323 -101.120844) (xy 2.160374 -101.057586) (xy 2.051571 -100.987437) (xy 1.947334 -100.910668)
			(xy 1.848064 -100.827575) (xy 1.754144 -100.738478) (xy 1.709674 -100.691442) (xy 1.693349 -100.674726)
			(xy 1.655769 -100.646973) (xy 1.613749 -100.626555) (xy 1.568705 -100.614162) (xy 1.522155 -100.61021)
			(xy 1.475666 -100.614833) (xy 1.430806 -100.627874) (xy 1.389085 -100.648896) (xy 1.351909 -100.677188)
			(xy 1.32053 -100.711799) (xy 1.296006 -100.751562) (xy 1.279162 -100.795138) (xy 1.270566 -100.841058)
			(xy 1.27 -100.864416) (xy 1.27 -104.795828) (xy 3.678936 -104.795828) (xy 5.330444 -104.795828) (xy 5.330444 -105.662391)
			(xy 6.21918 -105.662391) (xy 6.21918 -105.581281) (xy 6.22713 -105.500562) (xy 6.242953 -105.421011)
			(xy 6.266498 -105.343395) (xy 6.297537 -105.268459) (xy 6.335772 -105.196927) (xy 6.380834 -105.129487)
			(xy 6.432289 -105.066788) (xy 6.489642 -105.009435) (xy 6.552341 -104.95798) (xy 6.619781 -104.912918)
			(xy 6.691313 -104.874683) (xy 6.766249 -104.843644) (xy 6.843865 -104.820099) (xy 6.923416 -104.804276)
			(xy 7.004135 -104.796326) (xy 7.085245 -104.796326) (xy 7.165964 -104.804276) (xy 7.245515 -104.820099)
			(xy 7.323131 -104.843644) (xy 7.398067 -104.874683) (xy 7.469599 -104.912918) (xy 7.537039 -104.95798)
			(xy 7.599738 -105.009435) (xy 7.657091 -105.066788) (xy 7.708546 -105.129487) (xy 7.753608 -105.196927)
			(xy 7.791843 -105.268459) (xy 7.822882 -105.343395) (xy 7.846427 -105.421011) (xy 7.86225 -105.500562)
			(xy 7.8702 -105.581281) (xy 7.870698 -105.621836) (xy 7.8702 -105.662391) (xy 8.75918 -105.662391)
			(xy 8.75918 -105.581281) (xy 8.76713 -105.500562) (xy 8.782953 -105.421011) (xy 8.806498 -105.343395)
			(xy 8.837537 -105.268459) (xy 8.875772 -105.196927) (xy 8.920834 -105.129487) (xy 8.972289 -105.066788)
			(xy 9.029642 -105.009435) (xy 9.092341 -104.95798) (xy 9.159781 -104.912918) (xy 9.231313 -104.874683)
			(xy 9.306249 -104.843644) (xy 9.383865 -104.820099) (xy 9.463416 -104.804276) (xy 9.544135 -104.796326)
			(xy 9.625245 -104.796326) (xy 9.705964 -104.804276) (xy 9.785515 -104.820099) (xy 9.863131 -104.843644)
			(xy 9.938067 -104.874683) (xy 10.009599 -104.912918) (xy 10.077039 -104.95798) (xy 10.139738 -105.009435)
			(xy 10.197091 -105.066788) (xy 10.248546 -105.129487) (xy 10.293608 -105.196927) (xy 10.331843 -105.268459)
			(xy 10.362882 -105.343395) (xy 10.386427 -105.421011) (xy 10.40225 -105.500562) (xy 10.4102 -105.581281)
			(xy 10.410698 -105.621836) (xy 10.4102 -105.662391) (xy 11.29918 -105.662391) (xy 11.29918 -105.581281)
			(xy 11.30713 -105.500562) (xy 11.322953 -105.421011) (xy 11.346498 -105.343395) (xy 11.377537 -105.268459)
			(xy 11.415772 -105.196927) (xy 11.460834 -105.129487) (xy 11.512289 -105.066788) (xy 11.569642 -105.009435)
			(xy 11.632341 -104.95798) (xy 11.699781 -104.912918) (xy 11.771313 -104.874683) (xy 11.846249 -104.843644)
			(xy 11.923865 -104.820099) (xy 12.003416 -104.804276) (xy 12.084135 -104.796326) (xy 12.165245 -104.796326)
			(xy 12.245964 -104.804276) (xy 12.325515 -104.820099) (xy 12.403131 -104.843644) (xy 12.478067 -104.874683)
			(xy 12.549599 -104.912918) (xy 12.617039 -104.95798) (xy 12.679738 -105.009435) (xy 12.737091 -105.066788)
			(xy 12.788546 -105.129487) (xy 12.833608 -105.196927) (xy 12.871843 -105.268459) (xy 12.902882 -105.343395)
			(xy 12.926427 -105.421011) (xy 12.94225 -105.500562) (xy 12.9502 -105.581281) (xy 12.950698 -105.621836)
			(xy 12.9502 -105.662391) (xy 12.94225 -105.74311) (xy 12.926427 -105.822661) (xy 12.902882 -105.900277)
			(xy 12.871843 -105.975213) (xy 12.833608 -106.046745) (xy 12.788546 -106.114185) (xy 12.737091 -106.176884)
			(xy 12.679738 -106.234237) (xy 12.617039 -106.285692) (xy 12.549599 -106.330754) (xy 12.478067 -106.368989)
			(xy 12.403131 -106.400028) (xy 12.325515 -106.423573) (xy 12.245964 -106.439396) (xy 12.165245 -106.447346)
			(xy 12.084135 -106.447346) (xy 12.003416 -106.439396) (xy 11.923865 -106.423573) (xy 11.846249 -106.400028)
			(xy 11.771313 -106.368989) (xy 11.699781 -106.330754) (xy 11.632341 -106.285692) (xy 11.569642 -106.234237)
			(xy 11.512289 -106.176884) (xy 11.460834 -106.114185) (xy 11.415772 -106.046745) (xy 11.377537 -105.975213)
			(xy 11.346498 -105.900277) (xy 11.322953 -105.822661) (xy 11.30713 -105.74311) (xy 11.29918 -105.662391)
			(xy 10.4102 -105.662391) (xy 10.40225 -105.74311) (xy 10.386427 -105.822661) (xy 10.362882 -105.900277)
			(xy 10.331843 -105.975213) (xy 10.293608 -106.046745) (xy 10.248546 -106.114185) (xy 10.197091 -106.176884)
			(xy 10.139738 -106.234237) (xy 10.077039 -106.285692) (xy 10.009599 -106.330754) (xy 9.938067 -106.368989)
			(xy 9.863131 -106.400028) (xy 9.785515 -106.423573) (xy 9.705964 -106.439396) (xy 9.625245 -106.447346)
			(xy 9.544135 -106.447346) (xy 9.463416 -106.439396) (xy 9.383865 -106.423573) (xy 9.306249 -106.400028)
			(xy 9.231313 -106.368989) (xy 9.159781 -106.330754) (xy 9.092341 -106.285692) (xy 9.029642 -106.234237)
			(xy 8.972289 -106.176884) (xy 8.920834 -106.114185) (xy 8.875772 -106.046745) (xy 8.837537 -105.975213)
			(xy 8.806498 -105.900277) (xy 8.782953 -105.822661) (xy 8.76713 -105.74311) (xy 8.75918 -105.662391)
			(xy 7.8702 -105.662391) (xy 7.86225 -105.74311) (xy 7.846427 -105.822661) (xy 7.822882 -105.900277)
			(xy 7.791843 -105.975213) (xy 7.753608 -106.046745) (xy 7.708546 -106.114185) (xy 7.657091 -106.176884)
			(xy 7.599738 -106.234237) (xy 7.537039 -106.285692) (xy 7.469599 -106.330754) (xy 7.398067 -106.368989)
			(xy 7.323131 -106.400028) (xy 7.245515 -106.423573) (xy 7.165964 -106.439396) (xy 7.085245 -106.447346)
			(xy 7.004135 -106.447346) (xy 6.923416 -106.439396) (xy 6.843865 -106.423573) (xy 6.766249 -106.400028)
			(xy 6.691313 -106.368989) (xy 6.619781 -106.330754) (xy 6.552341 -106.285692) (xy 6.489642 -106.234237)
			(xy 6.432289 -106.176884) (xy 6.380834 -106.114185) (xy 6.335772 -106.046745) (xy 6.297537 -105.975213)
			(xy 6.266498 -105.900277) (xy 6.242953 -105.822661) (xy 6.22713 -105.74311) (xy 6.21918 -105.662391)
			(xy 5.330444 -105.662391) (xy 5.330444 -106.447844) (xy 3.678936 -106.447844) (xy 3.678936 -104.795828)
			(xy 1.27 -104.795828) (xy 1.27 -108.202391) (xy 4.94918 -108.202391) (xy 4.94918 -108.121281) (xy 4.95713 -108.040562)
			(xy 4.972953 -107.961011) (xy 4.996498 -107.883395) (xy 5.027537 -107.808459) (xy 5.065772 -107.736927)
			(xy 5.110834 -107.669487) (xy 5.162289 -107.606788) (xy 5.219642 -107.549435) (xy 5.282341 -107.49798)
			(xy 5.349781 -107.452918) (xy 5.421313 -107.414683) (xy 5.496249 -107.383644) (xy 5.573865 -107.360099)
			(xy 5.653416 -107.344276) (xy 5.734135 -107.336326) (xy 5.815245 -107.336326) (xy 5.895964 -107.344276)
			(xy 5.975515 -107.360099) (xy 6.053131 -107.383644) (xy 6.128067 -107.414683) (xy 6.199599 -107.452918)
			(xy 6.267039 -107.49798) (xy 6.329738 -107.549435) (xy 6.387091 -107.606788) (xy 6.438546 -107.669487)
			(xy 6.483608 -107.736927) (xy 6.521843 -107.808459) (xy 6.552882 -107.883395) (xy 6.576427 -107.961011)
			(xy 6.59225 -108.040562) (xy 6.6002 -108.121281) (xy 6.600698 -108.161836) (xy 6.6002 -108.202391)
			(xy 7.48918 -108.202391) (xy 7.48918 -108.121281) (xy 7.49713 -108.040562) (xy 7.512953 -107.961011)
			(xy 7.536498 -107.883395) (xy 7.567537 -107.808459) (xy 7.605772 -107.736927) (xy 7.650834 -107.669487)
			(xy 7.702289 -107.606788) (xy 7.759642 -107.549435) (xy 7.822341 -107.49798) (xy 7.889781 -107.452918)
			(xy 7.961313 -107.414683) (xy 8.036249 -107.383644) (xy 8.113865 -107.360099) (xy 8.193416 -107.344276)
			(xy 8.274135 -107.336326) (xy 8.355245 -107.336326) (xy 8.435964 -107.344276) (xy 8.515515 -107.360099)
			(xy 8.593131 -107.383644) (xy 8.668067 -107.414683) (xy 8.739599 -107.452918) (xy 8.807039 -107.49798)
			(xy 8.869738 -107.549435) (xy 8.927091 -107.606788) (xy 8.978546 -107.669487) (xy 9.023608 -107.736927)
			(xy 9.061843 -107.808459) (xy 9.092882 -107.883395) (xy 9.116427 -107.961011) (xy 9.13225 -108.040562)
			(xy 9.1402 -108.121281) (xy 9.140698 -108.161836) (xy 9.1402 -108.202391) (xy 10.02918 -108.202391)
			(xy 10.02918 -108.121281) (xy 10.03713 -108.040562) (xy 10.052953 -107.961011) (xy 10.076498 -107.883395)
			(xy 10.107537 -107.808459) (xy 10.145772 -107.736927) (xy 10.190834 -107.669487) (xy 10.242289 -107.606788)
			(xy 10.299642 -107.549435) (xy 10.362341 -107.49798) (xy 10.429781 -107.452918) (xy 10.501313 -107.414683)
			(xy 10.576249 -107.383644) (xy 10.653865 -107.360099) (xy 10.733416 -107.344276) (xy 10.814135 -107.336326)
			(xy 10.895245 -107.336326) (xy 10.975964 -107.344276) (xy 11.055515 -107.360099) (xy 11.133131 -107.383644)
			(xy 11.208067 -107.414683) (xy 11.279599 -107.452918) (xy 11.347039 -107.49798) (xy 11.409738 -107.549435)
			(xy 11.467091 -107.606788) (xy 11.518546 -107.669487) (xy 11.563608 -107.736927) (xy 11.601843 -107.808459)
			(xy 11.632882 -107.883395) (xy 11.656427 -107.961011) (xy 11.67225 -108.040562) (xy 11.6802 -108.121281)
			(xy 11.680698 -108.161836) (xy 11.6802 -108.202391) (xy 12.56918 -108.202391) (xy 12.56918 -108.121281)
			(xy 12.57713 -108.040562) (xy 12.592953 -107.961011) (xy 12.616498 -107.883395) (xy 12.647537 -107.808459)
			(xy 12.685772 -107.736927) (xy 12.730834 -107.669487) (xy 12.782289 -107.606788) (xy 12.839642 -107.549435)
			(xy 12.902341 -107.49798) (xy 12.969781 -107.452918) (xy 13.041313 -107.414683) (xy 13.116249 -107.383644)
			(xy 13.193865 -107.360099) (xy 13.273416 -107.344276) (xy 13.354135 -107.336326) (xy 13.435245 -107.336326)
			(xy 13.515964 -107.344276) (xy 13.595515 -107.360099) (xy 13.673131 -107.383644) (xy 13.748067 -107.414683)
			(xy 13.819599 -107.452918) (xy 13.887039 -107.49798) (xy 13.949738 -107.549435) (xy 14.007091 -107.606788)
			(xy 14.058546 -107.669487) (xy 14.103608 -107.736927) (xy 14.141843 -107.808459) (xy 14.172882 -107.883395)
			(xy 14.196427 -107.961011) (xy 14.21225 -108.040562) (xy 14.2202 -108.121281) (xy 14.220698 -108.161836)
			(xy 14.2202 -108.202391) (xy 14.21225 -108.28311) (xy 14.196427 -108.362661) (xy 14.172882 -108.440277)
			(xy 14.141843 -108.515213) (xy 14.103608 -108.586745) (xy 14.058546 -108.654185) (xy 14.007091 -108.716884)
			(xy 13.949738 -108.774237) (xy 13.887039 -108.825692) (xy 13.819599 -108.870754) (xy 13.748067 -108.908989)
			(xy 13.673131 -108.940028) (xy 13.595515 -108.963573) (xy 13.515964 -108.979396) (xy 13.435245 -108.987346)
			(xy 13.354135 -108.987346) (xy 13.273416 -108.979396) (xy 13.193865 -108.963573) (xy 13.116249 -108.940028)
			(xy 13.041313 -108.908989) (xy 12.969781 -108.870754) (xy 12.902341 -108.825692) (xy 12.839642 -108.774237)
			(xy 12.782289 -108.716884) (xy 12.730834 -108.654185) (xy 12.685772 -108.586745) (xy 12.647537 -108.515213)
			(xy 12.616498 -108.440277) (xy 12.592953 -108.362661) (xy 12.57713 -108.28311) (xy 12.56918 -108.202391)
			(xy 11.6802 -108.202391) (xy 11.67225 -108.28311) (xy 11.656427 -108.362661) (xy 11.632882 -108.440277)
			(xy 11.601843 -108.515213) (xy 11.563608 -108.586745) (xy 11.518546 -108.654185) (xy 11.467091 -108.716884)
			(xy 11.409738 -108.774237) (xy 11.347039 -108.825692) (xy 11.279599 -108.870754) (xy 11.208067 -108.908989)
			(xy 11.133131 -108.940028) (xy 11.055515 -108.963573) (xy 10.975964 -108.979396) (xy 10.895245 -108.987346)
			(xy 10.814135 -108.987346) (xy 10.733416 -108.979396) (xy 10.653865 -108.963573) (xy 10.576249 -108.940028)
			(xy 10.501313 -108.908989) (xy 10.429781 -108.870754) (xy 10.362341 -108.825692) (xy 10.299642 -108.774237)
			(xy 10.242289 -108.716884) (xy 10.190834 -108.654185) (xy 10.145772 -108.586745) (xy 10.107537 -108.515213)
			(xy 10.076498 -108.440277) (xy 10.052953 -108.362661) (xy 10.03713 -108.28311) (xy 10.02918 -108.202391)
			(xy 9.1402 -108.202391) (xy 9.13225 -108.28311) (xy 9.116427 -108.362661) (xy 9.092882 -108.440277)
			(xy 9.061843 -108.515213) (xy 9.023608 -108.586745) (xy 8.978546 -108.654185) (xy 8.927091 -108.716884)
			(xy 8.869738 -108.774237) (xy 8.807039 -108.825692) (xy 8.739599 -108.870754) (xy 8.668067 -108.908989)
			(xy 8.593131 -108.940028) (xy 8.515515 -108.963573) (xy 8.435964 -108.979396) (xy 8.355245 -108.987346)
			(xy 8.274135 -108.987346) (xy 8.193416 -108.979396) (xy 8.113865 -108.963573) (xy 8.036249 -108.940028)
			(xy 7.961313 -108.908989) (xy 7.889781 -108.870754) (xy 7.822341 -108.825692) (xy 7.759642 -108.774237)
			(xy 7.702289 -108.716884) (xy 7.650834 -108.654185) (xy 7.605772 -108.586745) (xy 7.567537 -108.515213)
			(xy 7.536498 -108.440277) (xy 7.512953 -108.362661) (xy 7.49713 -108.28311) (xy 7.48918 -108.202391)
			(xy 6.6002 -108.202391) (xy 6.59225 -108.28311) (xy 6.576427 -108.362661) (xy 6.552882 -108.440277)
			(xy 6.521843 -108.515213) (xy 6.483608 -108.586745) (xy 6.438546 -108.654185) (xy 6.387091 -108.716884)
			(xy 6.329738 -108.774237) (xy 6.267039 -108.825692) (xy 6.199599 -108.870754) (xy 6.128067 -108.908989)
			(xy 6.053131 -108.940028) (xy 5.975515 -108.963573) (xy 5.895964 -108.979396) (xy 5.815245 -108.987346)
			(xy 5.734135 -108.987346) (xy 5.653416 -108.979396) (xy 5.573865 -108.963573) (xy 5.496249 -108.940028)
			(xy 5.421313 -108.908989) (xy 5.349781 -108.870754) (xy 5.282341 -108.825692) (xy 5.219642 -108.774237)
			(xy 5.162289 -108.716884) (xy 5.110834 -108.654185) (xy 5.065772 -108.586745) (xy 5.027537 -108.515213)
			(xy 4.996498 -108.440277) (xy 4.972953 -108.362661) (xy 4.95713 -108.28311) (xy 4.94918 -108.202391)
			(xy 1.27 -108.202391) (xy 1.27 -118.09984) (xy 8.597656 -118.09984) (xy 8.601644 -117.84722) (xy 8.613605 -117.594852)
			(xy 8.633527 -117.342988) (xy 8.661391 -117.091878) (xy 8.697167 -116.841772) (xy 8.740821 -116.592921)
			(xy 8.79231 -116.345572) (xy 8.851581 -116.099971) (xy 8.918576 -115.856364) (xy 8.993227 -115.614994)
			(xy 9.075462 -115.3761) (xy 9.165196 -115.139922) (xy 9.262342 -114.906694) (xy 9.366802 -114.676648)
			(xy 9.478473 -114.450016) (xy 9.597242 -114.227021) (xy 9.722991 -114.007887) (xy 9.855596 -113.792832)
			(xy 9.994923 -113.58207) (xy 10.140835 -113.375812) (xy 10.293185 -113.174263) (xy 10.451821 -112.977623)
			(xy 10.616586 -112.78609) (xy 10.787316 -112.599853) (xy 10.96384 -112.419099) (xy 11.145982 -112.244008)
			(xy 11.33356 -112.074754) (xy 11.526388 -111.911505) (xy 11.724273 -111.754426) (xy 11.927019 -111.603671)
			(xy 12.134423 -111.459393) (xy 12.346278 -111.321733) (xy 12.562373 -111.19083) (xy 12.782493 -111.066814)
			(xy 13.006418 -110.949809) (xy 13.233925 -110.839931) (xy 13.464787 -110.73729) (xy 13.698775 -110.641988)
			(xy 13.935654 -110.554121) (xy 14.17519 -110.473774) (xy 14.417142 -110.40103) (xy 14.66127 -110.33596)
			(xy 14.907331 -110.27863) (xy 15.155079 -110.229096) (xy 15.404267 -110.187407) (xy 15.654647 -110.153606)
			(xy 15.905969 -110.127725) (xy 16.157983 -110.109792) (xy 16.410437 -110.099823) (xy 16.663081 -110.097829)
			(xy 16.915661 -110.103811) (xy 17.167927 -110.117764) (xy 17.419626 -110.139674) (xy 17.670509 -110.169518)
			(xy 17.920324 -110.207268) (xy 18.168823 -110.252885) (xy 18.415758 -110.306324) (xy 18.660883 -110.367532)
			(xy 18.903953 -110.436447) (xy 19.144727 -110.513002) (xy 19.382964 -110.597119) (xy 19.618427 -110.688716)
			(xy 19.850881 -110.7877) (xy 20.080095 -110.893972) (xy 20.305839 -111.007428) (xy 20.527889 -111.127953)
			(xy 20.746023 -111.255429) (xy 20.960025 -111.389727) (xy 21.169681 -111.530713) (xy 21.374781 -111.678248)
			(xy 21.575121 -111.832184) (xy 21.770502 -111.992368) (xy 21.960729 -112.15864) (xy 22.145612 -112.330835)
			(xy 22.324968 -112.508779) (xy 22.498616 -112.692298) (xy 22.666384 -112.881206) (xy 22.828105 -113.075317)
			(xy 22.983618 -113.274436) (xy 23.132767 -113.478365) (xy 23.275404 -113.686901) (xy 23.411387 -113.899836)
			(xy 23.54058 -114.116958) (xy 23.662855 -114.33805) (xy 23.778089 -114.562891) (xy 23.886168 -114.791259)
			(xy 23.986983 -115.022924) (xy 24.080435 -115.257657) (xy 24.16643 -115.495222) (xy 24.244883 -115.735384)
			(xy 24.315715 -115.977903) (xy 24.378856 -116.222538) (xy 24.434243 -116.469043) (xy 24.48182 -116.717174)
			(xy 24.52154 -116.966684) (xy 24.553364 -117.217323) (xy 24.57726 -117.468841) (xy 24.593204 -117.720989)
			(xy 24.601179 -117.973514) (xy 24.601678 -118.09984) (xy 24.601179 -118.226166) (xy 24.593204 -118.478691)
			(xy 24.57726 -118.730839) (xy 24.553364 -118.982357) (xy 24.52154 -119.232996) (xy 24.48182 -119.482506)
			(xy 24.434243 -119.730637) (xy 24.378856 -119.977142) (xy 24.315715 -120.221777) (xy 24.244883 -120.464296)
			(xy 24.16643 -120.704458) (xy 24.080435 -120.942023) (xy 23.986983 -121.176756) (xy 23.886168 -121.408421)
			(xy 23.778089 -121.636789) (xy 23.662855 -121.86163) (xy 23.54058 -122.082722) (xy 23.411387 -122.299844)
			(xy 23.275404 -122.512779) (xy 23.132767 -122.721315) (xy 22.983618 -122.925244) (xy 22.828105 -123.124363)
			(xy 22.666384 -123.318474) (xy 22.498616 -123.507382) (xy 22.324968 -123.690901) (xy 22.145612 -123.868845)
			(xy 21.960729 -124.04104) (xy 21.770502 -124.207312) (xy 21.575121 -124.367496) (xy 21.374781 -124.521432)
			(xy 21.169681 -124.668967) (xy 20.960025 -124.809953) (xy 20.746023 -124.944251) (xy 20.527889 -125.071727)
			(xy 20.305839 -125.192252) (xy 20.080095 -125.305708) (xy 19.850881 -125.41198) (xy 19.618427 -125.510964)
			(xy 19.382964 -125.602561) (xy 19.144727 -125.686678) (xy 18.903953 -125.763233) (xy 18.660883 -125.832148)
			(xy 18.415758 -125.893356) (xy 18.168823 -125.946795) (xy 17.920324 -125.992412) (xy 17.670509 -126.030162)
			(xy 17.419626 -126.060006) (xy 17.167927 -126.081916) (xy 16.915661 -126.095869) (xy 16.663081 -126.101851)
			(xy 16.410437 -126.099857) (xy 16.157983 -126.089888) (xy 15.905969 -126.071955) (xy 15.654647 -126.046074)
			(xy 15.404267 -126.012273) (xy 15.155079 -125.970584) (xy 14.907331 -125.92105) (xy 14.66127 -125.86372)
			(xy 14.417142 -125.79865) (xy 14.17519 -125.725906) (xy 13.935654 -125.645559) (xy 13.698775 -125.557692)
			(xy 13.464787 -125.46239) (xy 13.233925 -125.359749) (xy 13.006418 -125.249871) (xy 12.782493 -125.132866)
			(xy 12.562373 -125.00885) (xy 12.346278 -124.877947) (xy 12.134423 -124.740287) (xy 11.927019 -124.596009)
			(xy 11.724273 -124.445254) (xy 11.526388 -124.288175) (xy 11.33356 -124.124926) (xy 11.145982 -123.955672)
			(xy 10.96384 -123.780581) (xy 10.787316 -123.599827) (xy 10.616586 -123.41359) (xy 10.451821 -123.222057)
			(xy 10.293185 -123.025417) (xy 10.140835 -122.823868) (xy 9.994923 -122.61761) (xy 9.855596 -122.406848)
			(xy 9.722991 -122.191793) (xy 9.597242 -121.972659) (xy 9.478473 -121.749664) (xy 9.366802 -121.523032)
			(xy 9.262342 -121.292986) (xy 9.165196 -121.059758) (xy 9.075462 -120.82358) (xy 8.993227 -120.584686)
			(xy 8.918576 -120.343316) (xy 8.851581 -120.099709) (xy 8.79231 -119.854108) (xy 8.740821 -119.606759)
			(xy 8.697167 -119.357908) (xy 8.661391 -119.107802) (xy 8.633527 -118.856692) (xy 8.613605 -118.604828)
			(xy 8.601644 -118.35246) (xy 8.597656 -118.09984) (xy 1.27 -118.09984) (xy 1.27 -129.249987) (xy 4.037327 -129.249987)
			(xy 4.037327 -129.170121) (xy 4.045407 -129.090666) (xy 4.061484 -129.012436) (xy 4.085393 -128.936234)
			(xy 4.116888 -128.862841) (xy 4.155647 -128.793011) (xy 4.201271 -128.727461) (xy 4.253293 -128.666862)
			(xy 4.311178 -128.611838) (xy 4.374334 -128.562952) (xy 4.442111 -128.520706) (xy 4.513814 -128.485534)
			(xy 4.588708 -128.457797) (xy 4.666023 -128.437778) (xy 4.744967 -128.425685) (xy 4.82473 -128.42164)
			(xy 4.904493 -128.425685) (xy 4.983437 -128.437778) (xy 5.060752 -128.457797) (xy 5.135646 -128.485534)
			(xy 5.207349 -128.520706) (xy 5.275126 -128.562952) (xy 5.338282 -128.611838) (xy 5.396167 -128.666862)
			(xy 5.448189 -128.727461) (xy 5.493813 -128.793011) (xy 5.532572 -128.862841) (xy 5.564067 -128.936234)
			(xy 5.587976 -129.012436) (xy 5.604053 -129.090666) (xy 5.612133 -129.170121) (xy 5.612638 -129.210054)
			(xy 5.612133 -129.249987) (xy 6.577327 -129.249987) (xy 6.577327 -129.170121) (xy 6.585407 -129.090666)
			(xy 6.601484 -129.012436) (xy 6.625393 -128.936234) (xy 6.656888 -128.862841) (xy 6.695647 -128.793011)
			(xy 6.741271 -128.727461) (xy 6.793293 -128.666862) (xy 6.851178 -128.611838) (xy 6.914334 -128.562952)
			(xy 6.982111 -128.520706) (xy 7.053814 -128.485534) (xy 7.128708 -128.457797) (xy 7.206023 -128.437778)
			(xy 7.284967 -128.425685) (xy 7.36473 -128.42164) (xy 7.444493 -128.425685) (xy 7.523437 -128.437778)
			(xy 7.600752 -128.457797) (xy 7.675646 -128.485534) (xy 7.747349 -128.520706) (xy 7.815126 -128.562952)
			(xy 7.878282 -128.611838) (xy 7.936167 -128.666862) (xy 7.988189 -128.727461) (xy 8.033813 -128.793011)
			(xy 8.072572 -128.862841) (xy 8.104067 -128.936234) (xy 8.127976 -129.012436) (xy 8.144053 -129.090666)
			(xy 8.152133 -129.170121) (xy 8.152638 -129.210054) (xy 8.152133 -129.249987) (xy 9.117327 -129.249987)
			(xy 9.117327 -129.170121) (xy 9.125407 -129.090666) (xy 9.141484 -129.012436) (xy 9.165393 -128.936234)
			(xy 9.196888 -128.862841) (xy 9.235647 -128.793011) (xy 9.281271 -128.727461) (xy 9.333293 -128.666862)
			(xy 9.391178 -128.611838) (xy 9.454334 -128.562952) (xy 9.522111 -128.520706) (xy 9.593814 -128.485534)
			(xy 9.668708 -128.457797) (xy 9.746023 -128.437778) (xy 9.824967 -128.425685) (xy 9.90473 -128.42164)
			(xy 9.984493 -128.425685) (xy 10.063437 -128.437778) (xy 10.140752 -128.457797) (xy 10.215646 -128.485534)
			(xy 10.287349 -128.520706) (xy 10.355126 -128.562952) (xy 10.418282 -128.611838) (xy 10.476167 -128.666862)
			(xy 10.528189 -128.727461) (xy 10.573813 -128.793011) (xy 10.612572 -128.862841) (xy 10.644067 -128.936234)
			(xy 10.667976 -129.012436) (xy 10.684053 -129.090666) (xy 10.692133 -129.170121) (xy 10.692638 -129.210054)
			(xy 10.692133 -129.249987) (xy 11.657327 -129.249987) (xy 11.657327 -129.170121) (xy 11.665407 -129.090666)
			(xy 11.681484 -129.012436) (xy 11.705393 -128.936234) (xy 11.736888 -128.862841) (xy 11.775647 -128.793011)
			(xy 11.821271 -128.727461) (xy 11.873293 -128.666862) (xy 11.931178 -128.611838) (xy 11.994334 -128.562952)
			(xy 12.062111 -128.520706) (xy 12.133814 -128.485534) (xy 12.208708 -128.457797) (xy 12.286023 -128.437778)
			(xy 12.364967 -128.425685) (xy 12.44473 -128.42164) (xy 12.524493 -128.425685) (xy 12.603437 -128.437778)
			(xy 12.680752 -128.457797) (xy 12.755646 -128.485534) (xy 12.827349 -128.520706) (xy 12.895126 -128.562952)
			(xy 12.958282 -128.611838) (xy 13.016167 -128.666862) (xy 13.068189 -128.727461) (xy 13.113813 -128.793011)
			(xy 13.152572 -128.862841) (xy 13.184067 -128.936234) (xy 13.207976 -129.012436) (xy 13.224053 -129.090666)
			(xy 13.232133 -129.170121) (xy 13.232638 -129.210054) (xy 13.232133 -129.249987) (xy 13.224053 -129.329442)
			(xy 13.207976 -129.407672) (xy 13.184067 -129.483874) (xy 13.152572 -129.557267) (xy 13.113813 -129.627097)
			(xy 13.068189 -129.692647) (xy 13.016167 -129.753246) (xy 12.958282 -129.80827) (xy 12.895126 -129.857156)
			(xy 12.827349 -129.899402) (xy 12.755646 -129.934574) (xy 12.680752 -129.962311) (xy 12.603437 -129.98233)
			(xy 12.524493 -129.994423) (xy 12.44473 -129.998469) (xy 12.364967 -129.994423) (xy 12.286023 -129.98233)
			(xy 12.208708 -129.962311) (xy 12.133814 -129.934574) (xy 12.062111 -129.899402) (xy 11.994334 -129.857156)
			(xy 11.931178 -129.80827) (xy 11.873293 -129.753246) (xy 11.821271 -129.692647) (xy 11.775647 -129.627097)
			(xy 11.736888 -129.557267) (xy 11.705393 -129.483874) (xy 11.681484 -129.407672) (xy 11.665407 -129.329442)
			(xy 11.657327 -129.249987) (xy 10.692133 -129.249987) (xy 10.684053 -129.329442) (xy 10.667976 -129.407672)
			(xy 10.644067 -129.483874) (xy 10.612572 -129.557267) (xy 10.573813 -129.627097) (xy 10.528189 -129.692647)
			(xy 10.476167 -129.753246) (xy 10.418282 -129.80827) (xy 10.355126 -129.857156) (xy 10.287349 -129.899402)
			(xy 10.215646 -129.934574) (xy 10.140752 -129.962311) (xy 10.063437 -129.98233) (xy 9.984493 -129.994423)
			(xy 9.90473 -129.998469) (xy 9.824967 -129.994423) (xy 9.746023 -129.98233) (xy 9.668708 -129.962311)
			(xy 9.593814 -129.934574) (xy 9.522111 -129.899402) (xy 9.454334 -129.857156) (xy 9.391178 -129.80827)
			(xy 9.333293 -129.753246) (xy 9.281271 -129.692647) (xy 9.235647 -129.627097) (xy 9.196888 -129.557267)
			(xy 9.165393 -129.483874) (xy 9.141484 -129.407672) (xy 9.125407 -129.329442) (xy 9.117327 -129.249987)
			(xy 8.152133 -129.249987) (xy 8.144053 -129.329442) (xy 8.127976 -129.407672) (xy 8.104067 -129.483874)
			(xy 8.072572 -129.557267) (xy 8.033813 -129.627097) (xy 7.988189 -129.692647) (xy 7.936167 -129.753246)
			(xy 7.878282 -129.80827) (xy 7.815126 -129.857156) (xy 7.747349 -129.899402) (xy 7.675646 -129.934574)
			(xy 7.600752 -129.962311) (xy 7.523437 -129.98233) (xy 7.444493 -129.994423) (xy 7.36473 -129.998469)
			(xy 7.284967 -129.994423) (xy 7.206023 -129.98233) (xy 7.128708 -129.962311) (xy 7.053814 -129.934574)
			(xy 6.982111 -129.899402) (xy 6.914334 -129.857156) (xy 6.851178 -129.80827) (xy 6.793293 -129.753246)
			(xy 6.741271 -129.692647) (xy 6.695647 -129.627097) (xy 6.656888 -129.557267) (xy 6.625393 -129.483874)
			(xy 6.601484 -129.407672) (xy 6.585407 -129.329442) (xy 6.577327 -129.249987) (xy 5.612133 -129.249987)
			(xy 5.604053 -129.329442) (xy 5.587976 -129.407672) (xy 5.564067 -129.483874) (xy 5.532572 -129.557267)
			(xy 5.493813 -129.627097) (xy 5.448189 -129.692647) (xy 5.396167 -129.753246) (xy 5.338282 -129.80827)
			(xy 5.275126 -129.857156) (xy 5.207349 -129.899402) (xy 5.135646 -129.934574) (xy 5.060752 -129.962311)
			(xy 4.983437 -129.98233) (xy 4.904493 -129.994423) (xy 4.82473 -129.998469) (xy 4.744967 -129.994423)
			(xy 4.666023 -129.98233) (xy 4.588708 -129.962311) (xy 4.513814 -129.934574) (xy 4.442111 -129.899402)
			(xy 4.374334 -129.857156) (xy 4.311178 -129.80827) (xy 4.253293 -129.753246) (xy 4.201271 -129.692647)
			(xy 4.155647 -129.627097) (xy 4.116888 -129.557267) (xy 4.085393 -129.483874) (xy 4.061484 -129.407672)
			(xy 4.045407 -129.329442) (xy 4.037327 -129.249987) (xy 1.27 -129.249987) (xy 1.27 -131.789987) (xy 5.307327 -131.789987)
			(xy 5.307327 -131.710121) (xy 5.315407 -131.630666) (xy 5.331484 -131.552436) (xy 5.355393 -131.476234)
			(xy 5.386888 -131.402841) (xy 5.425647 -131.333011) (xy 5.471271 -131.267461) (xy 5.523293 -131.206862)
			(xy 5.581178 -131.151838) (xy 5.644334 -131.102952) (xy 5.712111 -131.060706) (xy 5.783814 -131.025534)
			(xy 5.858708 -130.997797) (xy 5.936023 -130.977778) (xy 6.014967 -130.965685) (xy 6.09473 -130.96164)
			(xy 6.174493 -130.965685) (xy 6.253437 -130.977778) (xy 6.330752 -130.997797) (xy 6.405646 -131.025534)
			(xy 6.477349 -131.060706) (xy 6.545126 -131.102952) (xy 6.608282 -131.151838) (xy 6.666167 -131.206862)
			(xy 6.718189 -131.267461) (xy 6.763813 -131.333011) (xy 6.802572 -131.402841) (xy 6.834067 -131.476234)
			(xy 6.857976 -131.552436) (xy 6.874053 -131.630666) (xy 6.882133 -131.710121) (xy 6.882638 -131.750054)
			(xy 6.882133 -131.789987) (xy 7.847327 -131.789987) (xy 7.847327 -131.710121) (xy 7.855407 -131.630666)
			(xy 7.871484 -131.552436) (xy 7.895393 -131.476234) (xy 7.926888 -131.402841) (xy 7.965647 -131.333011)
			(xy 8.011271 -131.267461) (xy 8.063293 -131.206862) (xy 8.121178 -131.151838) (xy 8.184334 -131.102952)
			(xy 8.252111 -131.060706) (xy 8.323814 -131.025534) (xy 8.398708 -130.997797) (xy 8.476023 -130.977778)
			(xy 8.554967 -130.965685) (xy 8.63473 -130.96164) (xy 8.714493 -130.965685) (xy 8.793437 -130.977778)
			(xy 8.870752 -130.997797) (xy 8.945646 -131.025534) (xy 9.017349 -131.060706) (xy 9.085126 -131.102952)
			(xy 9.148282 -131.151838) (xy 9.206167 -131.206862) (xy 9.258189 -131.267461) (xy 9.303813 -131.333011)
			(xy 9.342572 -131.402841) (xy 9.374067 -131.476234) (xy 9.397976 -131.552436) (xy 9.414053 -131.630666)
			(xy 9.422133 -131.710121) (xy 9.422638 -131.750054) (xy 9.422133 -131.789987) (xy 10.387327 -131.789987)
			(xy 10.387327 -131.710121) (xy 10.395407 -131.630666) (xy 10.411484 -131.552436) (xy 10.435393 -131.476234)
			(xy 10.466888 -131.402841) (xy 10.505647 -131.333011) (xy 10.551271 -131.267461) (xy 10.603293 -131.206862)
			(xy 10.661178 -131.151838) (xy 10.724334 -131.102952) (xy 10.792111 -131.060706) (xy 10.863814 -131.025534)
			(xy 10.938708 -130.997797) (xy 11.016023 -130.977778) (xy 11.094967 -130.965685) (xy 11.17473 -130.96164)
			(xy 11.189716 -130.9624) (xy 12.927076 -130.9624) (xy 14.502384 -130.9624) (xy 14.502384 -132.537708)
			(xy 12.927076 -132.537708) (xy 12.927076 -130.9624) (xy 11.189716 -130.9624) (xy 11.254493 -130.965685)
			(xy 11.333437 -130.977778) (xy 11.410752 -130.997797) (xy 11.485646 -131.025534) (xy 11.557349 -131.060706)
			(xy 11.625126 -131.102952) (xy 11.688282 -131.151838) (xy 11.746167 -131.206862) (xy 11.798189 -131.267461)
			(xy 11.843813 -131.333011) (xy 11.882572 -131.402841) (xy 11.914067 -131.476234) (xy 11.937976 -131.552436)
			(xy 11.954053 -131.630666) (xy 11.962133 -131.710121) (xy 11.962638 -131.750054) (xy 11.962133 -131.789987)
			(xy 11.954053 -131.869442) (xy 11.937976 -131.947672) (xy 11.914067 -132.023874) (xy 11.882572 -132.097267)
			(xy 11.843813 -132.167097) (xy 11.798189 -132.232647) (xy 11.746167 -132.293246) (xy 11.688282 -132.34827)
			(xy 11.625126 -132.397156) (xy 11.557349 -132.439402) (xy 11.485646 -132.474574) (xy 11.410752 -132.502311)
			(xy 11.333437 -132.52233) (xy 11.254493 -132.534423) (xy 11.17473 -132.538469) (xy 11.094967 -132.534423)
			(xy 11.016023 -132.52233) (xy 10.938708 -132.502311) (xy 10.863814 -132.474574) (xy 10.792111 -132.439402)
			(xy 10.724334 -132.397156) (xy 10.661178 -132.34827) (xy 10.603293 -132.293246) (xy 10.551271 -132.232647)
			(xy 10.505647 -132.167097) (xy 10.466888 -132.097267) (xy 10.435393 -132.023874) (xy 10.411484 -131.947672)
			(xy 10.395407 -131.869442) (xy 10.387327 -131.789987) (xy 9.422133 -131.789987) (xy 9.414053 -131.869442)
			(xy 9.397976 -131.947672) (xy 9.374067 -132.023874) (xy 9.342572 -132.097267) (xy 9.303813 -132.167097)
			(xy 9.258189 -132.232647) (xy 9.206167 -132.293246) (xy 9.148282 -132.34827) (xy 9.085126 -132.397156)
			(xy 9.017349 -132.439402) (xy 8.945646 -132.474574) (xy 8.870752 -132.502311) (xy 8.793437 -132.52233)
			(xy 8.714493 -132.534423) (xy 8.63473 -132.538469) (xy 8.554967 -132.534423) (xy 8.476023 -132.52233)
			(xy 8.398708 -132.502311) (xy 8.323814 -132.474574) (xy 8.252111 -132.439402) (xy 8.184334 -132.397156)
			(xy 8.121178 -132.34827) (xy 8.063293 -132.293246) (xy 8.011271 -132.232647) (xy 7.965647 -132.167097)
			(xy 7.926888 -132.097267) (xy 7.895393 -132.023874) (xy 7.871484 -131.947672) (xy 7.855407 -131.869442)
			(xy 7.847327 -131.789987) (xy 6.882133 -131.789987) (xy 6.874053 -131.869442) (xy 6.857976 -131.947672)
			(xy 6.834067 -132.023874) (xy 6.802572 -132.097267) (xy 6.763813 -132.167097) (xy 6.718189 -132.232647)
			(xy 6.666167 -132.293246) (xy 6.608282 -132.34827) (xy 6.545126 -132.397156) (xy 6.477349 -132.439402)
			(xy 6.405646 -132.474574) (xy 6.330752 -132.502311) (xy 6.253437 -132.52233) (xy 6.174493 -132.534423)
			(xy 6.09473 -132.538469) (xy 6.014967 -132.534423) (xy 5.936023 -132.52233) (xy 5.858708 -132.502311)
			(xy 5.783814 -132.474574) (xy 5.712111 -132.439402) (xy 5.644334 -132.397156) (xy 5.581178 -132.34827)
			(xy 5.523293 -132.293246) (xy 5.471271 -132.232647) (xy 5.425647 -132.167097) (xy 5.386888 -132.097267)
			(xy 5.355393 -132.023874) (xy 5.331484 -131.947672) (xy 5.315407 -131.869442) (xy 5.307327 -131.789987)
			(xy 1.27 -131.789987) (xy 1.27 -132.814568) (xy 1.39573 -132.940552) (xy 1.445514 -132.942584) (xy 1.496866 -132.945072)
			(xy 1.598977 -132.957114) (xy 1.699829 -132.977134) (xy 1.798798 -133.005006) (xy 1.895275 -133.04056)
			(xy 1.988663 -133.083576) (xy 2.078388 -133.133788) (xy 2.163895 -133.190887) (xy 2.244657 -133.254521)
			(xy 2.320176 -133.324297) (xy 2.389986 -133.399784) (xy 2.453656 -133.480518) (xy 2.510794 -133.565999)
			(xy 2.561047 -133.655701) (xy 2.604104 -133.74907) (xy 2.639702 -133.845531) (xy 2.667619 -133.944488)
			(xy 2.687684 -134.04533) (xy 2.699772 -134.147436) (xy 2.70381 -134.250176) (xy 2.70179 -134.301572)
			(xy 15.836642 -134.301572) (xy 15.836642 -134.19878) (xy 15.844707 -134.096306) (xy 15.860787 -133.994781)
			(xy 15.884783 -133.89483) (xy 15.916548 -133.79707) (xy 15.955884 -133.702103) (xy 16.00255 -133.610516)
			(xy 16.056258 -133.522872) (xy 16.116677 -133.439712) (xy 16.183435 -133.361549) (xy 16.256119 -133.288865)
			(xy 16.334282 -133.222107) (xy 16.417442 -133.161688) (xy 16.505086 -133.10798) (xy 16.596673 -133.061314)
			(xy 16.69164 -133.021978) (xy 16.7894 -132.990213) (xy 16.889351 -132.966217) (xy 16.990876 -132.950137)
			(xy 17.09335 -132.942072) (xy 17.196142 -132.942072) (xy 17.298616 -132.950137) (xy 17.400141 -132.966217)
			(xy 17.500092 -132.990213) (xy 17.597852 -133.021978) (xy 17.692819 -133.061314) (xy 17.784406 -133.10798)
			(xy 17.87205 -133.161688) (xy 17.95521 -133.222107) (xy 18.033373 -133.288865) (xy 18.106057 -133.361549)
			(xy 18.172815 -133.439712) (xy 18.233234 -133.522872) (xy 18.286942 -133.610516) (xy 18.333608 -133.702103)
			(xy 18.372944 -133.79707) (xy 18.404709 -133.89483) (xy 18.428705 -133.994781) (xy 18.444785 -134.096306)
			(xy 18.45285 -134.19878) (xy 18.453354 -134.250176) (xy 18.45285 -134.301572) (xy 18.444785 -134.404046)
			(xy 18.428705 -134.505571) (xy 18.404709 -134.605522) (xy 18.372944 -134.703282) (xy 18.333608 -134.798249)
			(xy 18.286942 -134.889836) (xy 18.233234 -134.97748) (xy 18.172815 -135.06064) (xy 18.106057 -135.138803)
			(xy 18.033373 -135.211487) (xy 17.95521 -135.278245) (xy 17.87205 -135.338664) (xy 17.784406 -135.392372)
			(xy 17.692819 -135.439038) (xy 17.597852 -135.478374) (xy 17.500092 -135.510139) (xy 17.400141 -135.534135)
			(xy 17.298616 -135.550215) (xy 17.196142 -135.55828) (xy 17.09335 -135.55828) (xy 16.990876 -135.550215)
			(xy 16.889351 -135.534135) (xy 16.7894 -135.510139) (xy 16.69164 -135.478374) (xy 16.596673 -135.439038)
			(xy 16.505086 -135.392372) (xy 16.417442 -135.338664) (xy 16.334282 -135.278245) (xy 16.256119 -135.211487)
			(xy 16.183435 -135.138803) (xy 16.116677 -135.06064) (xy 16.056258 -134.97748) (xy 16.00255 -134.889836)
			(xy 15.955884 -134.798249) (xy 15.916548 -134.703282) (xy 15.884783 -134.605522) (xy 15.860787 -134.505571)
			(xy 15.844707 -134.404046) (xy 15.836642 -134.301572) (xy 2.70179 -134.301572) (xy 2.699772 -134.352916)
			(xy 2.687684 -134.455022) (xy 2.667619 -134.555864) (xy 2.639702 -134.654821) (xy 2.604104 -134.751282)
			(xy 2.561047 -134.844651) (xy 2.510794 -134.934353) (xy 2.453656 -135.019834) (xy 2.389986 -135.100568)
			(xy 2.320176 -135.176055) (xy 2.244657 -135.245831) (xy 2.163895 -135.309465) (xy 2.078388 -135.366564)
			(xy 1.988663 -135.416776) (xy 1.895275 -135.459792) (xy 1.798798 -135.495346) (xy 1.699829 -135.523218)
			(xy 1.598977 -135.543238) (xy 1.496866 -135.55528) (xy 1.445514 -135.557768) (xy 1.39573 -135.5598)
			(xy 1.27 -135.685784) (xy 1.27 -138.163122) (xy 1.547863 -138.163122) (xy 1.547863 -138.036986) (xy 1.555783 -137.911098)
			(xy 1.571593 -137.785956) (xy 1.595228 -137.662053) (xy 1.626597 -137.53988) (xy 1.665575 -137.419917)
			(xy 1.712009 -137.302638) (xy 1.765716 -137.188506) (xy 1.826483 -137.077971) (xy 1.89407 -136.971471)
			(xy 1.968211 -136.869424) (xy 2.048614 -136.772234) (xy 2.13496 -136.680284) (xy 2.22691 -136.593938)
			(xy 2.3241 -136.513535) (xy 2.426147 -136.439394) (xy 2.532647 -136.371807) (xy 2.643182 -136.31104)
			(xy 2.757314 -136.257333) (xy 2.874593 -136.210899) (xy 2.994556 -136.171921) (xy 3.116729 -136.140552)
			(xy 3.240632 -136.116917) (xy 3.365774 -136.101107) (xy 3.491662 -136.093187) (xy 3.617798 -136.093187)
			(xy 3.743686 -136.101107) (xy 3.868828 -136.116917) (xy 3.992731 -136.140552) (xy 4.114904 -136.171921)
			(xy 4.234867 -136.210899) (xy 4.352146 -136.257333) (xy 4.466278 -136.31104) (xy 4.576813 -136.371807)
			(xy 4.683313 -136.439394) (xy 4.78536 -136.513535) (xy 4.88255 -136.593938) (xy 4.9745 -136.680284)
			(xy 5.060846 -136.772234) (xy 5.141249 -136.869424) (xy 5.21539 -136.971471) (xy 5.282977 -137.077971)
			(xy 5.343744 -137.188506) (xy 5.397451 -137.302638) (xy 5.443885 -137.419917) (xy 5.482863 -137.53988)
			(xy 5.514232 -137.662053) (xy 5.537867 -137.785956) (xy 5.553677 -137.911098) (xy 5.561597 -138.036986)
			(xy 5.562092 -138.100054) (xy 5.561597 -138.163122) (xy 12.977863 -138.163122) (xy 12.977863 -138.036986)
			(xy 12.985783 -137.911098) (xy 13.001593 -137.785956) (xy 13.025228 -137.662053) (xy 13.056597 -137.53988)
			(xy 13.095575 -137.419917) (xy 13.142009 -137.302638) (xy 13.195716 -137.188506) (xy 13.256483 -137.077971)
			(xy 13.32407 -136.971471) (xy 13.398211 -136.869424) (xy 13.478614 -136.772234) (xy 13.56496 -136.680284)
			(xy 13.65691 -136.593938) (xy 13.7541 -136.513535) (xy 13.856147 -136.439394) (xy 13.962647 -136.371807)
			(xy 14.073182 -136.31104) (xy 14.187314 -136.257333) (xy 14.304593 -136.210899) (xy 14.424556 -136.171921)
			(xy 14.546729 -136.140552) (xy 14.670632 -136.116917) (xy 14.795774 -136.101107) (xy 14.921662 -136.093187)
			(xy 15.047798 -136.093187) (xy 15.173686 -136.101107) (xy 15.298828 -136.116917) (xy 15.422731 -136.140552)
			(xy 15.544904 -136.171921) (xy 15.664867 -136.210899) (xy 15.782146 -136.257333) (xy 15.896278 -136.31104)
			(xy 16.006813 -136.371807) (xy 16.113313 -136.439394) (xy 16.21536 -136.513535) (xy 16.31255 -136.593938)
			(xy 16.4045 -136.680284) (xy 16.490846 -136.772234) (xy 16.571249 -136.869424) (xy 16.64539 -136.971471)
			(xy 16.712977 -137.077971) (xy 16.773744 -137.188506) (xy 16.827451 -137.302638) (xy 16.873885 -137.419917)
			(xy 16.912863 -137.53988) (xy 16.944232 -137.662053) (xy 16.967867 -137.785956) (xy 16.983677 -137.911098)
			(xy 16.991597 -138.036986) (xy 16.992092 -138.100054) (xy 16.991597 -138.163122) (xy 16.983677 -138.28901)
			(xy 16.967867 -138.414152) (xy 16.944232 -138.538055) (xy 16.912863 -138.660228) (xy 16.873885 -138.780191)
			(xy 16.827451 -138.89747) (xy 16.773744 -139.011602) (xy 16.712977 -139.122137) (xy 16.64539 -139.228637)
			(xy 16.571249 -139.330684) (xy 16.490846 -139.427874) (xy 16.4045 -139.519824) (xy 16.31255 -139.60617)
			(xy 16.21536 -139.686573) (xy 16.113313 -139.760714) (xy 16.006813 -139.828301) (xy 15.896278 -139.889068)
			(xy 15.782146 -139.942775) (xy 15.664867 -139.989209) (xy 15.544904 -140.028187) (xy 15.422731 -140.059556)
			(xy 15.298828 -140.083191) (xy 15.173686 -140.099001) (xy 15.047798 -140.106921) (xy 14.921662 -140.106921)
			(xy 14.795774 -140.099001) (xy 14.670632 -140.083191) (xy 14.546729 -140.059556) (xy 14.424556 -140.028187)
			(xy 14.304593 -139.989209) (xy 14.187314 -139.942775) (xy 14.073182 -139.889068) (xy 13.962647 -139.828301)
			(xy 13.856147 -139.760714) (xy 13.7541 -139.686573) (xy 13.65691 -139.60617) (xy 13.56496 -139.519824)
			(xy 13.478614 -139.427874) (xy 13.398211 -139.330684) (xy 13.32407 -139.228637) (xy 13.256483 -139.122137)
			(xy 13.195716 -139.011602) (xy 13.142009 -138.89747) (xy 13.095575 -138.780191) (xy 13.056597 -138.660228)
			(xy 13.025228 -138.538055) (xy 13.001593 -138.414152) (xy 12.985783 -138.28901) (xy 12.977863 -138.163122)
			(xy 5.561597 -138.163122) (xy 5.553677 -138.28901) (xy 5.537867 -138.414152) (xy 5.514232 -138.538055)
			(xy 5.482863 -138.660228) (xy 5.443885 -138.780191) (xy 5.397451 -138.89747) (xy 5.343744 -139.011602)
			(xy 5.282977 -139.122137) (xy 5.21539 -139.228637) (xy 5.141249 -139.330684) (xy 5.060846 -139.427874)
			(xy 4.9745 -139.519824) (xy 4.88255 -139.60617) (xy 4.78536 -139.686573) (xy 4.683313 -139.760714)
			(xy 4.576813 -139.828301) (xy 4.466278 -139.889068) (xy 4.352146 -139.942775) (xy 4.234867 -139.989209)
			(xy 4.114904 -140.028187) (xy 3.992731 -140.059556) (xy 3.868828 -140.083191) (xy 3.743686 -140.099001)
			(xy 3.617798 -140.106921) (xy 3.491662 -140.106921) (xy 3.365774 -140.099001) (xy 3.240632 -140.083191)
			(xy 3.116729 -140.059556) (xy 2.994556 -140.028187) (xy 2.874593 -139.989209) (xy 2.757314 -139.942775)
			(xy 2.643182 -139.889068) (xy 2.532647 -139.828301) (xy 2.426147 -139.760714) (xy 2.3241 -139.686573)
			(xy 2.22691 -139.60617) (xy 2.13496 -139.519824) (xy 2.048614 -139.427874) (xy 1.968211 -139.330684)
			(xy 1.89407 -139.228637) (xy 1.826483 -139.122137) (xy 1.765716 -139.011602) (xy 1.712009 -138.89747)
			(xy 1.665575 -138.780191) (xy 1.626597 -138.660228) (xy 1.595228 -138.538055) (xy 1.571593 -138.414152)
			(xy 1.555783 -138.28901) (xy 1.547863 -138.163122) (xy 1.27 -138.163122) (xy 1.27 -142.198195) (xy 2.181445 -142.198195)
			(xy 2.186624 -142.119001) (xy 2.199738 -142.04073) (xy 2.220653 -141.964172) (xy 2.249157 -141.890105)
			(xy 2.284962 -141.819279) (xy 2.327705 -141.75241) (xy 2.376953 -141.690176) (xy 2.432208 -141.633208)
			(xy 2.492908 -141.582082) (xy 2.558441 -141.537317) (xy 2.628141 -141.499366) (xy 2.701303 -141.468613)
			(xy 2.777185 -141.44537) (xy 2.85502 -141.429872) (xy 2.934018 -141.422276) (xy 3.01338 -141.42266)
			(xy 3.092301 -141.431019) (xy 3.169982 -141.447268) (xy 3.245637 -141.471244) (xy 3.318498 -141.502703)
			(xy 3.387828 -141.541326) (xy 3.452924 -141.586723) (xy 3.513128 -141.638433) (xy 3.567829 -141.695933)
			(xy 3.616473 -141.75864) (xy 3.658567 -141.825919) (xy 3.693686 -141.897089) (xy 3.721473 -141.971428)
			(xy 3.741646 -142.048184) (xy 3.754003 -142.126578) (xy 3.758416 -142.205818) (xy 3.756426 -142.249961)
			(xy 4.672327 -142.249961) (xy 4.672327 -142.170095) (xy 4.680407 -142.09064) (xy 4.696484 -142.01241)
			(xy 4.720393 -141.936208) (xy 4.751888 -141.862815) (xy 4.790647 -141.792985) (xy 4.836271 -141.727435)
			(xy 4.888293 -141.666836) (xy 4.946178 -141.611812) (xy 5.009334 -141.562926) (xy 5.077111 -141.52068)
			(xy 5.148814 -141.485508) (xy 5.223708 -141.457771) (xy 5.301023 -141.437752) (xy 5.379967 -141.425659)
			(xy 5.45973 -141.421614) (xy 5.539493 -141.425659) (xy 5.618437 -141.437752) (xy 5.695752 -141.457771)
			(xy 5.770646 -141.485508) (xy 5.842349 -141.52068) (xy 5.910126 -141.562926) (xy 5.973282 -141.611812)
			(xy 6.031167 -141.666836) (xy 6.083189 -141.727435) (xy 6.128813 -141.792985) (xy 6.167572 -141.862815)
			(xy 6.199067 -141.936208) (xy 6.222976 -142.01241) (xy 6.239053 -142.09064) (xy 6.247133 -142.170095)
			(xy 6.247537 -142.202059) (xy 12.291447 -142.202059) (xy 12.29624 -142.122862) (xy 12.30897 -142.044547)
			(xy 12.329508 -141.967909) (xy 12.357646 -141.893723) (xy 12.393098 -141.822742) (xy 12.435505 -141.755684)
			(xy 12.484439 -141.693228) (xy 12.539402 -141.636007) (xy 12.599839 -141.584601) (xy 12.665138 -141.53953)
			(xy 12.734635 -141.501252) (xy 12.807629 -141.470153) (xy 12.883379 -141.446549) (xy 12.961118 -141.430679)
			(xy 13.040059 -141.422703) (xy 13.119401 -141.422703) (xy 13.198342 -141.430679) (xy 13.276081 -141.446549)
			(xy 13.351831 -141.470153) (xy 13.424825 -141.501252) (xy 13.494322 -141.53953) (xy 13.559621 -141.584601)
			(xy 13.620058 -141.636007) (xy 13.675021 -141.693228) (xy 13.723955 -141.755684) (xy 13.766362 -141.822742)
			(xy 13.801814 -141.893723) (xy 13.829952 -141.967909) (xy 13.85049 -142.044547) (xy 13.86322 -142.122862)
			(xy 13.868013 -142.202059) (xy 13.864822 -142.281337) (xy 13.853677 -142.359893) (xy 13.834693 -142.436931)
			(xy 13.808061 -142.51167) (xy 13.774051 -142.583354) (xy 13.733008 -142.651256) (xy 13.685347 -142.714688)
			(xy 13.631552 -142.773008) (xy 13.572166 -142.825626) (xy 13.507793 -142.872007) (xy 13.473684 -142.892272)
			(xy 13.44422 -142.90929) (xy 13.410184 -142.968218) (xy 13.410184 -143.782288) (xy 15.034006 -145.405856)
			(xy 15.111984 -145.405856) (xy 15.128642 -145.405391) (xy 15.160822 -145.39677) (xy 15.189674 -145.380111)
			(xy 15.213228 -145.356551) (xy 15.229881 -145.327696) (xy 15.238495 -145.295514) (xy 15.238984 -145.278856)
			(xy 15.238984 -143.002254) (xy 15.238464 -142.985627) (xy 15.229877 -142.9535) (xy 15.213294 -142.924674)
			(xy 15.189839 -142.9011) (xy 15.175738 -142.892272) (xy 15.141629 -142.872007) (xy 15.077256 -142.825626)
			(xy 15.01787 -142.773008) (xy 14.964075 -142.714688) (xy 14.916414 -142.651256) (xy 14.875371 -142.583354)
			(xy 14.841361 -142.51167) (xy 14.814729 -142.436931) (xy 14.795745 -142.359893) (xy 14.7846 -142.281337)
			(xy 14.781409 -142.202059) (xy 14.786202 -142.122862) (xy 14.798932 -142.044547) (xy 14.81947 -141.967909)
			(xy 14.847608 -141.893723) (xy 14.88306 -141.822742) (xy 14.925467 -141.755684) (xy 14.974401 -141.693228)
			(xy 15.029364 -141.636007) (xy 15.089801 -141.584601) (xy 15.1551 -141.53953) (xy 15.224597 -141.501252)
			(xy 15.297591 -141.470153) (xy 15.373341 -141.446549) (xy 15.45108 -141.430679) (xy 15.530021 -141.422703)
			(xy 15.609363 -141.422703) (xy 15.688304 -141.430679) (xy 15.766043 -141.446549) (xy 15.841793 -141.470153)
			(xy 15.914787 -141.501252) (xy 15.984284 -141.53953) (xy 16.049583 -141.584601) (xy 16.11002 -141.636007)
			(xy 16.164983 -141.693228) (xy 16.213917 -141.755684) (xy 16.256324 -141.822742) (xy 16.291776 -141.893723)
			(xy 16.319914 -141.967909) (xy 16.340452 -142.044547) (xy 16.353182 -142.122862) (xy 16.357975 -142.202059)
			(xy 16.354784 -142.281337) (xy 16.343639 -142.359893) (xy 16.324655 -142.436931) (xy 16.298023 -142.51167)
			(xy 16.264013 -142.583354) (xy 16.22297 -142.651256) (xy 16.175309 -142.714688) (xy 16.121514 -142.773008)
			(xy 16.062128 -142.825626) (xy 15.997755 -142.872007) (xy 15.963646 -142.892272) (xy 15.934182 -142.90929)
			(xy 15.9004 -142.968218) (xy 15.9004 -145.001234) (xy 16.321786 -145.42262) (xy 16.591788 -145.42262)
			(xy 16.591788 -146.240246) (xy 16.617188 -146.274028) (xy 16.636368 -146.300516) (xy 16.66855 -146.357449)
			(xy 16.693174 -146.418035) (xy 16.709836 -146.481275) (xy 16.71826 -146.546129) (xy 16.718788 -146.578828)
			(xy 16.718788 -147.232116) (xy 16.718286 -147.264077) (xy 16.710275 -147.327495) (xy 16.694378 -147.389409)
			(xy 16.670846 -147.448842) (xy 16.640052 -147.504857) (xy 16.602479 -147.556572) (xy 16.558722 -147.603169)
			(xy 16.509469 -147.643914) (xy 16.455498 -147.678165) (xy 16.397659 -147.705382) (xy 16.336866 -147.725135)
			(xy 16.274076 -147.737113) (xy 16.21028 -147.741127) (xy 16.146484 -147.737113) (xy 16.083694 -147.725135)
			(xy 16.022901 -147.705382) (xy 15.965062 -147.678165) (xy 15.911091 -147.643914) (xy 15.861838 -147.603169)
			(xy 15.818081 -147.556572) (xy 15.780508 -147.504857) (xy 15.749714 -147.448842) (xy 15.726182 -147.389409)
			(xy 15.710285 -147.327495) (xy 15.702274 -147.264077) (xy 15.701772 -147.232116) (xy 15.701772 -146.578828)
			(xy 15.7023 -146.546126) (xy 15.71069 -146.481264) (xy 15.727336 -146.418014) (xy 15.751961 -146.357424)
			(xy 15.784159 -146.300495) (xy 15.803372 -146.274028) (xy 15.828772 -146.240246) (xy 15.828772 -145.864834)
			(xy 15.737586 -145.773648) (xy 15.720974 -145.75768) (xy 15.683058 -145.731504) (xy 15.641044 -145.712592)
			(xy 15.596309 -145.701563) (xy 15.550319 -145.69878) (xy 15.504581 -145.704333) (xy 15.460592 -145.71804)
			(xy 15.419796 -145.739452) (xy 15.383528 -145.767868) (xy 15.352976 -145.802356) (xy 15.329143 -145.841787)
			(xy 15.312807 -145.884868) (xy 15.304506 -145.930189) (xy 15.304008 -145.953226) (xy 15.304008 -146.223482)
			(xy 15.329408 -146.257264) (xy 15.348607 -146.283739) (xy 15.380785 -146.340676) (xy 15.405405 -146.401265)
			(xy 15.422063 -146.464508) (xy 15.430482 -146.529364) (xy 15.431008 -146.562064) (xy 15.431008 -147.231862)
			(xy 15.430506 -147.263823) (xy 15.422495 -147.327241) (xy 15.406598 -147.389155) (xy 15.383066 -147.448588)
			(xy 15.352272 -147.504603) (xy 15.314699 -147.556318) (xy 15.270942 -147.602915) (xy 15.221689 -147.64366)
			(xy 15.167718 -147.677911) (xy 15.109879 -147.705128) (xy 15.049086 -147.724881) (xy 14.986296 -147.736859)
			(xy 14.9225 -147.740873) (xy 14.858704 -147.736859) (xy 14.795914 -147.724881) (xy 14.735121 -147.705128)
			(xy 14.677282 -147.677911) (xy 14.623311 -147.64366) (xy 14.574058 -147.602915) (xy 14.530301 -147.556318)
			(xy 14.492728 -147.504603) (xy 14.461934 -147.448588) (xy 14.438402 -147.389155) (xy 14.422505 -147.327241)
			(xy 14.414494 -147.263823) (xy 14.413992 -147.231862) (xy 14.413992 -146.562064) (xy 14.414502 -146.529362)
			(xy 14.422899 -146.464499) (xy 14.439549 -146.40125) (xy 14.464178 -146.34066) (xy 14.496378 -146.283731)
			(xy 14.515592 -146.257264) (xy 14.540992 -146.223482) (xy 14.540992 -145.84807) (xy 12.749276 -144.0561)
			(xy 12.749022 -143.002254) (xy 12.748532 -142.985624) (xy 12.73994 -142.953493) (xy 12.723349 -142.924666)
			(xy 12.699882 -142.901096) (xy 12.685776 -142.892272) (xy 12.651667 -142.872007) (xy 12.587294 -142.825626)
			(xy 12.527908 -142.773008) (xy 12.474113 -142.714688) (xy 12.426452 -142.651256) (xy 12.385409 -142.583354)
			(xy 12.351399 -142.51167) (xy 12.324767 -142.436931) (xy 12.305783 -142.359893) (xy 12.294638 -142.281337)
			(xy 12.291447 -142.202059) (xy 6.247537 -142.202059) (xy 6.247638 -142.210028) (xy 6.247133 -142.249961)
			(xy 6.239053 -142.329416) (xy 6.222976 -142.407646) (xy 6.199067 -142.483848) (xy 6.167572 -142.557241)
			(xy 6.128813 -142.627071) (xy 6.083189 -142.692621) (xy 6.031167 -142.75322) (xy 5.973282 -142.808244)
			(xy 5.910126 -142.85713) (xy 5.842349 -142.899376) (xy 5.770646 -142.934548) (xy 5.695752 -142.962285)
			(xy 5.618437 -142.982304) (xy 5.539493 -142.994397) (xy 5.45973 -142.998443) (xy 5.379967 -142.994397)
			(xy 5.301023 -142.982304) (xy 5.223708 -142.962285) (xy 5.148814 -142.934548) (xy 5.077111 -142.899376)
			(xy 5.009334 -142.85713) (xy 4.946178 -142.808244) (xy 4.888293 -142.75322) (xy 4.836271 -142.692621)
			(xy 4.790647 -142.627071) (xy 4.751888 -142.557241) (xy 4.720393 -142.483848) (xy 4.696484 -142.407646)
			(xy 4.680407 -142.329416) (xy 4.672327 -142.249961) (xy 3.756426 -142.249961) (xy 3.754842 -142.2851)
			(xy 3.743317 -142.363621) (xy 3.723958 -142.440586) (xy 3.69696 -142.515216) (xy 3.662598 -142.586753)
			(xy 3.621218 -142.654475) (xy 3.573241 -142.717693) (xy 3.519153 -142.77577) (xy 3.4595 -142.828115)
			(xy 3.394888 -142.874198) (xy 3.360674 -142.894304) (xy 3.346405 -142.903065) (xy 3.322611 -142.926602)
			(xy 3.305744 -142.955511) (xy 3.296962 -142.987807) (xy 3.296412 -143.00454) (xy 3.296412 -145.08734)
			(xy 3.347466 -145.13814) (xy 3.347466 -145.955766) (xy 3.372866 -145.989548) (xy 3.392042 -146.016032)
			(xy 3.424187 -146.07297) (xy 3.448764 -146.133562) (xy 3.465367 -146.196805) (xy 3.473721 -146.261655)
			(xy 3.474212 -146.294348) (xy 3.474212 -147.006564) (xy 3.473711 -147.038509) (xy 3.465703 -147.101895)
			(xy 3.449814 -147.163778) (xy 3.426295 -147.223182) (xy 3.395515 -147.279169) (xy 3.357962 -147.330858)
			(xy 3.314226 -147.377432) (xy 3.264998 -147.418157) (xy 3.211053 -147.452391) (xy 3.153244 -147.479594)
			(xy 3.092481 -147.499337) (xy 3.029722 -147.511309) (xy 2.965958 -147.515321) (xy 2.902194 -147.511309)
			(xy 2.839435 -147.499337) (xy 2.778672 -147.479594) (xy 2.720863 -147.452391) (xy 2.666918 -147.418157)
			(xy 2.61769 -147.377432) (xy 2.573954 -147.330858) (xy 2.536401 -147.279169) (xy 2.505621 -147.223182)
			(xy 2.482102 -147.163778) (xy 2.466213 -147.101895) (xy 2.458205 -147.038509) (xy 2.457704 -147.006564)
			(xy 2.457704 -146.294348) (xy 2.458179 -146.261654) (xy 2.466534 -146.196802) (xy 2.483138 -146.133557)
			(xy 2.507716 -146.072965) (xy 2.539863 -146.016025) (xy 2.55905 -145.989548) (xy 2.58445 -145.955766)
			(xy 2.58445 -145.13814) (xy 2.635504 -145.08734) (xy 2.63525 -142.999968) (xy 2.634688 -142.983441)
			(xy 2.62617 -142.951503) (xy 2.609738 -142.922823) (xy 2.586495 -142.899321) (xy 2.572512 -142.890494)
			(xy 2.538494 -142.870058) (xy 2.474331 -142.823352) (xy 2.415187 -142.770433) (xy 2.361662 -142.711836)
			(xy 2.314299 -142.648157) (xy 2.273576 -142.580038) (xy 2.239907 -142.508172) (xy 2.213632 -142.433285)
			(xy 2.195017 -142.356136) (xy 2.184252 -142.277507) (xy 2.181445 -142.198195) (xy 1.27 -142.198195)
			(xy 1.27 -151.21128) (xy 1.289812 -151.231092) (xy 1.296162 -151.231092) (xy 3.583686 -151.231092)
			(xy 4.426458 -151.231092) (xy 4.474105 -151.231021) (xy 4.569149 -151.237831) (xy 4.663298 -151.252524)
			(xy 4.755897 -151.275) (xy 4.846306 -151.305101) (xy 4.933897 -151.342619) (xy 5.018063 -151.387295)
			(xy 5.09822 -151.438819) (xy 5.173813 -151.496832) (xy 5.244317 -151.560933) (xy 5.309244 -151.630678)
			(xy 5.368143 -151.705583) (xy 5.420606 -151.785128) (xy 5.466269 -151.868763) (xy 5.504816 -151.955906)
			(xy 5.535979 -152.045954) (xy 5.559543 -152.138283) (xy 5.575343 -152.232252) (xy 5.583271 -152.32721)
			(xy 5.583271 -152.422498) (xy 5.575343 -152.517456) (xy 5.559543 -152.611425) (xy 5.535979 -152.703754)
			(xy 5.504816 -152.793802) (xy 5.466269 -152.880945) (xy 5.420606 -152.96458) (xy 5.368143 -153.044125)
			(xy 5.309244 -153.11903) (xy 5.244317 -153.188775) (xy 5.173813 -153.252876) (xy 5.09822 -153.310889)
			(xy 5.018063 -153.362413) (xy 4.933897 -153.407089) (xy 4.846306 -153.444607) (xy 4.755897 -153.474708)
			(xy 4.663298 -153.497184) (xy 4.569149 -153.511877) (xy 4.474105 -153.518687) (xy 4.426458 -153.518616)
			(xy 3.583686 -153.518616) (xy 1.764284 -153.518616) (xy 1.755385 -153.529525) (xy 1.742167 -153.554376)
			(xy 1.734771 -153.581533) (xy 1.733804 -153.595578) (xy 1.733804 -158.181294) (xy 4.426458 -158.181294)
			(xy 4.474105 -158.181223) (xy 4.569149 -158.188033) (xy 4.663298 -158.202726) (xy 4.755897 -158.225202)
			(xy 4.846306 -158.255303) (xy 4.933897 -158.292821) (xy 5.018063 -158.337497) (xy 5.09822 -158.389021)
			(xy 5.173813 -158.447034) (xy 5.244317 -158.511135) (xy 5.309244 -158.58088) (xy 5.368143 -158.655785)
			(xy 5.420606 -158.73533) (xy 5.466269 -158.818965) (xy 5.504816 -158.906108) (xy 5.535979 -158.996156)
			(xy 5.559543 -159.088485) (xy 5.575343 -159.182454) (xy 5.583271 -159.277412) (xy 5.583271 -159.3727)
			(xy 5.575343 -159.467658) (xy 5.559543 -159.561627) (xy 5.535979 -159.653956) (xy 5.504816 -159.744004)
			(xy 5.466269 -159.831147) (xy 5.420606 -159.914782) (xy 5.368143 -159.994327) (xy 5.309244 -160.069232)
			(xy 5.244317 -160.138977) (xy 5.173813 -160.203078) (xy 5.09822 -160.261091) (xy 5.018063 -160.312615)
			(xy 4.933897 -160.357291) (xy 4.846306 -160.394809) (xy 4.755897 -160.42491) (xy 4.663298 -160.447386)
			(xy 4.569149 -160.462079) (xy 4.474105 -160.468889) (xy 4.426458 -160.468818) (xy 2.770632 -160.468818)
			(xy 2.770632 -160.823656) (xy 3.043936 -161.09696) (xy 3.45186 -161.505138) (xy 3.45186 -169.167048)
			(xy 15.337534 -169.167048) (xy 15.341605 -169.111426) (xy 15.353731 -169.056989) (xy 15.373654 -169.004898)
			(xy 15.40095 -168.956263) (xy 15.435036 -168.91212) (xy 15.475185 -168.873411) (xy 15.520543 -168.84096)
			(xy 15.570143 -168.815459) (xy 15.622927 -168.797452) (xy 15.67777 -168.787322) (xy 15.733504 -168.785285)
			(xy 15.788941 -168.791385) (xy 15.842898 -168.805491) (xy 15.894227 -168.827303) (xy 15.941833 -168.856357)
			(xy 15.984701 -168.892032) (xy 16.021918 -168.933569) (xy 16.052691 -168.980082) (xy 16.076363 -169.030579)
			(xy 16.092431 -169.083986) (xy 16.100551 -169.139162) (xy 16.10106 -169.167048) (xy 16.100551 -169.194934)
			(xy 16.092431 -169.25011) (xy 16.076363 -169.303517) (xy 16.052691 -169.354014) (xy 16.021918 -169.400527)
			(xy 15.984701 -169.442064) (xy 15.941833 -169.477739) (xy 15.894227 -169.506793) (xy 15.842898 -169.528605)
			(xy 15.788941 -169.542711) (xy 15.733504 -169.548811) (xy 15.67777 -169.546774) (xy 15.622927 -169.536644)
			(xy 15.570143 -169.518637) (xy 15.520543 -169.493136) (xy 15.475185 -169.460685) (xy 15.435036 -169.421976)
			(xy 15.40095 -169.377833) (xy 15.373654 -169.329198) (xy 15.353731 -169.277107) (xy 15.341605 -169.22267)
			(xy 15.337534 -169.167048) (xy 3.45186 -169.167048) (xy 3.45186 -170.372532) (xy 14.663926 -170.372532)
			(xy 14.667997 -170.31691) (xy 14.680123 -170.262473) (xy 14.700046 -170.210382) (xy 14.727342 -170.161747)
			(xy 14.761428 -170.117604) (xy 14.801577 -170.078895) (xy 14.846935 -170.046444) (xy 14.896535 -170.020943)
			(xy 14.949319 -170.002936) (xy 15.004162 -169.992806) (xy 15.059896 -169.990769) (xy 15.115333 -169.996869)
			(xy 15.16929 -170.010975) (xy 15.220619 -170.032787) (xy 15.268225 -170.061841) (xy 15.311093 -170.097516)
			(xy 15.34831 -170.139053) (xy 15.379083 -170.185566) (xy 15.402755 -170.236063) (xy 15.418823 -170.28947)
			(xy 15.426943 -170.344646) (xy 15.427452 -170.372532) (xy 15.426943 -170.400418) (xy 15.418823 -170.455594)
			(xy 15.402755 -170.509001) (xy 15.379083 -170.559498) (xy 15.34831 -170.606011) (xy 15.311093 -170.647548)
			(xy 15.268225 -170.683223) (xy 15.220619 -170.712277) (xy 15.16929 -170.734089) (xy 15.115333 -170.748195)
			(xy 15.059896 -170.754295) (xy 15.004162 -170.752258) (xy 14.949319 -170.742128) (xy 14.896535 -170.724121)
			(xy 14.846935 -170.69862) (xy 14.801577 -170.666169) (xy 14.761428 -170.62746) (xy 14.727342 -170.583317)
			(xy 14.700046 -170.534682) (xy 14.680123 -170.482591) (xy 14.667997 -170.428154) (xy 14.663926 -170.372532)
			(xy 3.45186 -170.372532) (xy 3.45186 -171.533058) (xy 14.127478 -171.533058) (xy 14.131549 -171.477436)
			(xy 14.143675 -171.422999) (xy 14.163598 -171.370908) (xy 14.190894 -171.322273) (xy 14.22498 -171.27813)
			(xy 14.265129 -171.239421) (xy 14.310487 -171.20697) (xy 14.360087 -171.181469) (xy 14.412871 -171.163462)
			(xy 14.467714 -171.153332) (xy 14.523448 -171.151295) (xy 14.578885 -171.157395) (xy 14.632842 -171.171501)
			(xy 14.684171 -171.193313) (xy 14.731777 -171.222367) (xy 14.774645 -171.258042) (xy 14.811862 -171.299579)
			(xy 14.842635 -171.346092) (xy 14.866307 -171.396589) (xy 14.882375 -171.449996) (xy 14.890495 -171.505172)
			(xy 14.891004 -171.533058) (xy 14.890495 -171.560944) (xy 14.882375 -171.61612) (xy 14.866307 -171.669527)
			(xy 14.842635 -171.720024) (xy 14.811862 -171.766537) (xy 14.774645 -171.808074) (xy 14.731777 -171.843749)
			(xy 14.684171 -171.872803) (xy 14.632842 -171.894615) (xy 14.578885 -171.908721) (xy 14.523448 -171.914821)
			(xy 14.467714 -171.912784) (xy 14.412871 -171.902654) (xy 14.360087 -171.884647) (xy 14.310487 -171.859146)
			(xy 14.265129 -171.826695) (xy 14.22498 -171.787986) (xy 14.190894 -171.743843) (xy 14.163598 -171.695208)
			(xy 14.143675 -171.643117) (xy 14.131549 -171.58868) (xy 14.127478 -171.533058) (xy 3.45186 -171.533058)
			(xy 3.45186 -172.67174) (xy 13.456664 -172.67174) (xy 13.460735 -172.616118) (xy 13.472861 -172.561681)
			(xy 13.492784 -172.50959) (xy 13.52008 -172.460955) (xy 13.554166 -172.416812) (xy 13.594315 -172.378103)
			(xy 13.639673 -172.345652) (xy 13.689273 -172.320151) (xy 13.742057 -172.302144) (xy 13.7969 -172.292014)
			(xy 13.852634 -172.289977) (xy 13.908071 -172.296077) (xy 13.962028 -172.310183) (xy 14.013357 -172.331995)
			(xy 14.060963 -172.361049) (xy 14.103831 -172.396724) (xy 14.141048 -172.438261) (xy 14.171821 -172.484774)
			(xy 14.195493 -172.535271) (xy 14.211561 -172.588678) (xy 14.219681 -172.643854) (xy 14.22019 -172.67174)
			(xy 14.219681 -172.699626) (xy 14.211561 -172.754802) (xy 14.195493 -172.808209) (xy 14.171821 -172.858706)
			(xy 14.141048 -172.905219) (xy 14.103831 -172.946756) (xy 14.060963 -172.982431) (xy 14.013357 -173.011485)
			(xy 13.962028 -173.033297) (xy 13.908071 -173.047403) (xy 13.852634 -173.053503) (xy 13.7969 -173.051466)
			(xy 13.742057 -173.041336) (xy 13.689273 -173.023329) (xy 13.639673 -172.997828) (xy 13.594315 -172.965377)
			(xy 13.554166 -172.926668) (xy 13.52008 -172.882525) (xy 13.492784 -172.83389) (xy 13.472861 -172.781799)
			(xy 13.460735 -172.727362) (xy 13.456664 -172.67174) (xy 3.45186 -172.67174) (xy 3.45186 -176.870614)
			(xy 3.864362 -176.870614) (xy 3.868375 -176.7672) (xy 3.88039 -176.664407) (xy 3.900334 -176.562855)
			(xy 3.928088 -176.463153) (xy 3.963484 -176.365903) (xy 4.00631 -176.271687) (xy 4.056309 -176.181074)
			(xy 4.113179 -176.094607) (xy 4.176578 -176.012808) (xy 4.246126 -175.936167) (xy 4.321403 -175.865146)
			(xy 4.401958 -175.800173) (xy 4.487305 -175.741637) (xy 4.576932 -175.689891) (xy 4.6703 -175.645245)
			(xy 4.766846 -175.60797) (xy 4.86599 -175.578288) (xy 4.967137 -175.556378) (xy 5.069677 -175.542372)
			(xy 5.172994 -175.536355) (xy 5.276467 -175.538362) (xy 5.379473 -175.548381) (xy 5.481393 -175.566352)
			(xy 5.581614 -175.592167) (xy 5.679533 -175.625671) (xy 5.774561 -175.666663) (xy 5.866127 -175.714894)
			(xy 5.95368 -175.770077) (xy 6.036694 -175.831878) (xy 6.114668 -175.899927) (xy 6.187135 -175.973813)
			(xy 6.253659 -176.053092) (xy 6.313839 -176.137289) (xy 6.367313 -176.225895) (xy 6.41376 -176.318379)
			(xy 6.452901 -176.414185) (xy 6.4845 -176.512735) (xy 6.508367 -176.613438) (xy 6.524359 -176.715687)
			(xy 6.532378 -176.818868) (xy 6.53288 -176.870614) (xy 6.532378 -176.92236) (xy 6.524359 -177.025541)
			(xy 6.508367 -177.12779) (xy 6.4845 -177.228493) (xy 6.452901 -177.327043) (xy 6.41376 -177.422849)
			(xy 6.367313 -177.515333) (xy 6.313839 -177.603939) (xy 6.253659 -177.688136) (xy 6.187135 -177.767415)
			(xy 6.114668 -177.841301) (xy 6.036694 -177.90935) (xy 5.95368 -177.971151) (xy 5.866127 -178.026334)
			(xy 5.774561 -178.074565) (xy 5.679533 -178.115557) (xy 5.581614 -178.149061) (xy 5.481393 -178.174876)
			(xy 5.379473 -178.192847) (xy 5.276467 -178.202866) (xy 5.172994 -178.204873) (xy 5.069677 -178.198856)
			(xy 4.967137 -178.18485) (xy 4.86599 -178.16294) (xy 4.766846 -178.133258) (xy 4.6703 -178.095983)
			(xy 4.576932 -178.051337) (xy 4.487305 -177.999591) (xy 4.401958 -177.941055) (xy 4.321403 -177.876082)
			(xy 4.246126 -177.805061) (xy 4.176578 -177.72842) (xy 4.113179 -177.646621) (xy 4.056309 -177.560154)
			(xy 4.00631 -177.469541) (xy 3.963484 -177.375325) (xy 3.928088 -177.278075) (xy 3.900334 -177.178373)
			(xy 3.88039 -177.076821) (xy 3.868375 -176.974028) (xy 3.864362 -176.870614) (xy 3.45186 -176.870614)
			(xy 3.45186 -178.822858) (xy 3.453101 -178.845925) (xy 3.462888 -178.891067) (xy 3.480671 -178.933697)
			(xy 3.505864 -178.972412) (xy 3.537637 -179.005938) (xy 3.574944 -179.033172) (xy 3.616558 -179.053217)
			(xy 3.661109 -179.065413) (xy 3.707131 -179.069359) (xy 3.753108 -179.064925) (xy 3.775456 -179.059078)
			(xy 3.80937 -179.049943) (xy 3.878643 -179.038337) (xy 3.948773 -179.03444) (xy 4.018906 -179.0383)
			(xy 4.088185 -179.04987) (xy 4.155766 -179.069008) (xy 4.220825 -179.095482) (xy 4.282568 -179.128968)
			(xy 4.340242 -179.169058) (xy 4.393143 -179.215263) (xy 4.440627 -179.267019) (xy 4.482115 -179.323696)
			(xy 4.5171 -179.384602) (xy 4.545156 -179.448994) (xy 4.565941 -179.516087) (xy 4.579201 -179.585063)
			(xy 4.584774 -179.65508) (xy 4.582592 -179.725285) (xy 4.578096 -179.760118) (xy 4.573778 -179.79009)
			(xy 4.592828 -179.846732) (xy 4.829556 -180.08346) (xy 6.66242 -180.08346)
		)
		(stroke
			(width 0)
			(type solid)
		)
		(fill yes)
		(layer "F.Cu")
		(net "P12V")
	)
	(gr_poly
		(pts
			(xy 101.000052 -528.729956) (xy 101.038285 -528.729475) (xy 101.114333 -528.721487) (xy 101.189128 -528.705592)
			(xy 101.261853 -528.681966) (xy 101.331709 -528.650867) (xy 101.397931 -528.612636) (xy 101.459795 -528.567691)
			(xy 101.51662 -528.516526) (xy 101.567786 -528.459701) (xy 101.612731 -528.397838) (xy 101.650963 -528.331616)
			(xy 101.682063 -528.26176) (xy 101.70569 -528.189036) (xy 101.721586 -528.11424) (xy 101.729575 -528.038193)
			(xy 101.730048 -527.99996) (xy 101.730048 -343.432384) (xy 100.618544 -342.32088) (xy 100.618544 -171.459906)
			(xy 100.21824 -171.059602) (xy 100.21824 -17.168622) (xy 100.217772 -17.146268) (xy 100.209954 -17.102249)
			(xy 100.194555 -17.060277) (xy 100.172051 -17.021646) (xy 100.143135 -16.987548) (xy 100.108699 -16.959035)
			(xy 100.069806 -16.936986) (xy 100.027655 -16.922082) (xy 99.983547 -16.914783) (xy 99.938843 -16.915313)
			(xy 99.89492 -16.923656) (xy 99.853135 -16.939554) (xy 99.814775 -16.962518) (xy 99.797616 -16.976852)
			(xy 99.755215 -17.014836) (xy 99.665915 -17.085455) (xy 99.571894 -17.149655) (xy 99.473614 -17.207122)
			(xy 99.371555 -17.257574) (xy 99.266217 -17.300765) (xy 99.158117 -17.336483) (xy 99.047782 -17.364553)
			(xy 98.935755 -17.384837) (xy 98.822584 -17.397237) (xy 98.708823 -17.401691) (xy 98.595028 -17.398177)
			(xy 98.481758 -17.386713) (xy 98.369567 -17.367356) (xy 98.259005 -17.340199) (xy 98.150613 -17.305375)
			(xy 98.044922 -17.263057) (xy 97.942449 -17.213449) (xy 97.843697 -17.156796) (xy 97.749149 -17.093376)
			(xy 97.659268 -17.023497) (xy 97.574495 -16.947504) (xy 97.495244 -16.865768) (xy 97.421904 -16.778689)
			(xy 97.354834 -16.686694) (xy 97.294362 -16.590233) (xy 97.240785 -16.489779) (xy 97.194365 -16.385824)
			(xy 97.155329 -16.278877) (xy 97.123868 -16.169461) (xy 97.100138 -16.058113) (xy 97.084253 -15.945378)
			(xy 97.076291 -15.831808) (xy 97.076292 -15.71796) (xy 97.084256 -15.60439) (xy 97.100143 -15.491655)
			(xy 97.123876 -15.380308) (xy 97.155339 -15.270893) (xy 97.194377 -15.163946) (xy 97.240799 -15.059992)
			(xy 97.294378 -14.959539) (xy 97.354852 -14.86308) (xy 97.421924 -14.771086) (xy 97.495266 -14.684008)
			(xy 97.574518 -14.602274) (xy 97.659293 -14.526282) (xy 97.749175 -14.456405) (xy 97.843725 -14.392987)
			(xy 97.942478 -14.336336) (xy 98.044951 -14.28673) (xy 98.150643 -14.244414) (xy 98.259036 -14.209592)
			(xy 98.369599 -14.182438) (xy 98.48179 -14.163082) (xy 98.59506 -14.151621) (xy 98.708855 -14.148109)
			(xy 98.822616 -14.152566) (xy 98.935787 -14.164967) (xy 99.047814 -14.185254) (xy 99.158148 -14.213326)
			(xy 99.266247 -14.249046) (xy 99.371584 -14.292239) (xy 99.473642 -14.342694) (xy 99.571922 -14.400162)
			(xy 99.665941 -14.464364) (xy 99.75524 -14.534985) (xy 99.797616 -14.572996) (xy 99.814795 -14.587302)
			(xy 99.853146 -14.610267) (xy 99.894924 -14.626166) (xy 99.938839 -14.63451) (xy 99.983537 -14.635041)
			(xy 100.027639 -14.627743) (xy 100.069783 -14.61284) (xy 100.108669 -14.590793) (xy 100.143097 -14.562282)
			(xy 100.172005 -14.528187) (xy 100.194501 -14.489559) (xy 100.209891 -14.447591) (xy 100.2177 -14.403577)
			(xy 100.21824 -14.381226) (xy 100.21824 -8.60933) (xy 94.035118 -2.426208) (xy 28.730448 -2.426208)
			(xy 28.232354 -2.924302) (xy 28.232354 -4.633484) (xy 29.519874 -4.633484) (xy 29.519874 -4.546584)
			(xy 29.527892 -4.460055) (xy 29.54386 -4.374635) (xy 29.567641 -4.291053) (xy 29.599033 -4.210021)
			(xy 29.637767 -4.132232) (xy 29.683514 -4.058348) (xy 29.735883 -3.989001) (xy 29.794427 -3.924781)
			(xy 29.858647 -3.866237) (xy 29.927994 -3.813868) (xy 30.001878 -3.768121) (xy 30.079667 -3.729387)
			(xy 30.160699 -3.697995) (xy 30.244281 -3.674214) (xy 30.329701 -3.658246) (xy 30.41623 -3.650228)
			(xy 30.50313 -3.650228) (xy 30.589659 -3.658246) (xy 30.675079 -3.674214) (xy 30.758661 -3.697995)
			(xy 30.839693 -3.729387) (xy 30.917482 -3.768121) (xy 30.991366 -3.813868) (xy 31.060713 -3.866237)
			(xy 31.124933 -3.924781) (xy 31.183477 -3.989001) (xy 31.235846 -4.058348) (xy 31.281593 -4.132232)
			(xy 31.320327 -4.210021) (xy 31.351719 -4.291053) (xy 31.3755 -4.374635) (xy 31.391468 -4.460055)
			(xy 31.399486 -4.546584) (xy 31.399988 -4.590034) (xy 31.399486 -4.633484) (xy 34.599874 -4.633484)
			(xy 34.599874 -4.546584) (xy 34.607892 -4.460055) (xy 34.62386 -4.374635) (xy 34.647641 -4.291053)
			(xy 34.679033 -4.210021) (xy 34.717767 -4.132232) (xy 34.763514 -4.058348) (xy 34.815883 -3.989001)
			(xy 34.874427 -3.924781) (xy 34.938647 -3.866237) (xy 35.007994 -3.813868) (xy 35.081878 -3.768121)
			(xy 35.159667 -3.729387) (xy 35.240699 -3.697995) (xy 35.324281 -3.674214) (xy 35.409701 -3.658246)
			(xy 35.49623 -3.650228) (xy 35.58313 -3.650228) (xy 35.669659 -3.658246) (xy 35.755079 -3.674214)
			(xy 35.838661 -3.697995) (xy 35.919693 -3.729387) (xy 35.997482 -3.768121) (xy 36.071366 -3.813868)
			(xy 36.140713 -3.866237) (xy 36.204933 -3.924781) (xy 36.263477 -3.989001) (xy 36.315846 -4.058348)
			(xy 36.361593 -4.132232) (xy 36.400327 -4.210021) (xy 36.431719 -4.291053) (xy 36.4555 -4.374635)
			(xy 36.471468 -4.460055) (xy 36.479486 -4.546584) (xy 36.479988 -4.590034) (xy 36.479486 -4.633484)
			(xy 36.471468 -4.720013) (xy 36.4555 -4.805433) (xy 36.431719 -4.889015) (xy 36.400327 -4.970047)
			(xy 36.361593 -5.047836) (xy 36.315846 -5.12172) (xy 36.263477 -5.191067) (xy 36.204933 -5.255287)
			(xy 36.140713 -5.313831) (xy 36.071366 -5.3662) (xy 35.997482 -5.411947) (xy 35.919693 -5.450681)
			(xy 35.838661 -5.482073) (xy 35.755079 -5.505854) (xy 35.669659 -5.521822) (xy 35.58313 -5.52984)
			(xy 35.49623 -5.52984) (xy 35.409701 -5.521822) (xy 35.324281 -5.505854) (xy 35.240699 -5.482073)
			(xy 35.159667 -5.450681) (xy 35.081878 -5.411947) (xy 35.007994 -5.3662) (xy 34.938647 -5.313831)
			(xy 34.874427 -5.255287) (xy 34.815883 -5.191067) (xy 34.763514 -5.12172) (xy 34.717767 -5.047836)
			(xy 34.679033 -4.970047) (xy 34.647641 -4.889015) (xy 34.62386 -4.805433) (xy 34.607892 -4.720013)
			(xy 34.599874 -4.633484) (xy 31.399486 -4.633484) (xy 31.391468 -4.720013) (xy 31.3755 -4.805433)
			(xy 31.351719 -4.889015) (xy 31.320327 -4.970047) (xy 31.281593 -5.047836) (xy 31.235846 -5.12172)
			(xy 31.183477 -5.191067) (xy 31.124933 -5.255287) (xy 31.060713 -5.313831) (xy 30.991366 -5.3662)
			(xy 30.917482 -5.411947) (xy 30.839693 -5.450681) (xy 30.758661 -5.482073) (xy 30.675079 -5.505854)
			(xy 30.589659 -5.521822) (xy 30.50313 -5.52984) (xy 30.41623 -5.52984) (xy 30.329701 -5.521822) (xy 30.244281 -5.505854)
			(xy 30.160699 -5.482073) (xy 30.079667 -5.450681) (xy 30.001878 -5.411947) (xy 29.927994 -5.3662)
			(xy 29.858647 -5.313831) (xy 29.794427 -5.255287) (xy 29.735883 -5.191067) (xy 29.683514 -5.12172)
			(xy 29.637767 -5.047836) (xy 29.599033 -4.970047) (xy 29.567641 -4.889015) (xy 29.54386 -4.805433)
			(xy 29.527892 -4.720013) (xy 29.519874 -4.633484) (xy 28.232354 -4.633484) (xy 28.232354 -6.44398)
			(xy 28.550616 -6.762242) (xy 28.562745 -6.773639) (xy 28.591528 -6.790324) (xy 28.623645 -6.799003)
			(xy 28.640278 -6.79958) (xy 29.532326 -6.79958) (xy 29.594302 -6.76021) (xy 29.61005 -6.726936) (xy 29.629123 -6.68785)
			(xy 29.673486 -6.613036) (xy 29.724568 -6.542639) (xy 29.781932 -6.47726) (xy 29.84509 -6.417457)
			(xy 29.913499 -6.363743) (xy 29.986578 -6.316576) (xy 30.063699 -6.276359) (xy 30.144205 -6.243436)
			(xy 30.227407 -6.218088) (xy 30.312595 -6.200532) (xy 30.39904 -6.190919) (xy 30.486003 -6.189329)
			(xy 30.572742 -6.195777) (xy 30.658514 -6.210207) (xy 30.742587 -6.232497) (xy 30.824243 -6.262455)
			(xy 30.902783 -6.299827) (xy 30.977536 -6.344291) (xy 31.047863 -6.395469) (xy 31.113164 -6.452923)
			(xy 31.17288 -6.516162) (xy 31.226501 -6.584645) (xy 31.273568 -6.657787) (xy 31.31368 -6.734963)
			(xy 31.346493 -6.815514) (xy 31.371728 -6.898751) (xy 31.389167 -6.983962) (xy 31.398663 -7.07042)
			(xy 31.400135 -7.157386) (xy 31.398916 -7.173484) (xy 34.599874 -7.173484) (xy 34.599874 -7.086584)
			(xy 34.607892 -7.000055) (xy 34.62386 -6.914635) (xy 34.647641 -6.831053) (xy 34.679033 -6.750021)
			(xy 34.717767 -6.672232) (xy 34.763514 -6.598348) (xy 34.815883 -6.529001) (xy 34.874427 -6.464781)
			(xy 34.938647 -6.406237) (xy 35.007994 -6.353868) (xy 35.081878 -6.308121) (xy 35.159667 -6.269387)
			(xy 35.240699 -6.237995) (xy 35.324281 -6.214214) (xy 35.409701 -6.198246) (xy 35.49623 -6.190228)
			(xy 35.58313 -6.190228) (xy 35.669659 -6.198246) (xy 35.755079 -6.214214) (xy 35.838661 -6.237995)
			(xy 35.919693 -6.269387) (xy 35.997482 -6.308121) (xy 36.071366 -6.353868) (xy 36.140713 -6.406237)
			(xy 36.204933 -6.464781) (xy 36.263477 -6.529001) (xy 36.315846 -6.598348) (xy 36.361593 -6.672232)
			(xy 36.400327 -6.750021) (xy 36.431719 -6.831053) (xy 36.454201 -6.91007) (xy 39.818063 -6.91007)
			(xy 39.82207 -6.794046) (xy 39.834072 -6.678574) (xy 39.854012 -6.564206) (xy 39.881795 -6.451486)
			(xy 39.917289 -6.340952) (xy 39.960324 -6.233129) (xy 40.010695 -6.128532) (xy 40.068162 -6.02766)
			(xy 40.132452 -5.930993) (xy 40.203257 -5.838992) (xy 40.280241 -5.752095) (xy 40.363037 -5.670716)
			(xy 40.45125 -5.595243) (xy 40.54446 -5.526036) (xy 40.642223 -5.463424) (xy 40.744072 -5.407707)
			(xy 40.849522 -5.359149) (xy 40.958071 -5.317981) (xy 41.069202 -5.284401) (xy 41.182385 -5.258568)
			(xy 41.29708 -5.240605) (xy 41.412742 -5.230597) (xy 41.528818 -5.228594) (xy 41.644756 -5.234603)
			(xy 41.760003 -5.248596) (xy 41.874009 -5.270507) (xy 41.986233 -5.300232) (xy 42.096139 -5.337628)
			(xy 42.203202 -5.382517) (xy 42.306914 -5.434686) (xy 42.406779 -5.493886) (xy 42.502322 -5.559835)
			(xy 42.502604 -5.56006) (xy 43.327577 -5.56006) (xy 43.331612 -5.484356) (xy 43.343671 -5.409511)
			(xy 43.363617 -5.33637) (xy 43.391224 -5.265765) (xy 43.42618 -5.198494) (xy 43.468088 -5.135319)
			(xy 43.516474 -5.076957) (xy 43.57079 -5.024069) (xy 43.630419 -4.977254) (xy 43.694687 -4.937042)
			(xy 43.762864 -4.90389) (xy 43.83418 -4.878172) (xy 43.907825 -4.86018) (xy 43.982965 -4.850118)
			(xy 44.058749 -4.848099) (xy 44.134319 -4.854148) (xy 44.208817 -4.868195) (xy 44.2814 -4.890081)
			(xy 44.351246 -4.919558) (xy 44.417563 -4.956293) (xy 44.479599 -4.999868) (xy 44.536652 -5.04979)
			(xy 44.588076 -5.105494) (xy 44.633287 -5.166349) (xy 44.671774 -5.231664) (xy 44.7031 -5.3007) (xy 44.72691 -5.372675)
			(xy 44.742935 -5.446773) (xy 44.750994 -5.522154) (xy 44.751498 -5.56006) (xy 45.867577 -5.56006)
			(xy 45.871612 -5.484356) (xy 45.883671 -5.409511) (xy 45.903617 -5.33637) (xy 45.931224 -5.265765)
			(xy 45.96618 -5.198494) (xy 46.008088 -5.135319) (xy 46.056474 -5.076957) (xy 46.11079 -5.024069)
			(xy 46.170419 -4.977254) (xy 46.234687 -4.937042) (xy 46.302864 -4.90389) (xy 46.37418 -4.878172)
			(xy 46.447825 -4.86018) (xy 46.522965 -4.850118) (xy 46.598749 -4.848099) (xy 46.674319 -4.854148)
			(xy 46.748817 -4.868195) (xy 46.8214 -4.890081) (xy 46.891246 -4.919558) (xy 46.957563 -4.956293)
			(xy 47.019599 -4.999868) (xy 47.076652 -5.04979) (xy 47.128076 -5.105494) (xy 47.173287 -5.166349)
			(xy 47.211774 -5.231664) (xy 47.2431 -5.3007) (xy 47.26691 -5.372675) (xy 47.282935 -5.446773) (xy 47.290994 -5.522154)
			(xy 47.291498 -5.56006) (xy 48.407577 -5.56006) (xy 48.411612 -5.484356) (xy 48.423671 -5.409511)
			(xy 48.443617 -5.33637) (xy 48.471224 -5.265765) (xy 48.50618 -5.198494) (xy 48.548088 -5.135319)
			(xy 48.596474 -5.076957) (xy 48.65079 -5.024069) (xy 48.710419 -4.977254) (xy 48.774687 -4.937042)
			(xy 48.842864 -4.90389) (xy 48.91418 -4.878172) (xy 48.987825 -4.86018) (xy 49.062965 -4.850118)
			(xy 49.138749 -4.848099) (xy 49.214319 -4.854148) (xy 49.288817 -4.868195) (xy 49.3614 -4.890081)
			(xy 49.431246 -4.919558) (xy 49.497563 -4.956293) (xy 49.559599 -4.999868) (xy 49.616652 -5.04979)
			(xy 49.668076 -5.105494) (xy 49.713287 -5.166349) (xy 49.751774 -5.231664) (xy 49.7831 -5.3007) (xy 49.80691 -5.372675)
			(xy 49.822935 -5.446773) (xy 49.830994 -5.522154) (xy 49.831498 -5.56006) (xy 50.947577 -5.56006)
			(xy 50.951612 -5.484356) (xy 50.963671 -5.409511) (xy 50.983617 -5.33637) (xy 51.011224 -5.265765)
			(xy 51.04618 -5.198494) (xy 51.088088 -5.135319) (xy 51.136474 -5.076957) (xy 51.19079 -5.024069)
			(xy 51.250419 -4.977254) (xy 51.314687 -4.937042) (xy 51.382864 -4.90389) (xy 51.45418 -4.878172)
			(xy 51.527825 -4.86018) (xy 51.602965 -4.850118) (xy 51.678749 -4.848099) (xy 51.754319 -4.854148)
			(xy 51.828817 -4.868195) (xy 51.9014 -4.890081) (xy 51.971246 -4.919558) (xy 52.037563 -4.956293)
			(xy 52.099599 -4.999868) (xy 52.156652 -5.04979) (xy 52.208076 -5.105494) (xy 52.253287 -5.166349)
			(xy 52.291774 -5.231664) (xy 52.3231 -5.3007) (xy 52.34691 -5.372675) (xy 52.362935 -5.446773) (xy 52.370994 -5.522154)
			(xy 52.371498 -5.56006) (xy 53.487577 -5.56006) (xy 53.491612 -5.484356) (xy 53.503671 -5.409511)
			(xy 53.523617 -5.33637) (xy 53.551224 -5.265765) (xy 53.58618 -5.198494) (xy 53.628088 -5.135319)
			(xy 53.676474 -5.076957) (xy 53.73079 -5.024069) (xy 53.790419 -4.977254) (xy 53.854687 -4.937042)
			(xy 53.922864 -4.90389) (xy 53.99418 -4.878172) (xy 54.067825 -4.86018) (xy 54.142965 -4.850118)
			(xy 54.218749 -4.848099) (xy 54.294319 -4.854148) (xy 54.368817 -4.868195) (xy 54.4414 -4.890081)
			(xy 54.511246 -4.919558) (xy 54.577563 -4.956293) (xy 54.639599 -4.999868) (xy 54.696652 -5.04979)
			(xy 54.748076 -5.105494) (xy 54.793287 -5.166349) (xy 54.831774 -5.231664) (xy 54.8631 -5.3007) (xy 54.88691 -5.372675)
			(xy 54.902935 -5.446773) (xy 54.910994 -5.522154) (xy 54.911498 -5.56006) (xy 56.027577 -5.56006)
			(xy 56.031612 -5.484356) (xy 56.043671 -5.409511) (xy 56.063617 -5.33637) (xy 56.091224 -5.265765)
			(xy 56.12618 -5.198494) (xy 56.168088 -5.135319) (xy 56.216474 -5.076957) (xy 56.27079 -5.024069)
			(xy 56.330419 -4.977254) (xy 56.394687 -4.937042) (xy 56.462864 -4.90389) (xy 56.53418 -4.878172)
			(xy 56.607825 -4.86018) (xy 56.682965 -4.850118) (xy 56.758749 -4.848099) (xy 56.834319 -4.854148)
			(xy 56.908817 -4.868195) (xy 56.9814 -4.890081) (xy 57.051246 -4.919558) (xy 57.117563 -4.956293)
			(xy 57.179599 -4.999868) (xy 57.236652 -5.04979) (xy 57.288076 -5.105494) (xy 57.333287 -5.166349)
			(xy 57.371774 -5.231664) (xy 57.4031 -5.3007) (xy 57.42691 -5.372675) (xy 57.442935 -5.446773) (xy 57.450994 -5.522154)
			(xy 57.451498 -5.56006) (xy 58.567577 -5.56006) (xy 58.571612 -5.484356) (xy 58.583671 -5.409511)
			(xy 58.603617 -5.33637) (xy 58.631224 -5.265765) (xy 58.66618 -5.198494) (xy 58.708088 -5.135319)
			(xy 58.756474 -5.076957) (xy 58.81079 -5.024069) (xy 58.870419 -4.977254) (xy 58.934687 -4.937042)
			(xy 59.002864 -4.90389) (xy 59.07418 -4.878172) (xy 59.147825 -4.86018) (xy 59.222965 -4.850118)
			(xy 59.298749 -4.848099) (xy 59.374319 -4.854148) (xy 59.448817 -4.868195) (xy 59.5214 -4.890081)
			(xy 59.591246 -4.919558) (xy 59.657563 -4.956293) (xy 59.719599 -4.999868) (xy 59.776652 -5.04979)
			(xy 59.828076 -5.105494) (xy 59.873287 -5.166349) (xy 59.911774 -5.231664) (xy 59.9431 -5.3007) (xy 59.96691 -5.372675)
			(xy 59.982935 -5.446773) (xy 59.990994 -5.522154) (xy 59.991498 -5.56006) (xy 61.107577 -5.56006)
			(xy 61.111612 -5.484356) (xy 61.123671 -5.409511) (xy 61.143617 -5.33637) (xy 61.171224 -5.265765)
			(xy 61.20618 -5.198494) (xy 61.248088 -5.135319) (xy 61.296474 -5.076957) (xy 61.35079 -5.024069)
			(xy 61.410419 -4.977254) (xy 61.474687 -4.937042) (xy 61.542864 -4.90389) (xy 61.61418 -4.878172)
			(xy 61.687825 -4.86018) (xy 61.762965 -4.850118) (xy 61.838749 -4.848099) (xy 61.914319 -4.854148)
			(xy 61.988817 -4.868195) (xy 62.0614 -4.890081) (xy 62.131246 -4.919558) (xy 62.197563 -4.956293)
			(xy 62.259599 -4.999868) (xy 62.265544 -5.00507) (xy 86.197697 -5.00507) (xy 86.201732 -4.929366)
			(xy 86.213791 -4.854521) (xy 86.233737 -4.78138) (xy 86.261344 -4.710775) (xy 86.2963 -4.643504)
			(xy 86.338208 -4.580329) (xy 86.386594 -4.521967) (xy 86.44091 -4.469079) (xy 86.500539 -4.422264)
			(xy 86.564807 -4.382052) (xy 86.632984 -4.3489) (xy 86.7043 -4.323182) (xy 86.777945 -4.30519) (xy 86.853085 -4.295128)
			(xy 86.928869 -4.293109) (xy 87.004439 -4.299158) (xy 87.078937 -4.313205) (xy 87.15152 -4.335091)
			(xy 87.221366 -4.364568) (xy 87.287683 -4.401303) (xy 87.349719 -4.444878) (xy 87.406772 -4.4948)
			(xy 87.458196 -4.550504) (xy 87.503407 -4.611359) (xy 87.541894 -4.676674) (xy 87.57322 -4.74571)
			(xy 87.59703 -4.817685) (xy 87.613055 -4.891783) (xy 87.621114 -4.967164) (xy 87.621618 -5.00507)
			(xy 88.737697 -5.00507) (xy 88.741732 -4.929366) (xy 88.753791 -4.854521) (xy 88.773737 -4.78138)
			(xy 88.801344 -4.710775) (xy 88.8363 -4.643504) (xy 88.878208 -4.580329) (xy 88.926594 -4.521967)
			(xy 88.98091 -4.469079) (xy 89.040539 -4.422264) (xy 89.104807 -4.382052) (xy 89.172984 -4.3489)
			(xy 89.2443 -4.323182) (xy 89.317945 -4.30519) (xy 89.393085 -4.295128) (xy 89.468869 -4.293109)
			(xy 89.544439 -4.299158) (xy 89.618937 -4.313205) (xy 89.69152 -4.335091) (xy 89.761366 -4.364568)
			(xy 89.827683 -4.401303) (xy 89.889719 -4.444878) (xy 89.946772 -4.4948) (xy 89.998196 -4.550504)
			(xy 90.043407 -4.611359) (xy 90.081894 -4.676674) (xy 90.11322 -4.74571) (xy 90.13703 -4.817685)
			(xy 90.153055 -4.891783) (xy 90.161114 -4.967164) (xy 90.161618 -5.00507) (xy 91.277697 -5.00507)
			(xy 91.281732 -4.929366) (xy 91.293791 -4.854521) (xy 91.313737 -4.78138) (xy 91.341344 -4.710775)
			(xy 91.3763 -4.643504) (xy 91.418208 -4.580329) (xy 91.466594 -4.521967) (xy 91.52091 -4.469079)
			(xy 91.580539 -4.422264) (xy 91.644807 -4.382052) (xy 91.712984 -4.3489) (xy 91.7843 -4.323182) (xy 91.857945 -4.30519)
			(xy 91.933085 -4.295128) (xy 92.008869 -4.293109) (xy 92.084439 -4.299158) (xy 92.158937 -4.313205)
			(xy 92.23152 -4.335091) (xy 92.301366 -4.364568) (xy 92.367683 -4.401303) (xy 92.429719 -4.444878)
			(xy 92.486772 -4.4948) (xy 92.538196 -4.550504) (xy 92.583407 -4.611359) (xy 92.621894 -4.676674)
			(xy 92.65322 -4.74571) (xy 92.67703 -4.817685) (xy 92.693055 -4.891783) (xy 92.701114 -4.967164)
			(xy 92.701618 -5.00507) (xy 92.701114 -5.042976) (xy 92.693055 -5.118357) (xy 92.67703 -5.192455)
			(xy 92.65322 -5.26443) (xy 92.621894 -5.333466) (xy 92.583407 -5.398781) (xy 92.538196 -5.459636)
			(xy 92.486772 -5.51534) (xy 92.429719 -5.565262) (xy 92.367683 -5.608837) (xy 92.301366 -5.645572)
			(xy 92.23152 -5.675049) (xy 92.158937 -5.696935) (xy 92.084439 -5.710982) (xy 92.008869 -5.717031)
			(xy 91.933085 -5.715012) (xy 91.857945 -5.70495) (xy 91.7843 -5.686958) (xy 91.712984 -5.66124) (xy 91.644807 -5.628088)
			(xy 91.580539 -5.587876) (xy 91.52091 -5.541061) (xy 91.466594 -5.488173) (xy 91.418208 -5.429811)
			(xy 91.3763 -5.366636) (xy 91.341344 -5.299365) (xy 91.313737 -5.22876) (xy 91.293791 -5.155619)
			(xy 91.281732 -5.080774) (xy 91.277697 -5.00507) (xy 90.161618 -5.00507) (xy 90.161114 -5.042976)
			(xy 90.153055 -5.118357) (xy 90.13703 -5.192455) (xy 90.11322 -5.26443) (xy 90.081894 -5.333466)
			(xy 90.043407 -5.398781) (xy 89.998196 -5.459636) (xy 89.946772 -5.51534) (xy 89.889719 -5.565262)
			(xy 89.827683 -5.608837) (xy 89.761366 -5.645572) (xy 89.69152 -5.675049) (xy 89.618937 -5.696935)
			(xy 89.544439 -5.710982) (xy 89.468869 -5.717031) (xy 89.393085 -5.715012) (xy 89.317945 -5.70495)
			(xy 89.2443 -5.686958) (xy 89.172984 -5.66124) (xy 89.104807 -5.628088) (xy 89.040539 -5.587876)
			(xy 88.98091 -5.541061) (xy 88.926594 -5.488173) (xy 88.878208 -5.429811) (xy 88.8363 -5.366636)
			(xy 88.801344 -5.299365) (xy 88.773737 -5.22876) (xy 88.753791 -5.155619) (xy 88.741732 -5.080774)
			(xy 88.737697 -5.00507) (xy 87.621618 -5.00507) (xy 87.621114 -5.042976) (xy 87.613055 -5.118357)
			(xy 87.59703 -5.192455) (xy 87.57322 -5.26443) (xy 87.541894 -5.333466) (xy 87.503407 -5.398781)
			(xy 87.458196 -5.459636) (xy 87.406772 -5.51534) (xy 87.349719 -5.565262) (xy 87.287683 -5.608837)
			(xy 87.221366 -5.645572) (xy 87.15152 -5.675049) (xy 87.078937 -5.696935) (xy 87.004439 -5.710982)
			(xy 86.928869 -5.717031) (xy 86.853085 -5.715012) (xy 86.777945 -5.70495) (xy 86.7043 -5.686958)
			(xy 86.632984 -5.66124) (xy 86.564807 -5.628088) (xy 86.500539 -5.587876) (xy 86.44091 -5.541061)
			(xy 86.386594 -5.488173) (xy 86.338208 -5.429811) (xy 86.2963 -5.366636) (xy 86.261344 -5.299365)
			(xy 86.233737 -5.22876) (xy 86.213791 -5.155619) (xy 86.201732 -5.080774) (xy 86.197697 -5.00507)
			(xy 62.265544 -5.00507) (xy 62.316652 -5.04979) (xy 62.368076 -5.105494) (xy 62.413287 -5.166349)
			(xy 62.451774 -5.231664) (xy 62.4831 -5.3007) (xy 62.50691 -5.372675) (xy 62.522935 -5.446773) (xy 62.530994 -5.522154)
			(xy 62.531498 -5.56006) (xy 62.530994 -5.597966) (xy 62.522935 -5.673347) (xy 62.50691 -5.747445)
			(xy 62.4831 -5.81942) (xy 62.451774 -5.888456) (xy 62.413287 -5.953771) (xy 62.368076 -6.014626)
			(xy 62.316652 -6.07033) (xy 62.259599 -6.120252) (xy 62.197563 -6.163827) (xy 62.131246 -6.200562)
			(xy 62.0614 -6.230039) (xy 61.988817 -6.251925) (xy 61.914319 -6.265972) (xy 61.838749 -6.272021)
			(xy 61.762965 -6.270002) (xy 61.687825 -6.25994) (xy 61.61418 -6.241948) (xy 61.542864 -6.21623)
			(xy 61.474687 -6.183078) (xy 61.410419 -6.142866) (xy 61.35079 -6.096051) (xy 61.296474 -6.043163)
			(xy 61.248088 -5.984801) (xy 61.20618 -5.921626) (xy 61.171224 -5.854355) (xy 61.143617 -5.78375)
			(xy 61.123671 -5.710609) (xy 61.111612 -5.635764) (xy 61.107577 -5.56006) (xy 59.991498 -5.56006)
			(xy 59.990994 -5.597966) (xy 59.982935 -5.673347) (xy 59.96691 -5.747445) (xy 59.9431 -5.81942) (xy 59.911774 -5.888456)
			(xy 59.873287 -5.953771) (xy 59.828076 -6.014626) (xy 59.776652 -6.07033) (xy 59.719599 -6.120252)
			(xy 59.657563 -6.163827) (xy 59.591246 -6.200562) (xy 59.5214 -6.230039) (xy 59.448817 -6.251925)
			(xy 59.374319 -6.265972) (xy 59.298749 -6.272021) (xy 59.222965 -6.270002) (xy 59.147825 -6.25994)
			(xy 59.07418 -6.241948) (xy 59.002864 -6.21623) (xy 58.934687 -6.183078) (xy 58.870419 -6.142866)
			(xy 58.81079 -6.096051) (xy 58.756474 -6.043163) (xy 58.708088 -5.984801) (xy 58.66618 -5.921626)
			(xy 58.631224 -5.854355) (xy 58.603617 -5.78375) (xy 58.583671 -5.710609) (xy 58.571612 -5.635764)
			(xy 58.567577 -5.56006) (xy 57.451498 -5.56006) (xy 57.450994 -5.597966) (xy 57.442935 -5.673347)
			(xy 57.42691 -5.747445) (xy 57.4031 -5.81942) (xy 57.371774 -5.888456) (xy 57.333287 -5.953771) (xy 57.288076 -6.014626)
			(xy 57.236652 -6.07033) (xy 57.179599 -6.120252) (xy 57.117563 -6.163827) (xy 57.051246 -6.200562)
			(xy 56.9814 -6.230039) (xy 56.908817 -6.251925) (xy 56.834319 -6.265972) (xy 56.758749 -6.272021)
			(xy 56.682965 -6.270002) (xy 56.607825 -6.25994) (xy 56.53418 -6.241948) (xy 56.462864 -6.21623)
			(xy 56.394687 -6.183078) (xy 56.330419 -6.142866) (xy 56.27079 -6.096051) (xy 56.216474 -6.043163)
			(xy 56.168088 -5.984801) (xy 56.12618 -5.921626) (xy 56.091224 -5.854355) (xy 56.063617 -5.78375)
			(xy 56.043671 -5.710609) (xy 56.031612 -5.635764) (xy 56.027577 -5.56006) (xy 54.911498 -5.56006)
			(xy 54.910994 -5.597966) (xy 54.902935 -5.673347) (xy 54.88691 -5.747445) (xy 54.8631 -5.81942) (xy 54.831774 -5.888456)
			(xy 54.793287 -5.953771) (xy 54.748076 -6.014626) (xy 54.696652 -6.07033) (xy 54.639599 -6.120252)
			(xy 54.577563 -6.163827) (xy 54.511246 -6.200562) (xy 54.4414 -6.230039) (xy 54.368817 -6.251925)
			(xy 54.294319 -6.265972) (xy 54.218749 -6.272021) (xy 54.142965 -6.270002) (xy 54.067825 -6.25994)
			(xy 53.99418 -6.241948) (xy 53.922864 -6.21623) (xy 53.854687 -6.183078) (xy 53.790419 -6.142866)
			(xy 53.73079 -6.096051) (xy 53.676474 -6.043163) (xy 53.628088 -5.984801) (xy 53.58618 -5.921626)
			(xy 53.551224 -5.854355) (xy 53.523617 -5.78375) (xy 53.503671 -5.710609) (xy 53.491612 -5.635764)
			(xy 53.487577 -5.56006) (xy 52.371498 -5.56006) (xy 52.370994 -5.597966) (xy 52.362935 -5.673347)
			(xy 52.34691 -5.747445) (xy 52.3231 -5.81942) (xy 52.291774 -5.888456) (xy 52.253287 -5.953771) (xy 52.208076 -6.014626)
			(xy 52.156652 -6.07033) (xy 52.099599 -6.120252) (xy 52.037563 -6.163827) (xy 51.971246 -6.200562)
			(xy 51.9014 -6.230039) (xy 51.828817 -6.251925) (xy 51.754319 -6.265972) (xy 51.678749 -6.272021)
			(xy 51.602965 -6.270002) (xy 51.527825 -6.25994) (xy 51.45418 -6.241948) (xy 51.382864 -6.21623)
			(xy 51.314687 -6.183078) (xy 51.250419 -6.142866) (xy 51.19079 -6.096051) (xy 51.136474 -6.043163)
			(xy 51.088088 -5.984801) (xy 51.04618 -5.921626) (xy 51.011224 -5.854355) (xy 50.983617 -5.78375)
			(xy 50.963671 -5.710609) (xy 50.951612 -5.635764) (xy 50.947577 -5.56006) (xy 49.831498 -5.56006)
			(xy 49.830994 -5.597966) (xy 49.822935 -5.673347) (xy 49.80691 -5.747445) (xy 49.7831 -5.81942) (xy 49.751774 -5.888456)
			(xy 49.713287 -5.953771) (xy 49.668076 -6.014626) (xy 49.616652 -6.07033) (xy 49.559599 -6.120252)
			(xy 49.497563 -6.163827) (xy 49.431246 -6.200562) (xy 49.3614 -6.230039) (xy 49.288817 -6.251925)
			(xy 49.214319 -6.265972) (xy 49.138749 -6.272021) (xy 49.062965 -6.270002) (xy 48.987825 -6.25994)
			(xy 48.91418 -6.241948) (xy 48.842864 -6.21623) (xy 48.774687 -6.183078) (xy 48.710419 -6.142866)
			(xy 48.65079 -6.096051) (xy 48.596474 -6.043163) (xy 48.548088 -5.984801) (xy 48.50618 -5.921626)
			(xy 48.471224 -5.854355) (xy 48.443617 -5.78375) (xy 48.423671 -5.710609) (xy 48.411612 -5.635764)
			(xy 48.407577 -5.56006) (xy 47.291498 -5.56006) (xy 47.290994 -5.597966) (xy 47.282935 -5.673347)
			(xy 47.26691 -5.747445) (xy 47.2431 -5.81942) (xy 47.211774 -5.888456) (xy 47.173287 -5.953771) (xy 47.128076 -6.014626)
			(xy 47.076652 -6.07033) (xy 47.019599 -6.120252) (xy 46.957563 -6.163827) (xy 46.891246 -6.200562)
			(xy 46.8214 -6.230039) (xy 46.748817 -6.251925) (xy 46.674319 -6.265972) (xy 46.598749 -6.272021)
			(xy 46.522965 -6.270002) (xy 46.447825 -6.25994) (xy 46.37418 -6.241948) (xy 46.302864 -6.21623)
			(xy 46.234687 -6.183078) (xy 46.170419 -6.142866) (xy 46.11079 -6.096051) (xy 46.056474 -6.043163)
			(xy 46.008088 -5.984801) (xy 45.96618 -5.921626) (xy 45.931224 -5.854355) (xy 45.903617 -5.78375)
			(xy 45.883671 -5.710609) (xy 45.871612 -5.635764) (xy 45.867577 -5.56006) (xy 44.751498 -5.56006)
			(xy 44.750994 -5.597966) (xy 44.742935 -5.673347) (xy 44.72691 -5.747445) (xy 44.7031 -5.81942) (xy 44.671774 -5.888456)
			(xy 44.633287 -5.953771) (xy 44.588076 -6.014626) (xy 44.536652 -6.07033) (xy 44.479599 -6.120252)
			(xy 44.417563 -6.163827) (xy 44.351246 -6.200562) (xy 44.2814 -6.230039) (xy 44.208817 -6.251925)
			(xy 44.134319 -6.265972) (xy 44.058749 -6.272021) (xy 43.982965 -6.270002) (xy 43.907825 -6.25994)
			(xy 43.83418 -6.241948) (xy 43.762864 -6.21623) (xy 43.694687 -6.183078) (xy 43.630419 -6.142866)
			(xy 43.57079 -6.096051) (xy 43.516474 -6.043163) (xy 43.468088 -5.984801) (xy 43.42618 -5.921626)
			(xy 43.391224 -5.854355) (xy 43.363617 -5.78375) (xy 43.343671 -5.710609) (xy 43.331612 -5.635764)
			(xy 43.327577 -5.56006) (xy 42.502604 -5.56006) (xy 42.593088 -5.632218) (xy 42.678643 -5.710691)
			(xy 42.758581 -5.794879) (xy 42.83252 -5.884381) (xy 42.900108 -5.978772) (xy 42.961022 -6.0776)
			(xy 43.014974 -6.180396) (xy 43.056604 -6.27507) (xy 84.927697 -6.27507) (xy 84.931732 -6.199366)
			(xy 84.943791 -6.124521) (xy 84.963737 -6.05138) (xy 84.991344 -5.980775) (xy 85.0263 -5.913504)
			(xy 85.068208 -5.850329) (xy 85.116594 -5.791967) (xy 85.17091 -5.739079) (xy 85.230539 -5.692264)
			(xy 85.294807 -5.652052) (xy 85.362984 -5.6189) (xy 85.4343 -5.593182) (xy 85.507945 -5.57519) (xy 85.583085 -5.565128)
			(xy 85.658869 -5.563109) (xy 85.734439 -5.569158) (xy 85.808937 -5.583205) (xy 85.88152 -5.605091)
			(xy 85.951366 -5.634568) (xy 86.017683 -5.671303) (xy 86.079719 -5.714878) (xy 86.136772 -5.7648)
			(xy 86.188196 -5.820504) (xy 86.233407 -5.881359) (xy 86.271894 -5.946674) (xy 86.30322 -6.01571)
			(xy 86.32703 -6.087685) (xy 86.343055 -6.161783) (xy 86.351114 -6.237164) (xy 86.351618 -6.27507)
			(xy 87.467697 -6.27507) (xy 87.471732 -6.199366) (xy 87.483791 -6.124521) (xy 87.503737 -6.05138)
			(xy 87.531344 -5.980775) (xy 87.5663 -5.913504) (xy 87.608208 -5.850329) (xy 87.656594 -5.791967)
			(xy 87.71091 -5.739079) (xy 87.770539 -5.692264) (xy 87.834807 -5.652052) (xy 87.902984 -5.6189)
			(xy 87.9743 -5.593182) (xy 88.047945 -5.57519) (xy 88.123085 -5.565128) (xy 88.198869 -5.563109)
			(xy 88.274439 -5.569158) (xy 88.348937 -5.583205) (xy 88.42152 -5.605091) (xy 88.491366 -5.634568)
			(xy 88.557683 -5.671303) (xy 88.619719 -5.714878) (xy 88.676772 -5.7648) (xy 88.728196 -5.820504)
			(xy 88.773407 -5.881359) (xy 88.811894 -5.946674) (xy 88.84322 -6.01571) (xy 88.86703 -6.087685)
			(xy 88.883055 -6.161783) (xy 88.891114 -6.237164) (xy 88.891618 -6.27507) (xy 90.007697 -6.27507)
			(xy 90.011732 -6.199366) (xy 90.023791 -6.124521) (xy 90.043737 -6.05138) (xy 90.071344 -5.980775)
			(xy 90.1063 -5.913504) (xy 90.148208 -5.850329) (xy 90.196594 -5.791967) (xy 90.25091 -5.739079)
			(xy 90.310539 -5.692264) (xy 90.374807 -5.652052) (xy 90.442984 -5.6189) (xy 90.5143 -5.593182) (xy 90.587945 -5.57519)
			(xy 90.663085 -5.565128) (xy 90.738869 -5.563109) (xy 90.814439 -5.569158) (xy 90.888937 -5.583205)
			(xy 90.96152 -5.605091) (xy 91.031366 -5.634568) (xy 91.097683 -5.671303) (xy 91.159719 -5.714878)
			(xy 91.216772 -5.7648) (xy 91.268196 -5.820504) (xy 91.313407 -5.881359) (xy 91.351894 -5.946674)
			(xy 91.38322 -6.01571) (xy 91.40703 -6.087685) (xy 91.423055 -6.161783) (xy 91.431114 -6.237164)
			(xy 91.431618 -6.27507) (xy 91.431114 -6.312976) (xy 91.423055 -6.388357) (xy 91.40703 -6.462455)
			(xy 91.38322 -6.53443) (xy 91.351894 -6.603466) (xy 91.313407 -6.668781) (xy 91.268196 -6.729636)
			(xy 91.216772 -6.78534) (xy 91.159719 -6.835262) (xy 91.097683 -6.878837) (xy 91.031366 -6.915572)
			(xy 90.96152 -6.945049) (xy 90.888937 -6.966935) (xy 90.814439 -6.980982) (xy 90.738869 -6.987031)
			(xy 90.663085 -6.985012) (xy 90.587945 -6.97495) (xy 90.5143 -6.956958) (xy 90.442984 -6.93124) (xy 90.374807 -6.898088)
			(xy 90.310539 -6.857876) (xy 90.25091 -6.811061) (xy 90.196594 -6.758173) (xy 90.148208 -6.699811)
			(xy 90.1063 -6.636636) (xy 90.071344 -6.569365) (xy 90.043737 -6.49876) (xy 90.023791 -6.425619)
			(xy 90.011732 -6.350774) (xy 90.007697 -6.27507) (xy 88.891618 -6.27507) (xy 88.891114 -6.312976)
			(xy 88.883055 -6.388357) (xy 88.86703 -6.462455) (xy 88.84322 -6.53443) (xy 88.811894 -6.603466)
			(xy 88.773407 -6.668781) (xy 88.728196 -6.729636) (xy 88.676772 -6.78534) (xy 88.619719 -6.835262)
			(xy 88.557683 -6.878837) (xy 88.491366 -6.915572) (xy 88.42152 -6.945049) (xy 88.348937 -6.966935)
			(xy 88.274439 -6.980982) (xy 88.198869 -6.987031) (xy 88.123085 -6.985012) (xy 88.047945 -6.97495)
			(xy 87.9743 -6.956958) (xy 87.902984 -6.93124) (xy 87.834807 -6.898088) (xy 87.770539 -6.857876)
			(xy 87.71091 -6.811061) (xy 87.656594 -6.758173) (xy 87.608208 -6.699811) (xy 87.5663 -6.636636)
			(xy 87.531344 -6.569365) (xy 87.503737 -6.49876) (xy 87.483791 -6.425619) (xy 87.471732 -6.350774)
			(xy 87.467697 -6.27507) (xy 86.351618 -6.27507) (xy 86.351114 -6.312976) (xy 86.343055 -6.388357)
			(xy 86.32703 -6.462455) (xy 86.30322 -6.53443) (xy 86.271894 -6.603466) (xy 86.233407 -6.668781)
			(xy 86.188196 -6.729636) (xy 86.136772 -6.78534) (xy 86.079719 -6.835262) (xy 86.017683 -6.878837)
			(xy 85.951366 -6.915572) (xy 85.88152 -6.945049) (xy 85.808937 -6.966935) (xy 85.734439 -6.980982)
			(xy 85.658869 -6.987031) (xy 85.583085 -6.985012) (xy 85.507945 -6.97495) (xy 85.4343 -6.956958)
			(xy 85.362984 -6.93124) (xy 85.294807 -6.898088) (xy 85.230539 -6.857876) (xy 85.17091 -6.811061)
			(xy 85.116594 -6.758173) (xy 85.068208 -6.699811) (xy 85.0263 -6.636636) (xy 84.991344 -6.569365)
			(xy 84.963737 -6.49876) (xy 84.943791 -6.425619) (xy 84.931732 -6.350774) (xy 84.927697 -6.27507)
			(xy 43.056604 -6.27507) (xy 43.061704 -6.286669) (xy 43.100992 -6.395913) (xy 43.132649 -6.507606)
			(xy 43.156525 -6.621218) (xy 43.172506 -6.736206) (xy 43.180515 -6.852023) (xy 43.181016 -6.91007)
			(xy 43.180515 -6.968117) (xy 43.172506 -7.083934) (xy 43.156525 -7.198922) (xy 43.132649 -7.312534)
			(xy 43.100992 -7.424227) (xy 43.061704 -7.533471) (xy 43.056604 -7.54507) (xy 86.197697 -7.54507)
			(xy 86.201732 -7.469366) (xy 86.213791 -7.394521) (xy 86.233737 -7.32138) (xy 86.261344 -7.250775)
			(xy 86.2963 -7.183504) (xy 86.338208 -7.120329) (xy 86.386594 -7.061967) (xy 86.44091 -7.009079)
			(xy 86.500539 -6.962264) (xy 86.564807 -6.922052) (xy 86.632984 -6.8889) (xy 86.7043 -6.863182) (xy 86.777945 -6.84519)
			(xy 86.853085 -6.835128) (xy 86.928869 -6.833109) (xy 87.004439 -6.839158) (xy 87.078937 -6.853205)
			(xy 87.15152 -6.875091) (xy 87.221366 -6.904568) (xy 87.287683 -6.941303) (xy 87.349719 -6.984878)
			(xy 87.406772 -7.0348) (xy 87.458196 -7.090504) (xy 87.503407 -7.151359) (xy 87.541894 -7.216674)
			(xy 87.57322 -7.28571) (xy 87.59703 -7.357685) (xy 87.613055 -7.431783) (xy 87.621114 -7.507164)
			(xy 87.621618 -7.54507) (xy 88.737697 -7.54507) (xy 88.741732 -7.469366) (xy 88.753791 -7.394521)
			(xy 88.773737 -7.32138) (xy 88.801344 -7.250775) (xy 88.8363 -7.183504) (xy 88.878208 -7.120329)
			(xy 88.926594 -7.061967) (xy 88.98091 -7.009079) (xy 89.040539 -6.962264) (xy 89.104807 -6.922052)
			(xy 89.172984 -6.8889) (xy 89.2443 -6.863182) (xy 89.317945 -6.84519) (xy 89.393085 -6.835128) (xy 89.468869 -6.833109)
			(xy 89.544439 -6.839158) (xy 89.618937 -6.853205) (xy 89.69152 -6.875091) (xy 89.761366 -6.904568)
			(xy 89.827683 -6.941303) (xy 89.889719 -6.984878) (xy 89.946772 -7.0348) (xy 89.998196 -7.090504)
			(xy 90.043407 -7.151359) (xy 90.081894 -7.216674) (xy 90.11322 -7.28571) (xy 90.13703 -7.357685)
			(xy 90.153055 -7.431783) (xy 90.161114 -7.507164) (xy 90.161618 -7.54507) (xy 91.277697 -7.54507)
			(xy 91.281732 -7.469366) (xy 91.293791 -7.394521) (xy 91.313737 -7.32138) (xy 91.341344 -7.250775)
			(xy 91.3763 -7.183504) (xy 91.418208 -7.120329) (xy 91.466594 -7.061967) (xy 91.52091 -7.009079)
			(xy 91.580539 -6.962264) (xy 91.644807 -6.922052) (xy 91.712984 -6.8889) (xy 91.7843 -6.863182) (xy 91.857945 -6.84519)
			(xy 91.933085 -6.835128) (xy 92.008869 -6.833109) (xy 92.084439 -6.839158) (xy 92.158937 -6.853205)
			(xy 92.23152 -6.875091) (xy 92.301366 -6.904568) (xy 92.367683 -6.941303) (xy 92.429719 -6.984878)
			(xy 92.486772 -7.0348) (xy 92.538196 -7.090504) (xy 92.583407 -7.151359) (xy 92.621894 -7.216674)
			(xy 92.65322 -7.28571) (xy 92.67703 -7.357685) (xy 92.693055 -7.431783) (xy 92.701114 -7.507164)
			(xy 92.701618 -7.54507) (xy 92.701114 -7.582976) (xy 92.693055 -7.658357) (xy 92.67703 -7.732455)
			(xy 92.65322 -7.80443) (xy 92.621894 -7.873466) (xy 92.583407 -7.938781) (xy 92.538196 -7.999636)
			(xy 92.486772 -8.05534) (xy 92.429719 -8.105262) (xy 92.367683 -8.148837) (xy 92.301366 -8.185572)
			(xy 92.23152 -8.215049) (xy 92.158937 -8.236935) (xy 92.084439 -8.250982) (xy 92.008869 -8.257031)
			(xy 91.933085 -8.255012) (xy 91.857945 -8.24495) (xy 91.7843 -8.226958) (xy 91.712984 -8.20124) (xy 91.644807 -8.168088)
			(xy 91.580539 -8.127876) (xy 91.52091 -8.081061) (xy 91.466594 -8.028173) (xy 91.418208 -7.969811)
			(xy 91.3763 -7.906636) (xy 91.341344 -7.839365) (xy 91.313737 -7.76876) (xy 91.293791 -7.695619)
			(xy 91.281732 -7.620774) (xy 91.277697 -7.54507) (xy 90.161618 -7.54507) (xy 90.161114 -7.582976)
			(xy 90.153055 -7.658357) (xy 90.13703 -7.732455) (xy 90.11322 -7.80443) (xy 90.081894 -7.873466)
			(xy 90.043407 -7.938781) (xy 89.998196 -7.999636) (xy 89.946772 -8.05534) (xy 89.889719 -8.105262)
			(xy 89.827683 -8.148837) (xy 89.761366 -8.185572) (xy 89.69152 -8.215049) (xy 89.618937 -8.236935)
			(xy 89.544439 -8.250982) (xy 89.468869 -8.257031) (xy 89.393085 -8.255012) (xy 89.317945 -8.24495)
			(xy 89.2443 -8.226958) (xy 89.172984 -8.20124) (xy 89.104807 -8.168088) (xy 89.040539 -8.127876)
			(xy 88.98091 -8.081061) (xy 88.926594 -8.028173) (xy 88.878208 -7.969811) (xy 88.8363 -7.906636)
			(xy 88.801344 -7.839365) (xy 88.773737 -7.76876) (xy 88.753791 -7.695619) (xy 88.741732 -7.620774)
			(xy 88.737697 -7.54507) (xy 87.621618 -7.54507) (xy 87.621114 -7.582976) (xy 87.613055 -7.658357)
			(xy 87.59703 -7.732455) (xy 87.57322 -7.80443) (xy 87.541894 -7.873466) (xy 87.503407 -7.938781)
			(xy 87.458196 -7.999636) (xy 87.406772 -8.05534) (xy 87.349719 -8.105262) (xy 87.287683 -8.148837)
			(xy 87.221366 -8.185572) (xy 87.15152 -8.215049) (xy 87.078937 -8.236935) (xy 87.004439 -8.250982)
			(xy 86.928869 -8.257031) (xy 86.853085 -8.255012) (xy 86.777945 -8.24495) (xy 86.7043 -8.226958)
			(xy 86.632984 -8.20124) (xy 86.564807 -8.168088) (xy 86.500539 -8.127876) (xy 86.44091 -8.081061)
			(xy 86.386594 -8.028173) (xy 86.338208 -7.969811) (xy 86.2963 -7.906636) (xy 86.261344 -7.839365)
			(xy 86.233737 -7.76876) (xy 86.213791 -7.695619) (xy 86.201732 -7.620774) (xy 86.197697 -7.54507)
			(xy 43.056604 -7.54507) (xy 43.055152 -7.548372) (xy 43.328336 -7.548372) (xy 44.751244 -7.548372)
			(xy 44.751244 -8.26008) (xy 45.867577 -8.26008) (xy 45.871612 -8.184376) (xy 45.883671 -8.109531)
			(xy 45.903617 -8.03639) (xy 45.931224 -7.965785) (xy 45.96618 -7.898514) (xy 46.008088 -7.835339)
			(xy 46.056474 -7.776977) (xy 46.11079 -7.724089) (xy 46.170419 -7.677274) (xy 46.234687 -7.637062)
			(xy 46.302864 -7.60391) (xy 46.37418 -7.578192) (xy 46.447825 -7.5602) (xy 46.522965 -7.550138) (xy 46.598749 -7.548119)
			(xy 46.674319 -7.554168) (xy 46.748817 -7.568215) (xy 46.8214 -7.590101) (xy 46.891246 -7.619578)
			(xy 46.957563 -7.656313) (xy 47.019599 -7.699888) (xy 47.076652 -7.74981) (xy 47.128076 -7.805514)
			(xy 47.173287 -7.866369) (xy 47.211774 -7.931684) (xy 47.2431 -8.00072) (xy 47.26691 -8.072695) (xy 47.282935 -8.146793)
			(xy 47.290994 -8.222174) (xy 47.291498 -8.26008) (xy 48.407577 -8.26008) (xy 48.411612 -8.184376)
			(xy 48.423671 -8.109531) (xy 48.443617 -8.03639) (xy 48.471224 -7.965785) (xy 48.50618 -7.898514)
			(xy 48.548088 -7.835339) (xy 48.596474 -7.776977) (xy 48.65079 -7.724089) (xy 48.710419 -7.677274)
			(xy 48.774687 -7.637062) (xy 48.842864 -7.60391) (xy 48.91418 -7.578192) (xy 48.987825 -7.5602) (xy 49.062965 -7.550138)
			(xy 49.138749 -7.548119) (xy 49.214319 -7.554168) (xy 49.288817 -7.568215) (xy 49.3614 -7.590101)
			(xy 49.431246 -7.619578) (xy 49.497563 -7.656313) (xy 49.559599 -7.699888) (xy 49.616652 -7.74981)
			(xy 49.668076 -7.805514) (xy 49.713287 -7.866369) (xy 49.751774 -7.931684) (xy 49.7831 -8.00072)
			(xy 49.80691 -8.072695) (xy 49.822935 -8.146793) (xy 49.830994 -8.222174) (xy 49.831498 -8.26008)
			(xy 50.947577 -8.26008) (xy 50.951612 -8.184376) (xy 50.963671 -8.109531) (xy 50.983617 -8.03639)
			(xy 51.011224 -7.965785) (xy 51.04618 -7.898514) (xy 51.088088 -7.835339) (xy 51.136474 -7.776977)
			(xy 51.19079 -7.724089) (xy 51.250419 -7.677274) (xy 51.314687 -7.637062) (xy 51.382864 -7.60391)
			(xy 51.45418 -7.578192) (xy 51.527825 -7.5602) (xy 51.602965 -7.550138) (xy 51.678749 -7.548119)
			(xy 51.754319 -7.554168) (xy 51.828817 -7.568215) (xy 51.9014 -7.590101) (xy 51.971246 -7.619578)
			(xy 52.037563 -7.656313) (xy 52.099599 -7.699888) (xy 52.156652 -7.74981) (xy 52.208076 -7.805514)
			(xy 52.253287 -7.866369) (xy 52.291774 -7.931684) (xy 52.3231 -8.00072) (xy 52.34691 -8.072695) (xy 52.362935 -8.146793)
			(xy 52.370994 -8.222174) (xy 52.371498 -8.26008) (xy 53.487577 -8.26008) (xy 53.491612 -8.184376)
			(xy 53.503671 -8.109531) (xy 53.523617 -8.03639) (xy 53.551224 -7.965785) (xy 53.58618 -7.898514)
			(xy 53.628088 -7.835339) (xy 53.676474 -7.776977) (xy 53.73079 -7.724089) (xy 53.790419 -7.677274)
			(xy 53.854687 -7.637062) (xy 53.922864 -7.60391) (xy 53.99418 -7.578192) (xy 54.067825 -7.5602) (xy 54.142965 -7.550138)
			(xy 54.218749 -7.548119) (xy 54.294319 -7.554168) (xy 54.368817 -7.568215) (xy 54.4414 -7.590101)
			(xy 54.511246 -7.619578) (xy 54.577563 -7.656313) (xy 54.639599 -7.699888) (xy 54.696652 -7.74981)
			(xy 54.748076 -7.805514) (xy 54.793287 -7.866369) (xy 54.831774 -7.931684) (xy 54.8631 -8.00072)
			(xy 54.88691 -8.072695) (xy 54.902935 -8.146793) (xy 54.910994 -8.222174) (xy 54.911498 -8.26008)
			(xy 56.027577 -8.26008) (xy 56.031612 -8.184376) (xy 56.043671 -8.109531) (xy 56.063617 -8.03639)
			(xy 56.091224 -7.965785) (xy 56.12618 -7.898514) (xy 56.168088 -7.835339) (xy 56.216474 -7.776977)
			(xy 56.27079 -7.724089) (xy 56.330419 -7.677274) (xy 56.394687 -7.637062) (xy 56.462864 -7.60391)
			(xy 56.53418 -7.578192) (xy 56.607825 -7.5602) (xy 56.682965 -7.550138) (xy 56.758749 -7.548119)
			(xy 56.834319 -7.554168) (xy 56.908817 -7.568215) (xy 56.9814 -7.590101) (xy 57.051246 -7.619578)
			(xy 57.117563 -7.656313) (xy 57.179599 -7.699888) (xy 57.236652 -7.74981) (xy 57.288076 -7.805514)
			(xy 57.333287 -7.866369) (xy 57.371774 -7.931684) (xy 57.4031 -8.00072) (xy 57.42691 -8.072695) (xy 57.442935 -8.146793)
			(xy 57.450994 -8.222174) (xy 57.451498 -8.26008) (xy 58.567577 -8.26008) (xy 58.571612 -8.184376)
			(xy 58.583671 -8.109531) (xy 58.603617 -8.03639) (xy 58.631224 -7.965785) (xy 58.66618 -7.898514)
			(xy 58.708088 -7.835339) (xy 58.756474 -7.776977) (xy 58.81079 -7.724089) (xy 58.870419 -7.677274)
			(xy 58.934687 -7.637062) (xy 59.002864 -7.60391) (xy 59.07418 -7.578192) (xy 59.147825 -7.5602) (xy 59.222965 -7.550138)
			(xy 59.298749 -7.548119) (xy 59.374319 -7.554168) (xy 59.448817 -7.568215) (xy 59.5214 -7.590101)
			(xy 59.591246 -7.619578) (xy 59.657563 -7.656313) (xy 59.719599 -7.699888) (xy 59.776652 -7.74981)
			(xy 59.828076 -7.805514) (xy 59.873287 -7.866369) (xy 59.911774 -7.931684) (xy 59.9431 -8.00072)
			(xy 59.96691 -8.072695) (xy 59.982935 -8.146793) (xy 59.990994 -8.222174) (xy 59.991498 -8.26008)
			(xy 61.107577 -8.26008) (xy 61.111612 -8.184376) (xy 61.123671 -8.109531) (xy 61.143617 -8.03639)
			(xy 61.171224 -7.965785) (xy 61.20618 -7.898514) (xy 61.248088 -7.835339) (xy 61.296474 -7.776977)
			(xy 61.35079 -7.724089) (xy 61.410419 -7.677274) (xy 61.474687 -7.637062) (xy 61.542864 -7.60391)
			(xy 61.61418 -7.578192) (xy 61.687825 -7.5602) (xy 61.762965 -7.550138) (xy 61.838749 -7.548119)
			(xy 61.914319 -7.554168) (xy 61.988817 -7.568215) (xy 62.0614 -7.590101) (xy 62.131246 -7.619578)
			(xy 62.197563 -7.656313) (xy 62.259599 -7.699888) (xy 62.316652 -7.74981) (xy 62.368076 -7.805514)
			(xy 62.413287 -7.866369) (xy 62.451774 -7.931684) (xy 62.4831 -8.00072) (xy 62.50691 -8.072695) (xy 62.522935 -8.146793)
			(xy 62.530994 -8.222174) (xy 62.531498 -8.26008) (xy 62.530994 -8.297986) (xy 62.522935 -8.373367)
			(xy 62.50691 -8.447465) (xy 62.4831 -8.51944) (xy 62.451774 -8.588476) (xy 62.413287 -8.653791) (xy 62.368076 -8.714646)
			(xy 62.316652 -8.77035) (xy 62.265544 -8.81507) (xy 84.927697 -8.81507) (xy 84.931732 -8.739366)
			(xy 84.943791 -8.664521) (xy 84.963737 -8.59138) (xy 84.991344 -8.520775) (xy 85.0263 -8.453504)
			(xy 85.068208 -8.390329) (xy 85.116594 -8.331967) (xy 85.17091 -8.279079) (xy 85.230539 -8.232264)
			(xy 85.294807 -8.192052) (xy 85.362984 -8.1589) (xy 85.4343 -8.133182) (xy 85.507945 -8.11519) (xy 85.583085 -8.105128)
			(xy 85.658869 -8.103109) (xy 85.734439 -8.109158) (xy 85.808937 -8.123205) (xy 85.88152 -8.145091)
			(xy 85.951366 -8.174568) (xy 86.017683 -8.211303) (xy 86.079719 -8.254878) (xy 86.136772 -8.3048)
			(xy 86.188196 -8.360504) (xy 86.233407 -8.421359) (xy 86.271894 -8.486674) (xy 86.30322 -8.55571)
			(xy 86.32703 -8.627685) (xy 86.343055 -8.701783) (xy 86.351114 -8.777164) (xy 86.351618 -8.81507)
			(xy 87.467697 -8.81507) (xy 87.471732 -8.739366) (xy 87.483791 -8.664521) (xy 87.503737 -8.59138)
			(xy 87.531344 -8.520775) (xy 87.5663 -8.453504) (xy 87.608208 -8.390329) (xy 87.656594 -8.331967)
			(xy 87.71091 -8.279079) (xy 87.770539 -8.232264) (xy 87.834807 -8.192052) (xy 87.902984 -8.1589)
			(xy 87.9743 -8.133182) (xy 88.047945 -8.11519) (xy 88.123085 -8.105128) (xy 88.198869 -8.103109)
			(xy 88.274439 -8.109158) (xy 88.348937 -8.123205) (xy 88.42152 -8.145091) (xy 88.491366 -8.174568)
			(xy 88.557683 -8.211303) (xy 88.619719 -8.254878) (xy 88.676772 -8.3048) (xy 88.728196 -8.360504)
			(xy 88.773407 -8.421359) (xy 88.811894 -8.486674) (xy 88.84322 -8.55571) (xy 88.86703 -8.627685)
			(xy 88.883055 -8.701783) (xy 88.891114 -8.777164) (xy 88.891618 -8.81507) (xy 90.007697 -8.81507)
			(xy 90.011732 -8.739366) (xy 90.023791 -8.664521) (xy 90.043737 -8.59138) (xy 90.071344 -8.520775)
			(xy 90.1063 -8.453504) (xy 90.148208 -8.390329) (xy 90.196594 -8.331967) (xy 90.25091 -8.279079)
			(xy 90.310539 -8.232264) (xy 90.374807 -8.192052) (xy 90.442984 -8.1589) (xy 90.5143 -8.133182) (xy 90.587945 -8.11519)
			(xy 90.663085 -8.105128) (xy 90.738869 -8.103109) (xy 90.814439 -8.109158) (xy 90.888937 -8.123205)
			(xy 90.96152 -8.145091) (xy 91.031366 -8.174568) (xy 91.097683 -8.211303) (xy 91.159719 -8.254878)
			(xy 91.165664 -8.26008) (xy 93.154506 -8.26008) (xy 93.158522 -8.14381) (xy 93.170549 -8.028095)
			(xy 93.190531 -7.913485) (xy 93.218373 -7.800526) (xy 93.253942 -7.689758) (xy 93.297068 -7.581707)
			(xy 93.347545 -7.476889) (xy 93.405134 -7.375804) (xy 93.46956 -7.278932) (xy 93.540515 -7.186736)
			(xy 93.617662 -7.099655) (xy 93.700633 -7.018104) (xy 93.789033 -6.942472) (xy 93.88244 -6.873118)
			(xy 93.980409 -6.810375) (xy 94.082473 -6.754539) (xy 94.188147 -6.705878) (xy 94.296926 -6.664624)
			(xy 94.408291 -6.630973) (xy 94.521714 -6.605085) (xy 94.636651 -6.587084) (xy 94.752557 -6.577055)
			(xy 94.868879 -6.575047) (xy 94.985062 -6.581069) (xy 95.100553 -6.595092) (xy 95.214801 -6.61705)
			(xy 95.327262 -6.646837) (xy 95.4374 -6.684312) (xy 95.54469 -6.729297) (xy 95.648621 -6.781576)
			(xy 95.748697 -6.840901) (xy 95.844443 -6.906989) (xy 95.9354 -6.979525) (xy 96.021136 -7.058164)
			(xy 96.101243 -7.14253) (xy 96.175339 -7.232222) (xy 96.243069 -7.326812) (xy 96.304113 -7.42585)
			(xy 96.358178 -7.528863) (xy 96.405008 -7.63536) (xy 96.444379 -7.744835) (xy 96.476103 -7.856765)
			(xy 96.500029 -7.970617) (xy 96.516043 -8.085849) (xy 96.52407 -8.201911) (xy 96.524572 -8.26008)
			(xy 96.52407 -8.318249) (xy 96.516043 -8.434311) (xy 96.500029 -8.549543) (xy 96.476103 -8.663395)
			(xy 96.444379 -8.775325) (xy 96.405008 -8.8848) (xy 96.358178 -8.991297) (xy 96.304113 -9.09431)
			(xy 96.243069 -9.193348) (xy 96.175339 -9.287938) (xy 96.101243 -9.37763) (xy 96.021136 -9.461996)
			(xy 95.9354 -9.540635) (xy 95.844443 -9.613171) (xy 95.748697 -9.679259) (xy 95.648621 -9.738584)
			(xy 95.54469 -9.790863) (xy 95.4374 -9.835848) (xy 95.327262 -9.873323) (xy 95.214801 -9.90311) (xy 95.100553 -9.925068)
			(xy 94.985062 -9.939091) (xy 94.868879 -9.945113) (xy 94.752557 -9.943105) (xy 94.636651 -9.933076)
			(xy 94.521714 -9.915075) (xy 94.408291 -9.889187) (xy 94.296926 -9.855536) (xy 94.188147 -9.814282)
			(xy 94.082473 -9.765621) (xy 93.980409 -9.709785) (xy 93.88244 -9.647042) (xy 93.789033 -9.577688)
			(xy 93.700633 -9.502056) (xy 93.617662 -9.420505) (xy 93.540515 -9.333424) (xy 93.46956 -9.241228)
			(xy 93.405134 -9.144356) (xy 93.347545 -9.043271) (xy 93.297068 -8.938453) (xy 93.253942 -8.830402)
			(xy 93.218373 -8.719634) (xy 93.190531 -8.606675) (xy 93.170549 -8.492065) (xy 93.158522 -8.37635)
			(xy 93.154506 -8.26008) (xy 91.165664 -8.26008) (xy 91.216772 -8.3048) (xy 91.268196 -8.360504) (xy 91.313407 -8.421359)
			(xy 91.351894 -8.486674) (xy 91.38322 -8.55571) (xy 91.40703 -8.627685) (xy 91.423055 -8.701783)
			(xy 91.431114 -8.777164) (xy 91.431618 -8.81507) (xy 91.431114 -8.852976) (xy 91.423055 -8.928357)
			(xy 91.40703 -9.002455) (xy 91.38322 -9.07443) (xy 91.351894 -9.143466) (xy 91.313407 -9.208781)
			(xy 91.268196 -9.269636) (xy 91.216772 -9.32534) (xy 91.159719 -9.375262) (xy 91.097683 -9.418837)
			(xy 91.031366 -9.455572) (xy 90.96152 -9.485049) (xy 90.888937 -9.506935) (xy 90.814439 -9.520982)
			(xy 90.738869 -9.527031) (xy 90.663085 -9.525012) (xy 90.587945 -9.51495) (xy 90.5143 -9.496958)
			(xy 90.442984 -9.47124) (xy 90.374807 -9.438088) (xy 90.310539 -9.397876) (xy 90.25091 -9.351061)
			(xy 90.196594 -9.298173) (xy 90.148208 -9.239811) (xy 90.1063 -9.176636) (xy 90.071344 -9.109365)
			(xy 90.043737 -9.03876) (xy 90.023791 -8.965619) (xy 90.011732 -8.890774) (xy 90.007697 -8.81507)
			(xy 88.891618 -8.81507) (xy 88.891114 -8.852976) (xy 88.883055 -8.928357) (xy 88.86703 -9.002455)
			(xy 88.84322 -9.07443) (xy 88.811894 -9.143466) (xy 88.773407 -9.208781) (xy 88.728196 -9.269636)
			(xy 88.676772 -9.32534) (xy 88.619719 -9.375262) (xy 88.557683 -9.418837) (xy 88.491366 -9.455572)
			(xy 88.42152 -9.485049) (xy 88.348937 -9.506935) (xy 88.274439 -9.520982) (xy 88.198869 -9.527031)
			(xy 88.123085 -9.525012) (xy 88.047945 -9.51495) (xy 87.9743 -9.496958) (xy 87.902984 -9.47124) (xy 87.834807 -9.438088)
			(xy 87.770539 -9.397876) (xy 87.71091 -9.351061) (xy 87.656594 -9.298173) (xy 87.608208 -9.239811)
			(xy 87.5663 -9.176636) (xy 87.531344 -9.109365) (xy 87.503737 -9.03876) (xy 87.483791 -8.965619)
			(xy 87.471732 -8.890774) (xy 87.467697 -8.81507) (xy 86.351618 -8.81507) (xy 86.351114 -8.852976)
			(xy 86.343055 -8.928357) (xy 86.32703 -9.002455) (xy 86.30322 -9.07443) (xy 86.271894 -9.143466)
			(xy 86.233407 -9.208781) (xy 86.188196 -9.269636) (xy 86.136772 -9.32534) (xy 86.079719 -9.375262)
			(xy 86.017683 -9.418837) (xy 85.951366 -9.455572) (xy 85.88152 -9.485049) (xy 85.808937 -9.506935)
			(xy 85.734439 -9.520982) (xy 85.658869 -9.527031) (xy 85.583085 -9.525012) (xy 85.507945 -9.51495)
			(xy 85.4343 -9.496958) (xy 85.362984 -9.47124) (xy 85.294807 -9.438088) (xy 85.230539 -9.397876)
			(xy 85.17091 -9.351061) (xy 85.116594 -9.298173) (xy 85.068208 -9.239811) (xy 85.0263 -9.176636)
			(xy 84.991344 -9.109365) (xy 84.963737 -9.03876) (xy 84.943791 -8.965619) (xy 84.931732 -8.890774)
			(xy 84.927697 -8.81507) (xy 62.265544 -8.81507) (xy 62.259599 -8.820272) (xy 62.197563 -8.863847)
			(xy 62.131246 -8.900582) (xy 62.0614 -8.930059) (xy 61.988817 -8.951945) (xy 61.914319 -8.965992)
			(xy 61.838749 -8.972041) (xy 61.762965 -8.970022) (xy 61.687825 -8.95996) (xy 61.61418 -8.941968)
			(xy 61.542864 -8.91625) (xy 61.474687 -8.883098) (xy 61.410419 -8.842886) (xy 61.35079 -8.796071)
			(xy 61.296474 -8.743183) (xy 61.248088 -8.684821) (xy 61.20618 -8.621646) (xy 61.171224 -8.554375)
			(xy 61.143617 -8.48377) (xy 61.123671 -8.410629) (xy 61.111612 -8.335784) (xy 61.107577 -8.26008)
			(xy 59.991498 -8.26008) (xy 59.990994 -8.297986) (xy 59.982935 -8.373367) (xy 59.96691 -8.447465)
			(xy 59.9431 -8.51944) (xy 59.911774 -8.588476) (xy 59.873287 -8.653791) (xy 59.828076 -8.714646)
			(xy 59.776652 -8.77035) (xy 59.719599 -8.820272) (xy 59.657563 -8.863847) (xy 59.591246 -8.900582)
			(xy 59.5214 -8.930059) (xy 59.448817 -8.951945) (xy 59.374319 -8.965992) (xy 59.298749 -8.972041)
			(xy 59.222965 -8.970022) (xy 59.147825 -8.95996) (xy 59.07418 -8.941968) (xy 59.002864 -8.91625)
			(xy 58.934687 -8.883098) (xy 58.870419 -8.842886) (xy 58.81079 -8.796071) (xy 58.756474 -8.743183)
			(xy 58.708088 -8.684821) (xy 58.66618 -8.621646) (xy 58.631224 -8.554375) (xy 58.603617 -8.48377)
			(xy 58.583671 -8.410629) (xy 58.571612 -8.335784) (xy 58.567577 -8.26008) (xy 57.451498 -8.26008)
			(xy 57.450994 -8.297986) (xy 57.442935 -8.373367) (xy 57.42691 -8.447465) (xy 57.4031 -8.51944) (xy 57.371774 -8.588476)
			(xy 57.333287 -8.653791) (xy 57.288076 -8.714646) (xy 57.236652 -8.77035) (xy 57.179599 -8.820272)
			(xy 57.117563 -8.863847) (xy 57.051246 -8.900582) (xy 56.9814 -8.930059) (xy 56.908817 -8.951945)
			(xy 56.834319 -8.965992) (xy 56.758749 -8.972041) (xy 56.682965 -8.970022) (xy 56.607825 -8.95996)
			(xy 56.53418 -8.941968) (xy 56.462864 -8.91625) (xy 56.394687 -8.883098) (xy 56.330419 -8.842886)
			(xy 56.27079 -8.796071) (xy 56.216474 -8.743183) (xy 56.168088 -8.684821) (xy 56.12618 -8.621646)
			(xy 56.091224 -8.554375) (xy 56.063617 -8.48377) (xy 56.043671 -8.410629) (xy 56.031612 -8.335784)
			(xy 56.027577 -8.26008) (xy 54.911498 -8.26008) (xy 54.910994 -8.297986) (xy 54.902935 -8.373367)
			(xy 54.88691 -8.447465) (xy 54.8631 -8.51944) (xy 54.831774 -8.588476) (xy 54.793287 -8.653791) (xy 54.748076 -8.714646)
			(xy 54.696652 -8.77035) (xy 54.639599 -8.820272) (xy 54.577563 -8.863847) (xy 54.511246 -8.900582)
			(xy 54.4414 -8.930059) (xy 54.368817 -8.951945) (xy 54.294319 -8.965992) (xy 54.218749 -8.972041)
			(xy 54.142965 -8.970022) (xy 54.067825 -8.95996) (xy 53.99418 -8.941968) (xy 53.922864 -8.91625)
			(xy 53.854687 -8.883098) (xy 53.790419 -8.842886) (xy 53.73079 -8.796071) (xy 53.676474 -8.743183)
			(xy 53.628088 -8.684821) (xy 53.58618 -8.621646) (xy 53.551224 -8.554375) (xy 53.523617 -8.48377)
			(xy 53.503671 -8.410629) (xy 53.491612 -8.335784) (xy 53.487577 -8.26008) (xy 52.371498 -8.26008)
			(xy 52.370994 -8.297986) (xy 52.362935 -8.373367) (xy 52.34691 -8.447465) (xy 52.3231 -8.51944) (xy 52.291774 -8.588476)
			(xy 52.253287 -8.653791) (xy 52.208076 -8.714646) (xy 52.156652 -8.77035) (xy 52.099599 -8.820272)
			(xy 52.037563 -8.863847) (xy 51.971246 -8.900582) (xy 51.9014 -8.930059) (xy 51.828817 -8.951945)
			(xy 51.754319 -8.965992) (xy 51.678749 -8.972041) (xy 51.602965 -8.970022) (xy 51.527825 -8.95996)
			(xy 51.45418 -8.941968) (xy 51.382864 -8.91625) (xy 51.314687 -8.883098) (xy 51.250419 -8.842886)
			(xy 51.19079 -8.796071) (xy 51.136474 -8.743183) (xy 51.088088 -8.684821) (xy 51.04618 -8.621646)
			(xy 51.011224 -8.554375) (xy 50.983617 -8.48377) (xy 50.963671 -8.410629) (xy 50.951612 -8.335784)
			(xy 50.947577 -8.26008) (xy 49.831498 -8.26008) (xy 49.830994 -8.297986) (xy 49.822935 -8.373367)
			(xy 49.80691 -8.447465) (xy 49.7831 -8.51944) (xy 49.751774 -8.588476) (xy 49.713287 -8.653791) (xy 49.668076 -8.714646)
			(xy 49.616652 -8.77035) (xy 49.559599 -8.820272) (xy 49.497563 -8.863847) (xy 49.431246 -8.900582)
			(xy 49.3614 -8.930059) (xy 49.288817 -8.951945) (xy 49.214319 -8.965992) (xy 49.138749 -8.972041)
			(xy 49.062965 -8.970022) (xy 48.987825 -8.95996) (xy 48.91418 -8.941968) (xy 48.842864 -8.91625)
			(xy 48.774687 -8.883098) (xy 48.710419 -8.842886) (xy 48.65079 -8.796071) (xy 48.596474 -8.743183)
			(xy 48.548088 -8.684821) (xy 48.50618 -8.621646) (xy 48.471224 -8.554375) (xy 48.443617 -8.48377)
			(xy 48.423671 -8.410629) (xy 48.411612 -8.335784) (xy 48.407577 -8.26008) (xy 47.291498 -8.26008)
			(xy 47.290994 -8.297986) (xy 47.282935 -8.373367) (xy 47.26691 -8.447465) (xy 47.2431 -8.51944) (xy 47.211774 -8.588476)
			(xy 47.173287 -8.653791) (xy 47.128076 -8.714646) (xy 47.076652 -8.77035) (xy 47.019599 -8.820272)
			(xy 46.957563 -8.863847) (xy 46.891246 -8.900582) (xy 46.8214 -8.930059) (xy 46.748817 -8.951945)
			(xy 46.674319 -8.965992) (xy 46.598749 -8.972041) (xy 46.522965 -8.970022) (xy 46.447825 -8.95996)
			(xy 46.37418 -8.941968) (xy 46.302864 -8.91625) (xy 46.234687 -8.883098) (xy 46.170419 -8.842886)
			(xy 46.11079 -8.796071) (xy 46.056474 -8.743183) (xy 46.008088 -8.684821) (xy 45.96618 -8.621646)
			(xy 45.931224 -8.554375) (xy 45.903617 -8.48377) (xy 45.883671 -8.410629) (xy 45.871612 -8.335784)
			(xy 45.867577 -8.26008) (xy 44.751244 -8.26008) (xy 44.751244 -8.971788) (xy 43.328336 -8.971788)
			(xy 43.328336 -7.548372) (xy 43.055152 -7.548372) (xy 43.014974 -7.639744) (xy 42.961022 -7.74254)
			(xy 42.900108 -7.841368) (xy 42.83252 -7.935759) (xy 42.758581 -8.025261) (xy 42.678643 -8.109449)
			(xy 42.593088 -8.187922) (xy 42.502322 -8.260305) (xy 42.406779 -8.326254) (xy 42.306914 -8.385454)
			(xy 42.203202 -8.437623) (xy 42.096139 -8.482512) (xy 41.986233 -8.519908) (xy 41.874009 -8.549633)
			(xy 41.760003 -8.571544) (xy 41.644756 -8.585537) (xy 41.528818 -8.591546) (xy 41.412742 -8.589543)
			(xy 41.29708 -8.579535) (xy 41.182385 -8.561572) (xy 41.069202 -8.535739) (xy 40.958071 -8.502159)
			(xy 40.849522 -8.460991) (xy 40.744072 -8.412433) (xy 40.642223 -8.356716) (xy 40.54446 -8.294104)
			(xy 40.45125 -8.224897) (xy 40.363037 -8.149424) (xy 40.280241 -8.068045) (xy 40.203257 -7.981148)
			(xy 40.132452 -7.889147) (xy 40.068162 -7.79248) (xy 40.010695 -7.691608) (xy 39.960324 -7.587011)
			(xy 39.917289 -7.479188) (xy 39.881795 -7.368654) (xy 39.854012 -7.255934) (xy 39.834072 -7.141566)
			(xy 39.82207 -7.026094) (xy 39.818063 -6.91007) (xy 36.454201 -6.91007) (xy 36.4555 -6.914635) (xy 36.471468 -7.000055)
			(xy 36.479486 -7.086584) (xy 36.479988 -7.130034) (xy 36.479486 -7.173484) (xy 36.471468 -7.260013)
			(xy 36.4555 -7.345433) (xy 36.431719 -7.429015) (xy 36.400327 -7.510047) (xy 36.361593 -7.587836)
			(xy 36.315846 -7.66172) (xy 36.263477 -7.731067) (xy 36.204933 -7.795287) (xy 36.140713 -7.853831)
			(xy 36.071366 -7.9062) (xy 35.997482 -7.951947) (xy 35.919693 -7.990681) (xy 35.838661 -8.022073)
			(xy 35.755079 -8.045854) (xy 35.669659 -8.061822) (xy 35.58313 -8.06984) (xy 35.49623 -8.06984) (xy 35.409701 -8.061822)
			(xy 35.324281 -8.045854) (xy 35.240699 -8.022073) (xy 35.159667 -7.990681) (xy 35.081878 -7.951947)
			(xy 35.007994 -7.9062) (xy 34.938647 -7.853831) (xy 34.874427 -7.795287) (xy 34.815883 -7.731067)
			(xy 34.763514 -7.66172) (xy 34.717767 -7.587836) (xy 34.679033 -7.510047) (xy 34.647641 -7.429015)
			(xy 34.62386 -7.345433) (xy 34.607892 -7.260013) (xy 34.599874 -7.173484) (xy 31.398916 -7.173484)
			(xy 31.393568 -7.244115) (xy 31.379021 -7.329868) (xy 31.356617 -7.413911) (xy 31.342076 -7.4549)
			(xy 31.328318 -7.491151) (xy 31.295639 -7.561473) (xy 31.276798 -7.595362) (xy 31.255462 -7.6327)
			(xy 31.266892 -7.717536) (xy 31.559246 -8.00989) (xy 31.559246 -9.713484) (xy 34.599874 -9.713484)
			(xy 34.599874 -9.626584) (xy 34.607892 -9.540055) (xy 34.62386 -9.454635) (xy 34.647641 -9.371053)
			(xy 34.679033 -9.290021) (xy 34.717767 -9.212232) (xy 34.763514 -9.138348) (xy 34.815883 -9.069001)
			(xy 34.874427 -9.004781) (xy 34.938647 -8.946237) (xy 35.007994 -8.893868) (xy 35.081878 -8.848121)
			(xy 35.159667 -8.809387) (xy 35.240699 -8.777995) (xy 35.324281 -8.754214) (xy 35.409701 -8.738246)
			(xy 35.49623 -8.730228) (xy 35.58313 -8.730228) (xy 35.669659 -8.738246) (xy 35.755079 -8.754214)
			(xy 35.838661 -8.777995) (xy 35.919693 -8.809387) (xy 35.997482 -8.848121) (xy 36.071366 -8.893868)
			(xy 36.140713 -8.946237) (xy 36.204933 -9.004781) (xy 36.263477 -9.069001) (xy 36.315846 -9.138348)
			(xy 36.361593 -9.212232) (xy 36.400327 -9.290021) (xy 36.431719 -9.371053) (xy 36.4555 -9.454635)
			(xy 36.471468 -9.540055) (xy 36.479486 -9.626584) (xy 36.479988 -9.670034) (xy 36.479486 -9.713484)
			(xy 36.471468 -9.800013) (xy 36.4555 -9.885433) (xy 36.431719 -9.969015) (xy 36.400327 -10.050047)
			(xy 36.361593 -10.127836) (xy 36.315846 -10.20172) (xy 36.263477 -10.271067) (xy 36.204933 -10.335287)
			(xy 36.140713 -10.393831) (xy 36.071366 -10.4462) (xy 35.997482 -10.491947) (xy 35.919693 -10.530681)
			(xy 35.838661 -10.562073) (xy 35.755079 -10.585854) (xy 35.669659 -10.601822) (xy 35.58313 -10.60984)
			(xy 35.49623 -10.60984) (xy 35.409701 -10.601822) (xy 35.324281 -10.585854) (xy 35.240699 -10.562073)
			(xy 35.159667 -10.530681) (xy 35.081878 -10.491947) (xy 35.007994 -10.4462) (xy 34.938647 -10.393831)
			(xy 34.874427 -10.335287) (xy 34.815883 -10.271067) (xy 34.763514 -10.20172) (xy 34.717767 -10.127836)
			(xy 34.679033 -10.050047) (xy 34.647641 -9.969015) (xy 34.62386 -9.885433) (xy 34.607892 -9.800013)
			(xy 34.599874 -9.713484) (xy 31.559246 -9.713484) (xy 31.559246 -12.210253) (xy 34.598948 -12.210253)
			(xy 34.602858 -12.124316) (xy 34.614602 -12.039096) (xy 34.634081 -11.955304) (xy 34.661134 -11.873642)
			(xy 34.695533 -11.794793) (xy 34.736991 -11.719416) (xy 34.785161 -11.648141) (xy 34.83964 -11.581564)
			(xy 34.899974 -11.520242) (xy 34.965656 -11.464688) (xy 35.036139 -11.415367) (xy 35.110833 -11.37269)
			(xy 35.189113 -11.337014) (xy 35.270325 -11.308639) (xy 35.353789 -11.2878) (xy 35.438807 -11.274673)
			(xy 35.524669 -11.269368) (xy 35.610657 -11.271927) (xy 35.696052 -11.282331) (xy 35.780139 -11.300492)
			(xy 35.862216 -11.326259) (xy 35.941596 -11.359415) (xy 36.017615 -11.399684) (xy 36.089638 -11.446728)
			(xy 36.157062 -11.500155) (xy 36.219324 -11.559518) (xy 36.275903 -11.62432) (xy 36.326325 -11.69402)
			(xy 36.37017 -11.768034) (xy 36.389056 -11.806682) (xy 36.397277 -11.8226) (xy 36.421027 -11.849403)
			(xy 36.451301 -11.868532) (xy 36.485704 -11.878474) (xy 36.50361 -11.879072) (xy 39.304214 -11.879072)
			(xy 40.117268 -12.692126) (xy 40.1447 -12.701778) (xy 40.169931 -12.710979) (xy 40.217713 -12.735496)
			(xy 40.261584 -12.766473) (xy 40.300676 -12.803298) (xy 40.334216 -12.845242) (xy 40.361542 -12.891476)
			(xy 40.382111 -12.941085) (xy 40.395519 -12.99309) (xy 40.401499 -13.046461) (xy 40.401166 -13.057886)
			(xy 83.794344 -13.057886) (xy 83.798415 -13.002264) (xy 83.810541 -12.947827) (xy 83.830464 -12.895736)
			(xy 83.85776 -12.847101) (xy 83.891846 -12.802958) (xy 83.931995 -12.764249) (xy 83.977353 -12.731798)
			(xy 84.026953 -12.706297) (xy 84.079737 -12.68829) (xy 84.13458 -12.67816) (xy 84.190314 -12.676123)
			(xy 84.245751 -12.682223) (xy 84.299708 -12.696329) (xy 84.351037 -12.718141) (xy 84.398643 -12.747195)
			(xy 84.441511 -12.78287) (xy 84.478728 -12.824407) (xy 84.509501 -12.87092) (xy 84.533173 -12.921417)
			(xy 84.549241 -12.974824) (xy 84.557361 -13.03) (xy 84.55787 -13.057886) (xy 84.557361 -13.085772)
			(xy 84.55511 -13.101066) (xy 86.072724 -13.101066) (xy 86.076795 -13.045444) (xy 86.088921 -12.991007)
			(xy 86.108844 -12.938916) (xy 86.13614 -12.890281) (xy 86.170226 -12.846138) (xy 86.210375 -12.807429)
			(xy 86.255733 -12.774978) (xy 86.305333 -12.749477) (xy 86.358117 -12.73147) (xy 86.41296 -12.72134)
			(xy 86.468694 -12.719303) (xy 86.524131 -12.725403) (xy 86.578088 -12.739509) (xy 86.629417 -12.761321)
			(xy 86.677023 -12.790375) (xy 86.719891 -12.82605) (xy 86.757108 -12.867587) (xy 86.787881 -12.9141)
			(xy 86.790273 -12.919202) (xy 88.083388 -12.919202) (xy 88.087459 -12.86358) (xy 88.099585 -12.809143)
			(xy 88.119508 -12.757052) (xy 88.146804 -12.708417) (xy 88.18089 -12.664274) (xy 88.221039 -12.625565)
			(xy 88.266397 -12.593114) (xy 88.315997 -12.567613) (xy 88.368781 -12.549606) (xy 88.423624 -12.539476)
			(xy 88.479358 -12.537439) (xy 88.534795 -12.543539) (xy 88.588752 -12.557645) (xy 88.640081 -12.579457)
			(xy 88.687687 -12.608511) (xy 88.730555 -12.644186) (xy 88.767772 -12.685723) (xy 88.798545 -12.732236)
			(xy 88.822217 -12.782733) (xy 88.838285 -12.83614) (xy 88.846405 -12.891316) (xy 88.846914 -12.919202)
			(xy 88.846405 -12.947088) (xy 88.838285 -13.002264) (xy 88.822217 -13.055671) (xy 88.798545 -13.106168)
			(xy 88.767772 -13.152681) (xy 88.730555 -13.194218) (xy 88.687687 -13.229893) (xy 88.6449 -13.256006)
			(xy 91.040456 -13.256006) (xy 91.044527 -13.200384) (xy 91.056653 -13.145947) (xy 91.076576 -13.093856)
			(xy 91.103872 -13.045221) (xy 91.137958 -13.001078) (xy 91.178107 -12.962369) (xy 91.223465 -12.929918)
			(xy 91.273065 -12.904417) (xy 91.325849 -12.88641) (xy 91.380692 -12.87628) (xy 91.436426 -12.874243)
			(xy 91.491863 -12.880343) (xy 91.54582 -12.894449) (xy 91.597149 -12.916261) (xy 91.644755 -12.945315)
			(xy 91.687623 -12.98099) (xy 91.72484 -13.022527) (xy 91.755613 -13.06904) (xy 91.779285 -13.119537)
			(xy 91.795353 -13.172944) (xy 91.803473 -13.22812) (xy 91.803982 -13.256006) (xy 91.803473 -13.283892)
			(xy 91.802082 -13.293344) (xy 92.510862 -13.293344) (xy 92.514933 -13.237722) (xy 92.527059 -13.183285)
			(xy 92.546982 -13.131194) (xy 92.574278 -13.082559) (xy 92.608364 -13.038416) (xy 92.648513 -12.999707)
			(xy 92.693871 -12.967256) (xy 92.743471 -12.941755) (xy 92.796255 -12.923748) (xy 92.851098 -12.913618)
			(xy 92.906832 -12.911581) (xy 92.962269 -12.917681) (xy 93.016226 -12.931787) (xy 93.067555 -12.953599)
			(xy 93.115161 -12.982653) (xy 93.158029 -13.018328) (xy 93.195246 -13.059865) (xy 93.226019 -13.106378)
			(xy 93.249691 -13.156875) (xy 93.265759 -13.210282) (xy 93.271329 -13.248132) (xy 95.94926 -13.248132)
			(xy 95.953331 -13.19251) (xy 95.965457 -13.138073) (xy 95.98538 -13.085982) (xy 96.012676 -13.037347)
			(xy 96.046762 -12.993204) (xy 96.086911 -12.954495) (xy 96.132269 -12.922044) (xy 96.181869 -12.896543)
			(xy 96.234653 -12.878536) (xy 96.289496 -12.868406) (xy 96.34523 -12.866369) (xy 96.400667 -12.872469)
			(xy 96.454624 -12.886575) (xy 96.505953 -12.908387) (xy 96.553559 -12.937441) (xy 96.596427 -12.973116)
			(xy 96.633644 -13.014653) (xy 96.664417 -13.061166) (xy 96.688089 -13.111663) (xy 96.704157 -13.16507)
			(xy 96.712277 -13.220246) (xy 96.712786 -13.248132) (xy 96.712277 -13.276018) (xy 96.704157 -13.331194)
			(xy 96.688089 -13.384601) (xy 96.664417 -13.435098) (xy 96.633644 -13.481611) (xy 96.596427 -13.523148)
			(xy 96.553559 -13.558823) (xy 96.505953 -13.587877) (xy 96.454624 -13.609689) (xy 96.400667 -13.623795)
			(xy 96.34523 -13.629895) (xy 96.289496 -13.627858) (xy 96.234653 -13.617728) (xy 96.181869 -13.599721)
			(xy 96.132269 -13.57422) (xy 96.086911 -13.541769) (xy 96.046762 -13.50306) (xy 96.012676 -13.458917)
			(xy 95.98538 -13.410282) (xy 95.965457 -13.358191) (xy 95.953331 -13.303754) (xy 95.94926 -13.248132)
			(xy 93.271329 -13.248132) (xy 93.273879 -13.265458) (xy 93.274388 -13.293344) (xy 93.273879 -13.32123)
			(xy 93.265759 -13.376406) (xy 93.249691 -13.429813) (xy 93.226019 -13.48031) (xy 93.195246 -13.526823)
			(xy 93.158029 -13.56836) (xy 93.115161 -13.604035) (xy 93.067555 -13.633089) (xy 93.016226 -13.654901)
			(xy 92.962269 -13.669007) (xy 92.906832 -13.675107) (xy 92.851098 -13.67307) (xy 92.796255 -13.66294)
			(xy 92.743471 -13.644933) (xy 92.693871 -13.619432) (xy 92.648513 -13.586981) (xy 92.608364 -13.548272)
			(xy 92.574278 -13.504129) (xy 92.546982 -13.455494) (xy 92.527059 -13.403403) (xy 92.514933 -13.348966)
			(xy 92.510862 -13.293344) (xy 91.802082 -13.293344) (xy 91.795353 -13.339068) (xy 91.779285 -13.392475)
			(xy 91.755613 -13.442972) (xy 91.72484 -13.489485) (xy 91.687623 -13.531022) (xy 91.644755 -13.566697)
			(xy 91.597149 -13.595751) (xy 91.54582 -13.617563) (xy 91.491863 -13.631669) (xy 91.436426 -13.637769)
			(xy 91.380692 -13.635732) (xy 91.325849 -13.625602) (xy 91.273065 -13.607595) (xy 91.223465 -13.582094)
			(xy 91.178107 -13.549643) (xy 91.137958 -13.510934) (xy 91.103872 -13.466791) (xy 91.076576 -13.418156)
			(xy 91.056653 -13.366065) (xy 91.044527 -13.311628) (xy 91.040456 -13.256006) (xy 88.6449 -13.256006)
			(xy 88.640081 -13.258947) (xy 88.588752 -13.280759) (xy 88.534795 -13.294865) (xy 88.479358 -13.300965)
			(xy 88.423624 -13.298928) (xy 88.368781 -13.288798) (xy 88.315997 -13.270791) (xy 88.266397 -13.24529)
			(xy 88.221039 -13.212839) (xy 88.18089 -13.17413) (xy 88.146804 -13.129987) (xy 88.119508 -13.081352)
			(xy 88.099585 -13.029261) (xy 88.087459 -12.974824) (xy 88.083388 -12.919202) (xy 86.790273 -12.919202)
			(xy 86.811553 -12.964597) (xy 86.827621 -13.018004) (xy 86.835741 -13.07318) (xy 86.83625 -13.101066)
			(xy 86.835741 -13.128952) (xy 86.827621 -13.184128) (xy 86.811553 -13.237535) (xy 86.787881 -13.288032)
			(xy 86.757108 -13.334545) (xy 86.719891 -13.376082) (xy 86.677023 -13.411757) (xy 86.629417 -13.440811)
			(xy 86.578088 -13.462623) (xy 86.524131 -13.476729) (xy 86.468694 -13.482829) (xy 86.41296 -13.480792)
			(xy 86.358117 -13.470662) (xy 86.305333 -13.452655) (xy 86.255733 -13.427154) (xy 86.210375 -13.394703)
			(xy 86.170226 -13.355994) (xy 86.13614 -13.311851) (xy 86.108844 -13.263216) (xy 86.088921 -13.211125)
			(xy 86.076795 -13.156688) (xy 86.072724 -13.101066) (xy 84.55511 -13.101066) (xy 84.549241 -13.140948)
			(xy 84.533173 -13.194355) (xy 84.509501 -13.244852) (xy 84.478728 -13.291365) (xy 84.441511 -13.332902)
			(xy 84.398643 -13.368577) (xy 84.351037 -13.397631) (xy 84.299708 -13.419443) (xy 84.245751 -13.433549)
			(xy 84.190314 -13.439649) (xy 84.13458 -13.437612) (xy 84.079737 -13.427482) (xy 84.026953 -13.409475)
			(xy 83.977353 -13.383974) (xy 83.931995 -13.351523) (xy 83.891846 -13.312814) (xy 83.85776 -13.268671)
			(xy 83.830464 -13.220036) (xy 83.810541 -13.167945) (xy 83.798415 -13.113508) (xy 83.794344 -13.057886)
			(xy 40.401166 -13.057886) (xy 40.399934 -13.100143) (xy 40.390855 -13.153075) (xy 40.37444 -13.204211)
			(xy 40.36314 -13.228574) (xy 40.35044 -13.254736) (xy 40.35044 -13.65631) (xy 40.295068 -13.711682)
			(xy 40.283607 -13.723815) (xy 40.266893 -13.752692) (xy 40.25824 -13.784916) (xy 40.25824 -13.818281)
			(xy 40.266892 -13.850505) (xy 40.283605 -13.879383) (xy 40.295068 -13.891514) (xy 40.319452 -13.915898)
			(xy 40.386 -13.93317) (xy 40.419274 -13.923772) (xy 40.453172 -13.914767) (xy 40.522636 -13.905075)
			(xy 40.557704 -13.904468) (xy 41.245536 -13.904468) (xy 41.277494 -13.90502) (xy 41.340906 -13.913035)
			(xy 41.402813 -13.928934) (xy 41.462239 -13.952466) (xy 41.518248 -13.983261) (xy 41.569956 -14.020832)
			(xy 41.616547 -14.064587) (xy 41.657287 -14.113837) (xy 41.691534 -14.167804) (xy 41.718747 -14.225638)
			(xy 41.738497 -14.286426) (xy 41.750473 -14.34921) (xy 41.754487 -14.413) (xy 41.750473 -14.47679)
			(xy 41.743488 -14.513407) (xy 60.567562 -14.513407) (xy 60.567562 -14.442085) (xy 60.575548 -14.371211)
			(xy 60.591418 -14.301676) (xy 60.614975 -14.234356) (xy 60.64592 -14.170097) (xy 60.683866 -14.109706)
			(xy 60.728335 -14.053944) (xy 60.778768 -14.003511) (xy 60.83453 -13.959042) (xy 60.894921 -13.921096)
			(xy 60.95918 -13.890151) (xy 61.0265 -13.866594) (xy 61.096035 -13.850724) (xy 61.166909 -13.842738)
			(xy 61.238231 -13.842738) (xy 61.309105 -13.850724) (xy 61.37864 -13.866594) (xy 61.44596 -13.890151)
			(xy 61.510219 -13.921096) (xy 61.57061 -13.959042) (xy 61.626372 -14.003511) (xy 61.676805 -14.053944)
			(xy 61.721274 -14.109706) (xy 61.75922 -14.170097) (xy 61.790165 -14.234356) (xy 61.813722 -14.301676)
			(xy 61.829592 -14.371211) (xy 61.837578 -14.442085) (xy 61.838078 -14.477746) (xy 61.837578 -14.513407)
			(xy 62.471546 -14.513407) (xy 62.471546 -14.442085) (xy 62.479532 -14.371211) (xy 62.495402 -14.301676)
			(xy 62.518959 -14.234356) (xy 62.549904 -14.170097) (xy 62.58785 -14.109706) (xy 62.632319 -14.053944)
			(xy 62.682752 -14.003511) (xy 62.738514 -13.959042) (xy 62.798905 -13.921096) (xy 62.863164 -13.890151)
			(xy 62.930484 -13.866594) (xy 63.000019 -13.850724) (xy 63.070893 -13.842738) (xy 63.142215 -13.842738)
			(xy 63.213089 -13.850724) (xy 63.282624 -13.866594) (xy 63.349944 -13.890151) (xy 63.414203 -13.921096)
			(xy 63.474594 -13.959042) (xy 63.530356 -14.003511) (xy 63.580789 -14.053944) (xy 63.625258 -14.109706)
			(xy 63.663204 -14.170097) (xy 63.691731 -14.229334) (xy 84.425788 -14.229334) (xy 84.429859 -14.173712)
			(xy 84.441985 -14.119275) (xy 84.461908 -14.067184) (xy 84.489204 -14.018549) (xy 84.52329 -13.974406)
			(xy 84.563439 -13.935697) (xy 84.608797 -13.903246) (xy 84.658397 -13.877745) (xy 84.711181 -13.859738)
			(xy 84.766024 -13.849608) (xy 84.821758 -13.847571) (xy 84.877195 -13.853671) (xy 84.931152 -13.867777)
			(xy 84.982481 -13.889589) (xy 85.030087 -13.918643) (xy 85.072955 -13.954318) (xy 85.110172 -13.995855)
			(xy 85.140945 -14.042368) (xy 85.164617 -14.092865) (xy 85.180685 -14.146272) (xy 85.188805 -14.201448)
			(xy 85.189314 -14.229334) (xy 85.188805 -14.25722) (xy 85.186592 -14.27226) (xy 87.270588 -14.27226)
			(xy 87.274659 -14.216638) (xy 87.286785 -14.162201) (xy 87.306708 -14.11011) (xy 87.334004 -14.061475)
			(xy 87.36809 -14.017332) (xy 87.408239 -13.978623) (xy 87.453597 -13.946172) (xy 87.503197 -13.920671)
			(xy 87.555981 -13.902664) (xy 87.610824 -13.892534) (xy 87.666558 -13.890497) (xy 87.721995 -13.896597)
			(xy 87.775952 -13.910703) (xy 87.827281 -13.932515) (xy 87.874887 -13.961569) (xy 87.917755 -13.997244)
			(xy 87.954972 -14.038781) (xy 87.985745 -14.085294) (xy 88.009417 -14.135791) (xy 88.025485 -14.189198)
			(xy 88.033605 -14.244374) (xy 88.033817 -14.256004) (xy 94.157798 -14.256004) (xy 94.161869 -14.200382)
			(xy 94.173995 -14.145945) (xy 94.193918 -14.093854) (xy 94.221214 -14.045219) (xy 94.2553 -14.001076)
			(xy 94.295449 -13.962367) (xy 94.340807 -13.929916) (xy 94.390407 -13.904415) (xy 94.443191 -13.886408)
			(xy 94.498034 -13.876278) (xy 94.553768 -13.874241) (xy 94.609205 -13.880341) (xy 94.663162 -13.894447)
			(xy 94.714491 -13.916259) (xy 94.762097 -13.945313) (xy 94.804965 -13.980988) (xy 94.842182 -14.022525)
			(xy 94.872955 -14.069038) (xy 94.896627 -14.119535) (xy 94.912695 -14.172942) (xy 94.920815 -14.228118)
			(xy 94.921324 -14.256004) (xy 94.920815 -14.28389) (xy 94.912695 -14.339066) (xy 94.896627 -14.392473)
			(xy 94.872955 -14.44297) (xy 94.842182 -14.489483) (xy 94.804965 -14.53102) (xy 94.762097 -14.566695)
			(xy 94.714491 -14.595749) (xy 94.663162 -14.617561) (xy 94.609205 -14.631667) (xy 94.553768 -14.637767)
			(xy 94.498034 -14.63573) (xy 94.443191 -14.6256) (xy 94.390407 -14.607593) (xy 94.340807 -14.582092)
			(xy 94.295449 -14.549641) (xy 94.2553 -14.510932) (xy 94.221214 -14.466789) (xy 94.193918 -14.418154)
			(xy 94.173995 -14.366063) (xy 94.161869 -14.311626) (xy 94.157798 -14.256004) (xy 88.033817 -14.256004)
			(xy 88.034114 -14.27226) (xy 88.033605 -14.300146) (xy 88.025485 -14.355322) (xy 88.009417 -14.408729)
			(xy 87.985745 -14.459226) (xy 87.954972 -14.505739) (xy 87.917755 -14.547276) (xy 87.874887 -14.582951)
			(xy 87.827281 -14.612005) (xy 87.775952 -14.633817) (xy 87.721995 -14.647923) (xy 87.666558 -14.654023)
			(xy 87.610824 -14.651986) (xy 87.555981 -14.641856) (xy 87.503197 -14.623849) (xy 87.453597 -14.598348)
			(xy 87.408239 -14.565897) (xy 87.36809 -14.527188) (xy 87.334004 -14.483045) (xy 87.306708 -14.43441)
			(xy 87.286785 -14.382319) (xy 87.274659 -14.327882) (xy 87.270588 -14.27226) (xy 85.186592 -14.27226)
			(xy 85.180685 -14.312396) (xy 85.164617 -14.365803) (xy 85.140945 -14.4163) (xy 85.110172 -14.462813)
			(xy 85.072955 -14.50435) (xy 85.030087 -14.540025) (xy 84.982481 -14.569079) (xy 84.931152 -14.590891)
			(xy 84.877195 -14.604997) (xy 84.821758 -14.611097) (xy 84.766024 -14.60906) (xy 84.711181 -14.59893)
			(xy 84.658397 -14.580923) (xy 84.608797 -14.555422) (xy 84.563439 -14.522971) (xy 84.52329 -14.484262)
			(xy 84.489204 -14.440119) (xy 84.461908 -14.391484) (xy 84.441985 -14.339393) (xy 84.429859 -14.284956)
			(xy 84.425788 -14.229334) (xy 63.691731 -14.229334) (xy 63.694149 -14.234356) (xy 63.717706 -14.301676)
			(xy 63.733576 -14.371211) (xy 63.741562 -14.442085) (xy 63.742062 -14.477746) (xy 63.741562 -14.513407)
			(xy 63.733576 -14.584281) (xy 63.717706 -14.653816) (xy 63.694149 -14.721136) (xy 63.663204 -14.785395)
			(xy 63.625258 -14.845786) (xy 63.580789 -14.901548) (xy 63.530356 -14.951981) (xy 63.474594 -14.99645)
			(xy 63.414203 -15.034396) (xy 63.349944 -15.065341) (xy 63.282624 -15.088898) (xy 63.213089 -15.104768)
			(xy 63.142215 -15.112754) (xy 63.070893 -15.112754) (xy 63.000019 -15.104768) (xy 62.930484 -15.088898)
			(xy 62.863164 -15.065341) (xy 62.798905 -15.034396) (xy 62.738514 -14.99645) (xy 62.682752 -14.951981)
			(xy 62.632319 -14.901548) (xy 62.58785 -14.845786) (xy 62.549904 -14.785395) (xy 62.518959 -14.721136)
			(xy 62.495402 -14.653816) (xy 62.479532 -14.584281) (xy 62.471546 -14.513407) (xy 61.837578 -14.513407)
			(xy 61.829592 -14.584281) (xy 61.813722 -14.653816) (xy 61.790165 -14.721136) (xy 61.75922 -14.785395)
			(xy 61.721274 -14.845786) (xy 61.676805 -14.901548) (xy 61.626372 -14.951981) (xy 61.57061 -14.99645)
			(xy 61.510219 -15.034396) (xy 61.44596 -15.065341) (xy 61.37864 -15.088898) (xy 61.309105 -15.104768)
			(xy 61.238231 -15.112754) (xy 61.166909 -15.112754) (xy 61.096035 -15.104768) (xy 61.0265 -15.088898)
			(xy 60.95918 -15.065341) (xy 60.894921 -15.034396) (xy 60.83453 -14.99645) (xy 60.778768 -14.951981)
			(xy 60.728335 -14.901548) (xy 60.683866 -14.845786) (xy 60.64592 -14.785395) (xy 60.614975 -14.721136)
			(xy 60.591418 -14.653816) (xy 60.575548 -14.584281) (xy 60.567562 -14.513407) (xy 41.743488 -14.513407)
			(xy 41.738497 -14.539574) (xy 41.718747 -14.600362) (xy 41.691534 -14.658196) (xy 41.657287 -14.712163)
			(xy 41.616547 -14.761413) (xy 41.569956 -14.805168) (xy 41.518248 -14.842739) (xy 41.462239 -14.873534)
			(xy 41.402813 -14.897066) (xy 41.340906 -14.912965) (xy 41.277494 -14.92098) (xy 41.245536 -14.921484)
			(xy 40.557704 -14.921484) (xy 40.525002 -14.920958) (xy 40.46014 -14.912565) (xy 40.396891 -14.895919)
			(xy 40.336301 -14.871293) (xy 40.279372 -14.839096) (xy 40.252904 -14.819884) (xy 40.219122 -14.794484)
			(xy 39.401496 -14.794484) (xy 39.401496 -14.031468) (xy 39.426896 -14.031468) (xy 39.426896 -13.644626)
			(xy 39.689024 -13.382498) (xy 39.689024 -13.254736) (xy 39.676324 -13.228574) (xy 39.671551 -13.218444)
			(xy 39.663034 -13.197731) (xy 39.659306 -13.187172) (xy 39.649654 -13.15974) (xy 39.030402 -12.540488)
			(xy 36.467034 -12.540488) (xy 36.405058 -12.579858) (xy 36.38931 -12.612878) (xy 36.370408 -12.651519)
			(xy 36.326603 -12.725557) (xy 36.276218 -12.795283) (xy 36.219674 -12.860116) (xy 36.157444 -12.919512)
			(xy 36.090049 -12.972976) (xy 36.018051 -13.020059) (xy 35.942054 -13.060369) (xy 35.862692 -13.093568)
			(xy 35.780629 -13.119378) (xy 35.696552 -13.137584) (xy 35.611163 -13.148034) (xy 35.525176 -13.15064)
			(xy 35.439311 -13.145381) (xy 35.354285 -13.1323) (xy 35.27081 -13.111506) (xy 35.189583 -13.083174)
			(xy 35.111284 -13.047541) (xy 35.036568 -13.004904) (xy 34.966058 -12.955621) (xy 34.900345 -12.900102)
			(xy 34.839979 -12.838813) (xy 34.785463 -12.772265) (xy 34.737255 -12.701016) (xy 34.695756 -12.625662)
			(xy 34.661315 -12.546831) (xy 34.634219 -12.465184) (xy 34.614694 -12.381403) (xy 34.602904 -12.296188)
			(xy 34.598948 -12.210253) (xy 31.559246 -12.210253) (xy 31.559246 -14.418056) (xy 31.934674 -14.793484)
			(xy 34.599874 -14.793484) (xy 34.599874 -14.706584) (xy 34.607892 -14.620055) (xy 34.62386 -14.534635)
			(xy 34.647641 -14.451053) (xy 34.679033 -14.370021) (xy 34.717767 -14.292232) (xy 34.763514 -14.218348)
			(xy 34.815883 -14.149001) (xy 34.874427 -14.084781) (xy 34.938647 -14.026237) (xy 35.007994 -13.973868)
			(xy 35.081878 -13.928121) (xy 35.159667 -13.889387) (xy 35.240699 -13.857995) (xy 35.324281 -13.834214)
			(xy 35.409701 -13.818246) (xy 35.49623 -13.810228) (xy 35.58313 -13.810228) (xy 35.669659 -13.818246)
			(xy 35.755079 -13.834214) (xy 35.838661 -13.857995) (xy 35.919693 -13.889387) (xy 35.997482 -13.928121)
			(xy 36.071366 -13.973868) (xy 36.140713 -14.026237) (xy 36.204933 -14.084781) (xy 36.263477 -14.149001)
			(xy 36.315846 -14.218348) (xy 36.361593 -14.292232) (xy 36.400327 -14.370021) (xy 36.431719 -14.451053)
			(xy 36.4555 -14.534635) (xy 36.471468 -14.620055) (xy 36.479486 -14.706584) (xy 36.479988 -14.750034)
			(xy 36.479486 -14.793484) (xy 36.471468 -14.880013) (xy 36.4555 -14.965433) (xy 36.431719 -15.049015)
			(xy 36.400327 -15.130047) (xy 36.361593 -15.207836) (xy 36.315846 -15.28172) (xy 36.263477 -15.351067)
			(xy 36.204933 -15.415287) (xy 36.140713 -15.473831) (xy 36.071366 -15.5262) (xy 35.997482 -15.571947)
			(xy 35.919693 -15.610681) (xy 35.838661 -15.642073) (xy 35.755079 -15.665854) (xy 35.669659 -15.681822)
			(xy 35.58313 -15.68984) (xy 35.49623 -15.68984) (xy 35.409701 -15.681822) (xy 35.324281 -15.665854)
			(xy 35.240699 -15.642073) (xy 35.159667 -15.610681) (xy 35.081878 -15.571947) (xy 35.007994 -15.5262)
			(xy 34.938647 -15.473831) (xy 34.874427 -15.415287) (xy 34.815883 -15.351067) (xy 34.763514 -15.28172)
			(xy 34.717767 -15.207836) (xy 34.679033 -15.130047) (xy 34.647641 -15.049015) (xy 34.62386 -14.965433)
			(xy 34.607892 -14.880013) (xy 34.599874 -14.793484) (xy 31.934674 -14.793484) (xy 33.527492 -16.386302)
			(xy 35.27933 -16.386302) (xy 35.295586 -16.381984) (xy 35.3278 -16.373616) (xy 35.39314 -16.360906)
			(xy 35.426142 -16.356584) (xy 35.470066 -16.351733) (xy 35.55841 -16.349309) (xy 35.646592 -16.355189)
			(xy 35.733831 -16.369322) (xy 35.819359 -16.391582) (xy 35.881979 -16.414343) (xy 60.567562 -16.414343)
			(xy 60.567562 -16.343021) (xy 60.575548 -16.272147) (xy 60.591418 -16.202612) (xy 60.614975 -16.135292)
			(xy 60.64592 -16.071033) (xy 60.683866 -16.010642) (xy 60.728335 -15.95488) (xy 60.778768 -15.904447)
			(xy 60.83453 -15.859978) (xy 60.894921 -15.822032) (xy 60.95918 -15.791087) (xy 61.0265 -15.76753)
			(xy 61.096035 -15.75166) (xy 61.166909 -15.743674) (xy 61.238231 -15.743674) (xy 61.309105 -15.75166)
			(xy 61.37864 -15.76753) (xy 61.44596 -15.791087) (xy 61.510219 -15.822032) (xy 61.57061 -15.859978)
			(xy 61.626372 -15.904447) (xy 61.676805 -15.95488) (xy 61.721274 -16.010642) (xy 61.75922 -16.071033)
			(xy 61.790165 -16.135292) (xy 61.813722 -16.202612) (xy 61.829592 -16.272147) (xy 61.837578 -16.343021)
			(xy 61.838078 -16.378682) (xy 61.837578 -16.414343) (xy 62.471546 -16.414343) (xy 62.471546 -16.343021)
			(xy 62.479532 -16.272147) (xy 62.495402 -16.202612) (xy 62.518959 -16.135292) (xy 62.549904 -16.071033)
			(xy 62.58785 -16.010642) (xy 62.632319 -15.95488) (xy 62.682752 -15.904447) (xy 62.738514 -15.859978)
			(xy 62.798905 -15.822032) (xy 62.863164 -15.791087) (xy 62.930484 -15.76753) (xy 63.000019 -15.75166)
			(xy 63.070893 -15.743674) (xy 63.142215 -15.743674) (xy 63.213089 -15.75166) (xy 63.282624 -15.76753)
			(xy 63.349944 -15.791087) (xy 63.414203 -15.822032) (xy 63.474594 -15.859978) (xy 63.530356 -15.904447)
			(xy 63.580789 -15.95488) (xy 63.625258 -16.010642) (xy 63.663204 -16.071033) (xy 63.694149 -16.135292)
			(xy 63.717706 -16.202612) (xy 63.733576 -16.272147) (xy 63.741562 -16.343021) (xy 63.742062 -16.378682)
			(xy 63.741562 -16.414343) (xy 63.733576 -16.485217) (xy 63.717706 -16.554752) (xy 63.694149 -16.622072)
			(xy 63.663204 -16.686331) (xy 63.625258 -16.746722) (xy 63.580789 -16.802484) (xy 63.530356 -16.852917)
			(xy 63.474594 -16.897386) (xy 63.414203 -16.935332) (xy 63.349944 -16.966277) (xy 63.282624 -16.989834)
			(xy 63.213089 -17.005704) (xy 63.142215 -17.01369) (xy 63.070893 -17.01369) (xy 63.000019 -17.005704)
			(xy 62.930484 -16.989834) (xy 62.863164 -16.966277) (xy 62.798905 -16.935332) (xy 62.738514 -16.897386)
			(xy 62.682752 -16.852917) (xy 62.632319 -16.802484) (xy 62.58785 -16.746722) (xy 62.549904 -16.686331)
			(xy 62.518959 -16.622072) (xy 62.495402 -16.554752) (xy 62.479532 -16.485217) (xy 62.471546 -16.414343)
			(xy 61.837578 -16.414343) (xy 61.829592 -16.485217) (xy 61.813722 -16.554752) (xy 61.790165 -16.622072)
			(xy 61.75922 -16.686331) (xy 61.721274 -16.746722) (xy 61.676805 -16.802484) (xy 61.626372 -16.852917)
			(xy 61.57061 -16.897386) (xy 61.510219 -16.935332) (xy 61.44596 -16.966277) (xy 61.37864 -16.989834)
			(xy 61.309105 -17.005704) (xy 61.238231 -17.01369) (xy 61.166909 -17.01369) (xy 61.096035 -17.005704)
			(xy 61.0265 -16.989834) (xy 60.95918 -16.966277) (xy 60.894921 -16.935332) (xy 60.83453 -16.897386)
			(xy 60.778768 -16.852917) (xy 60.728335 -16.802484) (xy 60.683866 -16.746722) (xy 60.64592 -16.686331)
			(xy 60.614975 -16.622072) (xy 60.591418 -16.554752) (xy 60.575548 -16.485217) (xy 60.567562 -16.414343)
			(xy 35.881979 -16.414343) (xy 35.90242 -16.421773) (xy 35.982279 -16.459628) (xy 36.020502 -16.481806)
			(xy 41.125648 -16.481806) (xy 41.15689 -16.513048) (xy 41.547034 -16.513048) (xy 41.858946 -16.82496)
			(xy 41.858946 -17.203928) (xy 74.290428 -17.203928) (xy 74.290428 -16.184372) (xy 74.291055 -16.148314)
			(xy 74.301257 -16.076924) (xy 74.310748 -16.042132) (xy 74.315828 -16.024606) (xy 74.315828 -15.650464)
			(xy 75.281536 -15.650464) (xy 75.281536 -16.024606) (xy 75.286616 -16.042132) (xy 75.296102 -16.076925)
			(xy 75.306303 -16.148315) (xy 75.306936 -16.184372) (xy 75.306936 -16.199612) (xy 75.612244 -16.199612)
			(xy 75.612244 -15.339822) (xy 75.612742 -15.307095) (xy 75.621135 -15.242183) (xy 75.637785 -15.178883)
			(xy 75.662417 -15.118242) (xy 75.694625 -15.061261) (xy 75.713844 -15.034768) (xy 75.739244 -15.000986)
			(xy 75.739244 -14.983968) (xy 75.754484 -14.983968) (xy 75.790298 -14.953488) (xy 75.815475 -14.932635)
			(xy 75.870207 -14.896884) (xy 75.929072 -14.868445) (xy 75.991097 -14.84779) (xy 76.055259 -14.835259)
			(xy 76.120498 -14.831059) (xy 76.185737 -14.835259) (xy 76.249899 -14.84779) (xy 76.311924 -14.868445)
			(xy 76.370789 -14.896884) (xy 76.425521 -14.932635) (xy 76.450698 -14.953488) (xy 76.486512 -14.983968)
			(xy 76.501752 -14.983968) (xy 76.501752 -15.000986) (xy 76.527152 -15.034768) (xy 76.540326 -15.052701)
			(xy 76.563857 -15.090473) (xy 76.574142 -15.110206) (xy 76.581564 -15.123913) (xy 76.601935 -15.147495)
			(xy 76.627421 -15.165425) (xy 76.656498 -15.176631) (xy 76.687426 -15.180443) (xy 76.718354 -15.176631)
			(xy 76.747431 -15.165425) (xy 76.772917 -15.147495) (xy 76.793288 -15.123913) (xy 76.80071 -15.110206)
			(xy 76.810986 -15.090468) (xy 76.834517 -15.052695) (xy 76.8477 -15.034768) (xy 76.8731 -15.000986)
			(xy 76.8731 -14.983968) (xy 76.88834 -14.983968) (xy 76.924154 -14.953488) (xy 76.949331 -14.932635)
			(xy 77.004063 -14.896884) (xy 77.062928 -14.868445) (xy 77.124953 -14.84779) (xy 77.189115 -14.835259)
			(xy 77.254354 -14.831059) (xy 77.319593 -14.835259) (xy 77.383755 -14.84779) (xy 77.44578 -14.868445)
			(xy 77.504645 -14.896884) (xy 77.559377 -14.932635) (xy 77.584554 -14.953488) (xy 77.620368 -14.983968)
			(xy 77.635608 -14.983968) (xy 77.635608 -15.000986) (xy 77.661008 -15.034768) (xy 77.675361 -15.054372)
			(xy 77.700677 -15.095846) (xy 77.711554 -15.117572) (xy 77.718885 -15.131602) (xy 77.73927 -15.155806)
			(xy 77.764987 -15.174246) (xy 77.794454 -15.185784) (xy 77.825854 -15.189711) (xy 77.857254 -15.185784)
			(xy 77.886721 -15.174246) (xy 77.912438 -15.155806) (xy 77.932823 -15.131602) (xy 77.940154 -15.117572)
			(xy 77.951033 -15.095847) (xy 77.976348 -15.054373) (xy 77.9907 -15.034768) (xy 78.0161 -15.000986)
			(xy 78.0161 -14.983968) (xy 78.03134 -14.983968) (xy 78.067154 -14.953488) (xy 78.092331 -14.932635)
			(xy 78.147063 -14.896884) (xy 78.205928 -14.868445) (xy 78.267953 -14.84779) (xy 78.332115 -14.835259)
			(xy 78.397354 -14.831059) (xy 78.462593 -14.835259) (xy 78.526755 -14.84779) (xy 78.58878 -14.868445)
			(xy 78.647645 -14.896884) (xy 78.702377 -14.932635) (xy 78.727554 -14.953488) (xy 78.763368 -14.983968)
			(xy 78.778608 -14.983968) (xy 78.778608 -15.000986) (xy 78.804008 -15.034768) (xy 78.816312 -15.051538)
			(xy 78.838437 -15.086762) (xy 78.848204 -15.105126) (xy 78.855711 -15.118619) (xy 78.876116 -15.141782)
			(xy 78.901487 -15.159369) (xy 78.930337 -15.17035) (xy 78.96098 -15.174083) (xy 78.991623 -15.17035)
			(xy 79.020473 -15.159369) (xy 79.045844 -15.141782) (xy 79.066249 -15.118619) (xy 79.073756 -15.105126)
			(xy 79.083532 -15.086768) (xy 79.105661 -15.051547) (xy 79.117952 -15.034768) (xy 79.143352 -15.000986)
			(xy 79.143352 -14.983968) (xy 79.158592 -14.983968) (xy 79.194406 -14.953488) (xy 79.219583 -14.932635)
			(xy 79.274315 -14.896884) (xy 79.33318 -14.868445) (xy 79.395205 -14.84779) (xy 79.459367 -14.835259)
			(xy 79.524606 -14.831059) (xy 79.589845 -14.835259) (xy 79.654007 -14.84779) (xy 79.716032 -14.868445)
			(xy 79.774897 -14.896884) (xy 79.829629 -14.932635) (xy 79.854806 -14.953488) (xy 79.89062 -14.983968)
			(xy 79.90586 -14.983968) (xy 79.90586 -15.000986) (xy 79.93126 -15.034768) (xy 79.944863 -15.053335)
			(xy 79.96903 -15.092512) (xy 79.97952 -15.113) (xy 79.986923 -15.126835) (xy 80.00733 -15.150659)
			(xy 80.032931 -15.168785) (xy 80.062181 -15.180118) (xy 80.093312 -15.183973) (xy 80.124443 -15.180118)
			(xy 80.153693 -15.168785) (xy 80.179294 -15.150659) (xy 80.199701 -15.126835) (xy 80.207104 -15.113)
			(xy 80.217603 -15.092517) (xy 80.241768 -15.05334) (xy 80.255364 -15.034768) (xy 80.280764 -15.000986)
			(xy 80.280764 -14.983968) (xy 80.296004 -14.983968) (xy 80.331818 -14.953488) (xy 80.356995 -14.932635)
			(xy 80.411727 -14.896884) (xy 80.470592 -14.868445) (xy 80.532617 -14.84779) (xy 80.596779 -14.835259)
			(xy 80.662018 -14.831059) (xy 80.727257 -14.835259) (xy 80.791419 -14.84779) (xy 80.853444 -14.868445)
			(xy 80.912309 -14.896884) (xy 80.967041 -14.932635) (xy 80.992218 -14.953488) (xy 81.028032 -14.983968)
			(xy 81.043272 -14.983968) (xy 81.043272 -15.000986) (xy 81.068672 -15.034768) (xy 81.080974 -15.051539)
			(xy 81.103101 -15.086763) (xy 81.112868 -15.105126) (xy 81.120375 -15.118619) (xy 81.14078 -15.141782)
			(xy 81.166151 -15.159369) (xy 81.195001 -15.17035) (xy 81.225644 -15.174083) (xy 81.256287 -15.17035)
			(xy 81.285137 -15.159369) (xy 81.310508 -15.141782) (xy 81.330913 -15.118619) (xy 81.33842 -15.105126)
			(xy 81.348198 -15.086769) (xy 81.370325 -15.051547) (xy 81.382616 -15.034768) (xy 81.408016 -15.000986)
			(xy 81.408016 -14.983968) (xy 81.423256 -14.983968) (xy 81.45907 -14.953488) (xy 81.484247 -14.932635)
			(xy 81.538979 -14.896884) (xy 81.597844 -14.868445) (xy 81.659869 -14.84779) (xy 81.724031 -14.835259)
			(xy 81.78927 -14.831059) (xy 81.854509 -14.835259) (xy 81.899337 -14.844014) (xy 96.02927 -14.844014)
			(xy 96.033341 -14.788392) (xy 96.045467 -14.733955) (xy 96.06539 -14.681864) (xy 96.092686 -14.633229)
			(xy 96.126772 -14.589086) (xy 96.166921 -14.550377) (xy 96.212279 -14.517926) (xy 96.261879 -14.492425)
			(xy 96.314663 -14.474418) (xy 96.369506 -14.464288) (xy 96.42524 -14.462251) (xy 96.480677 -14.468351)
			(xy 96.534634 -14.482457) (xy 96.585963 -14.504269) (xy 96.633569 -14.533323) (xy 96.676437 -14.568998)
			(xy 96.713654 -14.610535) (xy 96.744427 -14.657048) (xy 96.768099 -14.707545) (xy 96.784167 -14.760952)
			(xy 96.792287 -14.816128) (xy 96.792796 -14.844014) (xy 96.792287 -14.8719) (xy 96.784167 -14.927076)
			(xy 96.768099 -14.980483) (xy 96.744427 -15.03098) (xy 96.713654 -15.077493) (xy 96.676437 -15.11903)
			(xy 96.633569 -15.154705) (xy 96.585963 -15.183759) (xy 96.534634 -15.205571) (xy 96.480677 -15.219677)
			(xy 96.42524 -15.225777) (xy 96.369506 -15.22374) (xy 96.314663 -15.21361) (xy 96.261879 -15.195603)
			(xy 96.212279 -15.170102) (xy 96.166921 -15.137651) (xy 96.126772 -15.098942) (xy 96.092686 -15.054799)
			(xy 96.06539 -15.006164) (xy 96.045467 -14.954073) (xy 96.033341 -14.899636) (xy 96.02927 -14.844014)
			(xy 81.899337 -14.844014) (xy 81.918671 -14.84779) (xy 81.980696 -14.868445) (xy 82.039561 -14.896884)
			(xy 82.094293 -14.932635) (xy 82.11947 -14.953488) (xy 82.155284 -14.983968) (xy 82.170524 -14.983968)
			(xy 82.170524 -15.000986) (xy 82.195924 -15.034768) (xy 82.215147 -15.061261) (xy 82.247377 -15.118231)
			(xy 82.272019 -15.178871) (xy 82.288664 -15.242176) (xy 82.297034 -15.307094) (xy 82.297524 -15.339822)
			(xy 82.297524 -15.635986) (xy 85.52764 -15.635986) (xy 85.531711 -15.580364) (xy 85.543837 -15.525927)
			(xy 85.56376 -15.473836) (xy 85.591056 -15.425201) (xy 85.625142 -15.381058) (xy 85.665291 -15.342349)
			(xy 85.710649 -15.309898) (xy 85.760249 -15.284397) (xy 85.813033 -15.26639) (xy 85.867876 -15.25626)
			(xy 85.92361 -15.254223) (xy 85.979047 -15.260323) (xy 86.033004 -15.274429) (xy 86.084333 -15.296241)
			(xy 86.131939 -15.325295) (xy 86.174807 -15.36097) (xy 86.212024 -15.402507) (xy 86.242797 -15.44902)
			(xy 86.266469 -15.499517) (xy 86.282537 -15.552924) (xy 86.290657 -15.6081) (xy 86.291166 -15.635986)
			(xy 86.290657 -15.663872) (xy 86.282537 -15.719048) (xy 86.266469 -15.772455) (xy 86.242797 -15.822952)
			(xy 86.212024 -15.869465) (xy 86.174807 -15.911002) (xy 86.131939 -15.946677) (xy 86.084333 -15.975731)
			(xy 86.033004 -15.997543) (xy 85.979047 -16.011649) (xy 85.92361 -16.017749) (xy 85.867876 -16.015712)
			(xy 85.813033 -16.005582) (xy 85.760249 -15.987575) (xy 85.710649 -15.962074) (xy 85.665291 -15.929623)
			(xy 85.625142 -15.890914) (xy 85.591056 -15.846771) (xy 85.56376 -15.798136) (xy 85.543837 -15.746045)
			(xy 85.531711 -15.691608) (xy 85.52764 -15.635986) (xy 82.297524 -15.635986) (xy 82.297524 -16.199612)
			(xy 82.297087 -16.231764) (xy 82.288953 -16.295552) (xy 82.272842 -16.357806) (xy 82.24901 -16.417531)
			(xy 82.217838 -16.473775) (xy 82.179824 -16.525641) (xy 82.135574 -16.572299) (xy 82.085795 -16.613007)
			(xy 82.03128 -16.647113) (xy 81.972901 -16.674074) (xy 81.911588 -16.69346) (xy 81.84832 -16.70496)
			(xy 81.784107 -16.708392) (xy 81.719974 -16.703701) (xy 81.656944 -16.690962) (xy 81.596023 -16.670377)
			(xy 81.538184 -16.642276) (xy 81.484349 -16.607107) (xy 81.435377 -16.565431) (xy 81.41335 -16.542004)
			(xy 81.397155 -16.524978) (xy 81.359671 -16.496648) (xy 81.317618 -16.475693) (xy 81.272429 -16.462827)
			(xy 81.225644 -16.45849) (xy 81.178859 -16.462827) (xy 81.13367 -16.475693) (xy 81.091617 -16.496648)
			(xy 81.054133 -16.524978) (xy 81.037938 -16.542004) (xy 81.015521 -16.565879) (xy 80.965557 -16.608222)
			(xy 80.910571 -16.6438) (xy 80.851471 -16.672024) (xy 80.789238 -16.692426) (xy 80.724899 -16.70467)
			(xy 80.659522 -16.708552) (xy 80.594187 -16.704008) (xy 80.529976 -16.691113) (xy 80.467952 -16.670081)
			(xy 80.409142 -16.641261) (xy 80.354518 -16.605128) (xy 80.304986 -16.562281) (xy 80.282796 -16.538194)
			(xy 80.266557 -16.520809) (xy 80.228832 -16.491838) (xy 80.186375 -16.470391) (xy 80.14067 -16.457215)
			(xy 80.093312 -16.452771) (xy 80.045954 -16.457215) (xy 80.000249 -16.470391) (xy 79.957792 -16.491838)
			(xy 79.920067 -16.520809) (xy 79.903828 -16.538194) (xy 79.881603 -16.562253) (xy 79.832086 -16.605121)
			(xy 79.777472 -16.641274) (xy 79.718667 -16.670113) (xy 79.656644 -16.691158) (xy 79.592432 -16.704062)
			(xy 79.527094 -16.70861) (xy 79.461713 -16.704728) (xy 79.397373 -16.69248) (xy 79.335139 -16.672068)
			(xy 79.276042 -16.643831) (xy 79.221063 -16.608237) (xy 79.171111 -16.565875) (xy 79.148686 -16.542004)
			(xy 79.132491 -16.524978) (xy 79.095007 -16.496648) (xy 79.052954 -16.475693) (xy 79.007765 -16.462827)
			(xy 78.96098 -16.45849) (xy 78.914195 -16.462827) (xy 78.869006 -16.475693) (xy 78.826953 -16.496648)
			(xy 78.789469 -16.524978) (xy 78.773274 -16.542004) (xy 78.750728 -16.565896) (xy 78.700592 -16.608343)
			(xy 78.645408 -16.643981) (xy 78.586094 -16.672215) (xy 78.523638 -16.692577) (xy 78.45908 -16.704727)
			(xy 78.393495 -16.708462) (xy 78.327975 -16.703721) (xy 78.263611 -16.690583) (xy 78.201475 -16.669265)
			(xy 78.142601 -16.640124) (xy 78.08797 -16.603643) (xy 78.038491 -16.560432) (xy 78.016354 -16.536162)
			(xy 78.001752 -16.520305) (xy 77.968185 -16.493266) (xy 77.930538 -16.472278) (xy 77.88989 -16.457942)
			(xy 77.847405 -16.45067) (xy 77.804303 -16.45067) (xy 77.761818 -16.457942) (xy 77.72117 -16.472278)
			(xy 77.683523 -16.493266) (xy 77.649956 -16.520305) (xy 77.635354 -16.536162) (xy 77.613124 -16.560512)
			(xy 77.563442 -16.603859) (xy 77.508573 -16.640419) (xy 77.449438 -16.669578) (xy 77.387029 -16.690848)
			(xy 77.322394 -16.703871) (xy 77.256618 -16.708428) (xy 77.190805 -16.704444) (xy 77.126059 -16.691985)
			(xy 77.063468 -16.67126) (xy 77.00408 -16.642617) (xy 76.948895 -16.606537) (xy 76.898836 -16.563626)
			(xy 76.876402 -16.539464) (xy 76.860167 -16.522197) (xy 76.822502 -16.493438) (xy 76.780161 -16.472154)
			(xy 76.73461 -16.459081) (xy 76.687426 -16.454673) (xy 76.640242 -16.459081) (xy 76.594691 -16.472154)
			(xy 76.55235 -16.493438) (xy 76.514685 -16.522197) (xy 76.49845 -16.539464) (xy 76.476504 -16.56308)
			(xy 76.42768 -16.605182) (xy 76.373924 -16.640771) (xy 76.316099 -16.669277) (xy 76.255134 -16.690242)
			(xy 76.192007 -16.703329) (xy 76.127731 -16.708328) (xy 76.06334 -16.705158) (xy 75.999866 -16.693871)
			(xy 75.93833 -16.674647) (xy 75.879718 -16.647796) (xy 75.824972 -16.613749) (xy 75.774972 -16.573052)
			(xy 75.730519 -16.526358) (xy 75.692328 -16.474418) (xy 75.661013 -16.418066) (xy 75.637074 -16.358205)
			(xy 75.620898 -16.295798) (xy 75.612744 -16.231847) (xy 75.612244 -16.199612) (xy 75.306936 -16.199612)
			(xy 75.306936 -17.203928) (xy 75.306435 -17.235873) (xy 75.298427 -17.299259) (xy 75.282538 -17.361142)
			(xy 75.259019 -17.420546) (xy 75.228239 -17.476533) (xy 75.190686 -17.528222) (xy 75.14695 -17.574796)
			(xy 75.097722 -17.615521) (xy 75.043777 -17.649755) (xy 74.985968 -17.676958) (xy 74.925205 -17.696701)
			(xy 74.862446 -17.708673) (xy 74.798682 -17.712685) (xy 74.734918 -17.708673) (xy 74.672159 -17.696701)
			(xy 74.611396 -17.676958) (xy 74.553587 -17.649755) (xy 74.499642 -17.615521) (xy 74.450414 -17.574796)
			(xy 74.406678 -17.528222) (xy 74.369125 -17.476533) (xy 74.338345 -17.420546) (xy 74.314826 -17.361142)
			(xy 74.298937 -17.299259) (xy 74.290929 -17.235873) (xy 74.290428 -17.203928) (xy 41.858946 -17.203928)
			(xy 41.858946 -18.532602) (xy 41.782323 -18.609225) (xy 47.374038 -18.609225) (xy 47.374038 -18.528115)
			(xy 47.381988 -18.447396) (xy 47.397811 -18.367845) (xy 47.421356 -18.290229) (xy 47.452395 -18.215293)
			(xy 47.49063 -18.143761) (xy 47.535692 -18.076321) (xy 47.587147 -18.013622) (xy 47.6445 -17.956269)
			(xy 47.707199 -17.904814) (xy 47.774639 -17.859752) (xy 47.846171 -17.821517) (xy 47.921107 -17.790478)
			(xy 47.998723 -17.766933) (xy 48.078274 -17.75111) (xy 48.158993 -17.74316) (xy 48.240103 -17.74316)
			(xy 48.320822 -17.75111) (xy 48.400373 -17.766933) (xy 48.477989 -17.790478) (xy 48.552925 -17.821517)
			(xy 48.624457 -17.859752) (xy 48.691897 -17.904814) (xy 48.754596 -17.956269) (xy 48.811949 -18.013622)
			(xy 48.863404 -18.076321) (xy 48.872192 -18.089473) (xy 60.567562 -18.089473) (xy 60.567562 -18.018151)
			(xy 60.575548 -17.947277) (xy 60.591418 -17.877742) (xy 60.614975 -17.810422) (xy 60.64592 -17.746163)
			(xy 60.683866 -17.685772) (xy 60.728335 -17.63001) (xy 60.778768 -17.579577) (xy 60.83453 -17.535108)
			(xy 60.894921 -17.497162) (xy 60.95918 -17.466217) (xy 61.0265 -17.44266) (xy 61.096035 -17.42679)
			(xy 61.166909 -17.418804) (xy 61.238231 -17.418804) (xy 61.309105 -17.42679) (xy 61.37864 -17.44266)
			(xy 61.44596 -17.466217) (xy 61.510219 -17.497162) (xy 61.57061 -17.535108) (xy 61.626372 -17.579577)
			(xy 61.676805 -17.63001) (xy 61.721274 -17.685772) (xy 61.75922 -17.746163) (xy 61.790165 -17.810422)
			(xy 61.813722 -17.877742) (xy 61.829592 -17.947277) (xy 61.837578 -18.018151) (xy 61.838078 -18.053812)
			(xy 61.837578 -18.089473) (xy 62.471546 -18.089473) (xy 62.471546 -18.018151) (xy 62.479532 -17.947277)
			(xy 62.495402 -17.877742) (xy 62.518959 -17.810422) (xy 62.549904 -17.746163) (xy 62.58785 -17.685772)
			(xy 62.632319 -17.63001) (xy 62.682752 -17.579577) (xy 62.738514 -17.535108) (xy 62.798905 -17.497162)
			(xy 62.863164 -17.466217) (xy 62.930484 -17.44266) (xy 63.000019 -17.42679) (xy 63.070893 -17.418804)
			(xy 63.142215 -17.418804) (xy 63.213089 -17.42679) (xy 63.282624 -17.44266) (xy 63.349944 -17.466217)
			(xy 63.414203 -17.497162) (xy 63.474594 -17.535108) (xy 63.530356 -17.579577) (xy 63.580789 -17.63001)
			(xy 63.625258 -17.685772) (xy 63.663204 -17.746163) (xy 63.694149 -17.810422) (xy 63.717706 -17.877742)
			(xy 63.733576 -17.947277) (xy 63.741562 -18.018151) (xy 63.742062 -18.053812) (xy 63.741562 -18.089473)
			(xy 63.733576 -18.160347) (xy 63.717706 -18.229882) (xy 63.694149 -18.297202) (xy 63.663204 -18.361461)
			(xy 63.625258 -18.421852) (xy 63.580789 -18.477614) (xy 63.530356 -18.528047) (xy 63.474594 -18.572516)
			(xy 63.414203 -18.610462) (xy 63.349944 -18.641407) (xy 63.282624 -18.664964) (xy 63.213089 -18.680834)
			(xy 63.142215 -18.68882) (xy 63.070893 -18.68882) (xy 63.000019 -18.680834) (xy 62.930484 -18.664964)
			(xy 62.863164 -18.641407) (xy 62.798905 -18.610462) (xy 62.738514 -18.572516) (xy 62.682752 -18.528047)
			(xy 62.632319 -18.477614) (xy 62.58785 -18.421852) (xy 62.549904 -18.361461) (xy 62.518959 -18.297202)
			(xy 62.495402 -18.229882) (xy 62.479532 -18.160347) (xy 62.471546 -18.089473) (xy 61.837578 -18.089473)
			(xy 61.829592 -18.160347) (xy 61.813722 -18.229882) (xy 61.790165 -18.297202) (xy 61.75922 -18.361461)
			(xy 61.721274 -18.421852) (xy 61.676805 -18.477614) (xy 61.626372 -18.528047) (xy 61.57061 -18.572516)
			(xy 61.510219 -18.610462) (xy 61.44596 -18.641407) (xy 61.37864 -18.664964) (xy 61.309105 -18.680834)
			(xy 61.238231 -18.68882) (xy 61.166909 -18.68882) (xy 61.096035 -18.680834) (xy 61.0265 -18.664964)
			(xy 60.95918 -18.641407) (xy 60.894921 -18.610462) (xy 60.83453 -18.572516) (xy 60.778768 -18.528047)
			(xy 60.728335 -18.477614) (xy 60.683866 -18.421852) (xy 60.64592 -18.361461) (xy 60.614975 -18.297202)
			(xy 60.591418 -18.229882) (xy 60.575548 -18.160347) (xy 60.567562 -18.089473) (xy 48.872192 -18.089473)
			(xy 48.908466 -18.143761) (xy 48.946701 -18.215293) (xy 48.97774 -18.290229) (xy 49.001285 -18.367845)
			(xy 49.017108 -18.447396) (xy 49.025058 -18.528115) (xy 49.025556 -18.56867) (xy 49.025058 -18.609225)
			(xy 49.017108 -18.689944) (xy 49.001285 -18.769495) (xy 48.97774 -18.847111) (xy 48.946701 -18.922047)
			(xy 48.908466 -18.993579) (xy 48.863404 -19.061019) (xy 48.811949 -19.123718) (xy 48.754596 -19.181071)
			(xy 48.691897 -19.232526) (xy 48.624457 -19.277588) (xy 48.552925 -19.315823) (xy 48.477989 -19.346862)
			(xy 48.400373 -19.370407) (xy 48.320822 -19.38623) (xy 48.240103 -19.39418) (xy 48.158993 -19.39418)
			(xy 48.078274 -19.38623) (xy 47.998723 -19.370407) (xy 47.921107 -19.346862) (xy 47.846171 -19.315823)
			(xy 47.774639 -19.277588) (xy 47.707199 -19.232526) (xy 47.6445 -19.181071) (xy 47.587147 -19.123718)
			(xy 47.535692 -19.061019) (xy 47.49063 -18.993579) (xy 47.452395 -18.922047) (xy 47.421356 -18.847111)
			(xy 47.397811 -18.769495) (xy 47.381988 -18.689944) (xy 47.374038 -18.609225) (xy 41.782323 -18.609225)
			(xy 40.671496 -19.720052) (xy 40.671496 -20.100645) (xy 60.524128 -20.100645) (xy 60.524128 -20.029323)
			(xy 60.532114 -19.958449) (xy 60.547984 -19.888914) (xy 60.571541 -19.821594) (xy 60.602486 -19.757335)
			(xy 60.640432 -19.696944) (xy 60.684901 -19.641182) (xy 60.735334 -19.590749) (xy 60.791096 -19.54628)
			(xy 60.851487 -19.508334) (xy 60.915746 -19.477389) (xy 60.983066 -19.453832) (xy 61.052601 -19.437962)
			(xy 61.123475 -19.429976) (xy 61.194797 -19.429976) (xy 61.265671 -19.437962) (xy 61.335206 -19.453832)
			(xy 61.402526 -19.477389) (xy 61.466785 -19.508334) (xy 61.527176 -19.54628) (xy 61.582938 -19.590749)
			(xy 61.633371 -19.641182) (xy 61.67784 -19.696944) (xy 61.715786 -19.757335) (xy 61.746731 -19.821594)
			(xy 61.770288 -19.888914) (xy 61.786158 -19.958449) (xy 61.794144 -20.029323) (xy 61.794644 -20.064984)
			(xy 61.794144 -20.100645) (xy 62.428112 -20.100645) (xy 62.428112 -20.029323) (xy 62.436098 -19.958449)
			(xy 62.451968 -19.888914) (xy 62.475525 -19.821594) (xy 62.50647 -19.757335) (xy 62.544416 -19.696944)
			(xy 62.588885 -19.641182) (xy 62.639318 -19.590749) (xy 62.69508 -19.54628) (xy 62.755471 -19.508334)
			(xy 62.81973 -19.477389) (xy 62.88705 -19.453832) (xy 62.956585 -19.437962) (xy 63.027459 -19.429976)
			(xy 63.098781 -19.429976) (xy 63.169655 -19.437962) (xy 63.23919 -19.453832) (xy 63.30651 -19.477389)
			(xy 63.370769 -19.508334) (xy 63.43116 -19.54628) (xy 63.486922 -19.590749) (xy 63.537355 -19.641182)
			(xy 63.581824 -19.696944) (xy 63.61977 -19.757335) (xy 63.650715 -19.821594) (xy 63.674272 -19.888914)
			(xy 63.690142 -19.958449) (xy 63.695964 -20.01012) (xy 86.39887 -20.01012) (xy 86.402874 -19.810022)
			(xy 86.414881 -19.610244) (xy 86.434872 -19.411107) (xy 86.462814 -19.212929) (xy 86.498662 -19.016027)
			(xy 86.54236 -18.820718) (xy 86.593837 -18.627313) (xy 86.653011 -18.436123) (xy 86.719787 -18.247453)
			(xy 86.794059 -18.061606) (xy 86.875706 -17.878879) (xy 86.964599 -17.699566) (xy 87.060595 -17.523952)
			(xy 87.16354 -17.35232) (xy 87.27327 -17.184944) (xy 87.389608 -17.022093) (xy 87.512369 -16.864026)
			(xy 87.641356 -16.710998) (xy 87.776363 -16.563253) (xy 87.917172 -16.421027) (xy 88.063559 -16.28455)
			(xy 88.215289 -16.154038) (xy 88.37212 -16.029702) (xy 88.533799 -15.91174) (xy 88.700069 -15.800341)
			(xy 88.870662 -15.695684) (xy 89.045306 -15.597936) (xy 89.223722 -15.507253) (xy 89.405622 -15.423782)
			(xy 89.590717 -15.347655) (xy 89.778709 -15.278995) (xy 89.969298 -15.217911) (xy 90.162178 -15.164501)
			(xy 90.35704 -15.118852) (xy 90.553573 -15.081035) (xy 90.751462 -15.051111) (xy 90.950389 -15.029129)
			(xy 91.150037 -15.015124) (xy 91.350085 -15.009118) (xy 91.550213 -15.01112) (xy 91.750101 -15.021128)
			(xy 91.949428 -15.039125) (xy 92.147876 -15.065083) (xy 92.345126 -15.09896) (xy 92.540863 -15.140702)
			(xy 92.734773 -15.190241) (xy 92.926546 -15.247499) (xy 93.115875 -15.312384) (xy 93.302455 -15.384792)
			(xy 93.48599 -15.464608) (xy 93.666184 -15.551702) (xy 93.842749 -15.645936) (xy 94.015402 -15.747159)
			(xy 94.183867 -15.855209) (xy 94.347875 -15.969912) (xy 94.507162 -16.091086) (xy 94.661473 -16.218535)
			(xy 94.810561 -16.352056) (xy 94.954188 -16.491436) (xy 95.092124 -16.63645) (xy 95.224147 -16.786867)
			(xy 95.350046 -16.942445) (xy 95.46962 -17.102937) (xy 95.582676 -17.268083) (xy 95.689035 -17.437621)
			(xy 95.788526 -17.611279) (xy 95.880989 -17.788778) (xy 95.966276 -17.969834) (xy 96.044251 -18.154158)
			(xy 96.114788 -18.341454) (xy 96.177776 -18.531422) (xy 96.233113 -18.723758) (xy 96.28071 -18.918154)
			(xy 96.320491 -19.114299) (xy 96.352393 -19.311878) (xy 96.376364 -19.510575) (xy 96.377051 -19.519138)
			(xy 98.049078 -19.519138) (xy 98.053149 -19.463516) (xy 98.065275 -19.409079) (xy 98.085198 -19.356988)
			(xy 98.112494 -19.308353) (xy 98.14658 -19.26421) (xy 98.186729 -19.225501) (xy 98.232087 -19.19305)
			(xy 98.281687 -19.167549) (xy 98.334471 -19.149542) (xy 98.389314 -19.139412) (xy 98.445048 -19.137375)
			(xy 98.500485 -19.143475) (xy 98.554442 -19.157581) (xy 98.605771 -19.179393) (xy 98.653377 -19.208447)
			(xy 98.696245 -19.244122) (xy 98.733462 -19.285659) (xy 98.764235 -19.332172) (xy 98.787907 -19.382669)
			(xy 98.803975 -19.436076) (xy 98.812095 -19.491252) (xy 98.812604 -19.519138) (xy 98.812095 -19.547024)
			(xy 98.803975 -19.6022) (xy 98.787907 -19.655607) (xy 98.764235 -19.706104) (xy 98.733462 -19.752617)
			(xy 98.696245 -19.794154) (xy 98.653377 -19.829829) (xy 98.605771 -19.858883) (xy 98.554442 -19.880695)
			(xy 98.500485 -19.894801) (xy 98.445048 -19.900901) (xy 98.389314 -19.898864) (xy 98.334471 -19.888734)
			(xy 98.281687 -19.870727) (xy 98.232087 -19.845226) (xy 98.186729 -19.812775) (xy 98.14658 -19.774066)
			(xy 98.112494 -19.729923) (xy 98.085198 -19.681288) (xy 98.065275 -19.629197) (xy 98.053149 -19.57476)
			(xy 98.049078 -19.519138) (xy 96.377051 -19.519138) (xy 96.392366 -19.710073) (xy 96.400373 -19.910051)
			(xy 96.400874 -20.01012) (xy 96.400373 -20.110189) (xy 96.392366 -20.310167) (xy 96.376364 -20.509665)
			(xy 96.352393 -20.708362) (xy 96.320491 -20.905941) (xy 96.28071 -21.102086) (xy 96.233113 -21.296482)
			(xy 96.177776 -21.488818) (xy 96.114788 -21.678786) (xy 96.044251 -21.866082) (xy 95.966276 -22.050406)
			(xy 95.880989 -22.231462) (xy 95.788526 -22.408961) (xy 95.689035 -22.582619) (xy 95.582676 -22.752157)
			(xy 95.46962 -22.917303) (xy 95.350046 -23.077795) (xy 95.224147 -23.233373) (xy 95.092124 -23.38379)
			(xy 94.954188 -23.528804) (xy 94.810561 -23.668184) (xy 94.661473 -23.801705) (xy 94.507162 -23.929154)
			(xy 94.347875 -24.050328) (xy 94.183867 -24.165031) (xy 94.015402 -24.273081) (xy 93.842749 -24.374304)
			(xy 93.666184 -24.468538) (xy 93.48599 -24.555632) (xy 93.302455 -24.635448) (xy 93.115875 -24.707856)
			(xy 92.926546 -24.772741) (xy 92.734773 -24.829999) (xy 92.540863 -24.879538) (xy 92.345126 -24.92128)
			(xy 92.147876 -24.955157) (xy 91.949428 -24.981115) (xy 91.750101 -24.999112) (xy 91.550213 -25.00912)
			(xy 91.350085 -25.011122) (xy 91.150037 -25.005116) (xy 90.950389 -24.991111) (xy 90.751462 -24.969129)
			(xy 90.553573 -24.939205) (xy 90.35704 -24.901388) (xy 90.162178 -24.855739) (xy 89.969298 -24.802329)
			(xy 89.778709 -24.741245) (xy 89.590717 -24.672585) (xy 89.405622 -24.596458) (xy 89.223722 -24.512987)
			(xy 89.045306 -24.422304) (xy 88.870662 -24.324556) (xy 88.700069 -24.219899) (xy 88.533799 -24.1085)
			(xy 88.37212 -23.990538) (xy 88.215289 -23.866202) (xy 88.063559 -23.73569) (xy 87.917172 -23.599213)
			(xy 87.776363 -23.456987) (xy 87.641356 -23.309242) (xy 87.512369 -23.156214) (xy 87.389608 -22.998147)
			(xy 87.27327 -22.835296) (xy 87.16354 -22.66792) (xy 87.060595 -22.496288) (xy 86.964599 -22.320674)
			(xy 86.875706 -22.141361) (xy 86.794059 -21.958634) (xy 86.719787 -21.772787) (xy 86.653011 -21.584117)
			(xy 86.593837 -21.392927) (xy 86.54236 -21.199522) (xy 86.498662 -21.004213) (xy 86.462814 -20.807311)
			(xy 86.434872 -20.609133) (xy 86.414881 -20.409996) (xy 86.402874 -20.210218) (xy 86.39887 -20.01012)
			(xy 63.695964 -20.01012) (xy 63.698128 -20.029323) (xy 63.698628 -20.064984) (xy 63.698128 -20.100645)
			(xy 63.690142 -20.171519) (xy 63.674272 -20.241054) (xy 63.650715 -20.308374) (xy 63.61977 -20.372633)
			(xy 63.581824 -20.433024) (xy 63.537355 -20.488786) (xy 63.486922 -20.539219) (xy 63.43116 -20.583688)
			(xy 63.370769 -20.621634) (xy 63.30651 -20.652579) (xy 63.23919 -20.676136) (xy 63.169655 -20.692006)
			(xy 63.098781 -20.699992) (xy 63.027459 -20.699992) (xy 62.956585 -20.692006) (xy 62.88705 -20.676136)
			(xy 62.81973 -20.652579) (xy 62.755471 -20.621634) (xy 62.69508 -20.583688) (xy 62.639318 -20.539219)
			(xy 62.588885 -20.488786) (xy 62.544416 -20.433024) (xy 62.50647 -20.372633) (xy 62.475525 -20.308374)
			(xy 62.451968 -20.241054) (xy 62.436098 -20.171519) (xy 62.428112 -20.100645) (xy 61.794144 -20.100645)
			(xy 61.786158 -20.171519) (xy 61.770288 -20.241054) (xy 61.746731 -20.308374) (xy 61.715786 -20.372633)
			(xy 61.67784 -20.433024) (xy 61.633371 -20.488786) (xy 61.582938 -20.539219) (xy 61.527176 -20.583688)
			(xy 61.466785 -20.621634) (xy 61.402526 -20.652579) (xy 61.335206 -20.676136) (xy 61.265671 -20.692006)
			(xy 61.194797 -20.699992) (xy 61.123475 -20.699992) (xy 61.052601 -20.692006) (xy 60.983066 -20.676136)
			(xy 60.915746 -20.652579) (xy 60.851487 -20.621634) (xy 60.791096 -20.583688) (xy 60.735334 -20.539219)
			(xy 60.684901 -20.488786) (xy 60.640432 -20.433024) (xy 60.602486 -20.372633) (xy 60.571541 -20.308374)
			(xy 60.547984 -20.241054) (xy 60.532114 -20.171519) (xy 60.524128 -20.100645) (xy 40.671496 -20.100645)
			(xy 40.671496 -21.169376) (xy 40.671993 -21.185698) (xy 40.680273 -21.217273) (xy 40.696296 -21.245714)
			(xy 40.70731 -21.257768) (xy 40.728851 -21.280659) (xy 40.766437 -21.331041) (xy 40.797169 -21.385873)
			(xy 40.820526 -21.44423) (xy 40.836113 -21.505124) (xy 40.843668 -21.567526) (xy 40.843061 -21.630381)
			(xy 40.834305 -21.692625) (xy 40.817545 -21.753207) (xy 40.793067 -21.811102) (xy 40.761283 -21.865332)
			(xy 40.722732 -21.914979) (xy 40.678064 -21.959204) (xy 40.636046 -21.991167) (xy 60.524128 -21.991167)
			(xy 60.524128 -21.919845) (xy 60.532114 -21.848971) (xy 60.547984 -21.779436) (xy 60.571541 -21.712116)
			(xy 60.602486 -21.647857) (xy 60.640432 -21.587466) (xy 60.684901 -21.531704) (xy 60.735334 -21.481271)
			(xy 60.791096 -21.436802) (xy 60.851487 -21.398856) (xy 60.915746 -21.367911) (xy 60.983066 -21.344354)
			(xy 61.052601 -21.328484) (xy 61.123475 -21.320498) (xy 61.194797 -21.320498) (xy 61.265671 -21.328484)
			(xy 61.335206 -21.344354) (xy 61.402526 -21.367911) (xy 61.466785 -21.398856) (xy 61.527176 -21.436802)
			(xy 61.582938 -21.481271) (xy 61.633371 -21.531704) (xy 61.67784 -21.587466) (xy 61.715786 -21.647857)
			(xy 61.746731 -21.712116) (xy 61.770288 -21.779436) (xy 61.786158 -21.848971) (xy 61.794144 -21.919845)
			(xy 61.794644 -21.955506) (xy 61.794144 -21.991167) (xy 62.428112 -21.991167) (xy 62.428112 -21.919845)
			(xy 62.436098 -21.848971) (xy 62.451968 -21.779436) (xy 62.475525 -21.712116) (xy 62.50647 -21.647857)
			(xy 62.544416 -21.587466) (xy 62.588885 -21.531704) (xy 62.639318 -21.481271) (xy 62.69508 -21.436802)
			(xy 62.755471 -21.398856) (xy 62.81973 -21.367911) (xy 62.88705 -21.344354) (xy 62.956585 -21.328484)
			(xy 63.027459 -21.320498) (xy 63.098781 -21.320498) (xy 63.169655 -21.328484) (xy 63.23919 -21.344354)
			(xy 63.30651 -21.367911) (xy 63.370769 -21.398856) (xy 63.43116 -21.436802) (xy 63.486922 -21.481271)
			(xy 63.537355 -21.531704) (xy 63.581824 -21.587466) (xy 63.61977 -21.647857) (xy 63.650715 -21.712116)
			(xy 63.674272 -21.779436) (xy 63.690142 -21.848971) (xy 63.698128 -21.919845) (xy 63.698628 -21.955506)
			(xy 63.698128 -21.991167) (xy 63.690142 -22.062041) (xy 63.674272 -22.131576) (xy 63.650715 -22.198896)
			(xy 63.61977 -22.263155) (xy 63.581824 -22.323546) (xy 63.537355 -22.379308) (xy 63.486922 -22.429741)
			(xy 63.43116 -22.47421) (xy 63.370769 -22.512156) (xy 63.30651 -22.543101) (xy 63.23919 -22.566658)
			(xy 63.169655 -22.582528) (xy 63.098781 -22.590514) (xy 63.027459 -22.590514) (xy 62.956585 -22.582528)
			(xy 62.88705 -22.566658) (xy 62.81973 -22.543101) (xy 62.755471 -22.512156) (xy 62.69508 -22.47421)
			(xy 62.639318 -22.429741) (xy 62.588885 -22.379308) (xy 62.544416 -22.323546) (xy 62.50647 -22.263155)
			(xy 62.475525 -22.198896) (xy 62.451968 -22.131576) (xy 62.436098 -22.062041) (xy 62.428112 -21.991167)
			(xy 61.794144 -21.991167) (xy 61.786158 -22.062041) (xy 61.770288 -22.131576) (xy 61.746731 -22.198896)
			(xy 61.715786 -22.263155) (xy 61.67784 -22.323546) (xy 61.633371 -22.379308) (xy 61.582938 -22.429741)
			(xy 61.527176 -22.47421) (xy 61.466785 -22.512156) (xy 61.402526 -22.543101) (xy 61.335206 -22.566658)
			(xy 61.265671 -22.582528) (xy 61.194797 -22.590514) (xy 61.123475 -22.590514) (xy 61.052601 -22.582528)
			(xy 60.983066 -22.566658) (xy 60.915746 -22.543101) (xy 60.851487 -22.512156) (xy 60.791096 -22.47421)
			(xy 60.735334 -22.429741) (xy 60.684901 -22.379308) (xy 60.640432 -22.323546) (xy 60.602486 -22.263155)
			(xy 60.571541 -22.198896) (xy 60.547984 -22.131576) (xy 60.532114 -22.062041) (xy 60.524128 -21.991167)
			(xy 40.636046 -21.991167) (xy 40.628036 -21.99726) (xy 40.573493 -22.028502) (xy 40.515357 -22.052404)
			(xy 40.454611 -22.068559) (xy 40.392283 -22.076696) (xy 40.360854 -22.077172) (xy 40.21455 -22.077172)
			(xy 40.187934 -22.0787) (xy 40.136192 -22.091512) (xy 40.111934 -22.102572) (xy 40.111934 -22.676866)
			(xy 40.136301 -22.688026) (xy 40.188302 -22.700963) (xy 40.215058 -22.70252) (xy 40.491918 -22.70252)
			(xy 40.523533 -22.703038) (xy 40.586222 -22.711293) (xy 40.647297 -22.72766) (xy 40.705713 -22.751859)
			(xy 40.760471 -22.783476) (xy 40.810634 -22.821969) (xy 40.855343 -22.86668) (xy 40.893835 -22.916844)
			(xy 40.925449 -22.971603) (xy 40.949645 -23.03002) (xy 40.96601 -23.091096) (xy 40.974263 -23.153785)
			(xy 40.974263 -23.217015) (xy 40.96601 -23.279704) (xy 40.949645 -23.34078) (xy 40.925449 -23.399197)
			(xy 40.893835 -23.453956) (xy 40.855343 -23.50412) (xy 40.810634 -23.548831) (xy 40.760471 -23.587324)
			(xy 40.705713 -23.618941) (xy 40.647297 -23.64314) (xy 40.586222 -23.659507) (xy 40.523533 -23.667762)
			(xy 40.491918 -23.668228) (xy 39.46398 -23.668228) (xy 39.437279 -23.667863) (xy 39.384201 -23.662005)
			(xy 39.358062 -23.656544) (xy 39.355268 -23.656036) (xy 39.341298 -23.652734) (xy 38.937946 -23.652734)
			(xy 38.1635 -22.878288) (xy 36.397184 -22.878288) (xy 36.382355 -22.87873) (xy 36.3535 -22.885584)
			(xy 36.326999 -22.898899) (xy 36.304274 -22.917957) (xy 36.295076 -22.929596) (xy 36.269377 -22.963503)
			(xy 36.212771 -23.027028) (xy 36.150656 -23.085178) (xy 36.08354 -23.137477) (xy 36.011974 -23.183498)
			(xy 35.936541 -23.222864) (xy 35.857861 -23.255252) (xy 35.776575 -23.280398) (xy 35.69335 -23.298097)
			(xy 35.608866 -23.308202) (xy 35.523814 -23.310633) (xy 35.438891 -23.305368) (xy 35.354791 -23.29245)
			(xy 35.272202 -23.271987) (xy 35.1918 -23.244144) (xy 35.114243 -23.20915) (xy 35.040165 -23.167291)
			(xy 34.970173 -23.118909) (xy 34.904839 -23.064401) (xy 34.844698 -23.004212) (xy 34.790241 -22.938835)
			(xy 34.741915 -22.868804) (xy 34.700115 -22.794694) (xy 34.682176 -22.756114) (xy 34.666936 -22.722078)
			(xy 34.603944 -22.681184) (xy 31.395416 -22.681184) (xy 31.332424 -22.722078) (xy 31.317184 -22.756114)
			(xy 31.29901 -22.795288) (xy 31.256483 -22.870456) (xy 31.207242 -22.941407) (xy 31.151703 -23.007545)
			(xy 31.090335 -23.068311) (xy 31.023652 -23.123195) (xy 30.952219 -23.171733) (xy 30.876636 -23.213517)
			(xy 30.79754 -23.248195) (xy 30.715597 -23.275475) (xy 30.631499 -23.295126) (xy 30.545953 -23.306983)
			(xy 30.45968 -23.310946) (xy 30.373407 -23.306983) (xy 30.287861 -23.295126) (xy 30.203763 -23.275475)
			(xy 30.12182 -23.248195) (xy 30.042724 -23.213517) (xy 29.967141 -23.171733) (xy 29.895708 -23.123195)
			(xy 29.829025 -23.068311) (xy 29.767657 -23.007545) (xy 29.712118 -22.941407) (xy 29.662877 -22.870456)
			(xy 29.62035 -22.795288) (xy 29.602176 -22.756114) (xy 29.586936 -22.722078) (xy 29.523944 -22.681184)
			(xy 29.36748 -22.681184) (xy 29.350833 -22.68173) (xy 29.318673 -22.69035) (xy 29.28984 -22.707)
			(xy 29.266297 -22.730543) (xy 29.249649 -22.759377) (xy 29.241029 -22.791537) (xy 29.24048 -22.808184)
			(xy 29.24048 -24.953484) (xy 29.519874 -24.953484) (xy 29.519874 -24.866584) (xy 29.527892 -24.780055)
			(xy 29.54386 -24.694635) (xy 29.567641 -24.611053) (xy 29.599033 -24.530021) (xy 29.637767 -24.452232)
			(xy 29.683514 -24.378348) (xy 29.735883 -24.309001) (xy 29.794427 -24.244781) (xy 29.858647 -24.186237)
			(xy 29.927994 -24.133868) (xy 30.001878 -24.088121) (xy 30.079667 -24.049387) (xy 30.160699 -24.017995)
			(xy 30.244281 -23.994214) (xy 30.329701 -23.978246) (xy 30.41623 -23.970228) (xy 30.50313 -23.970228)
			(xy 30.589659 -23.978246) (xy 30.675079 -23.994214) (xy 30.758661 -24.017995) (xy 30.839693 -24.049387)
			(xy 30.917482 -24.088121) (xy 30.991366 -24.133868) (xy 31.060713 -24.186237) (xy 31.124933 -24.244781)
			(xy 31.183477 -24.309001) (xy 31.235846 -24.378348) (xy 31.281593 -24.452232) (xy 31.320327 -24.530021)
			(xy 31.351719 -24.611053) (xy 31.3755 -24.694635) (xy 31.391468 -24.780055) (xy 31.399486 -24.866584)
			(xy 31.399988 -24.910034) (xy 31.399486 -24.953484) (xy 34.599874 -24.953484) (xy 34.599874 -24.866584)
			(xy 34.607892 -24.780055) (xy 34.62386 -24.694635) (xy 34.647641 -24.611053) (xy 34.679033 -24.530021)
			(xy 34.717767 -24.452232) (xy 34.763514 -24.378348) (xy 34.815883 -24.309001) (xy 34.874427 -24.244781)
			(xy 34.938647 -24.186237) (xy 35.007994 -24.133868) (xy 35.081878 -24.088121) (xy 35.159667 -24.049387)
			(xy 35.240699 -24.017995) (xy 35.324281 -23.994214) (xy 35.409701 -23.978246) (xy 35.49623 -23.970228)
			(xy 35.58313 -23.970228) (xy 35.669659 -23.978246) (xy 35.755079 -23.994214) (xy 35.838661 -24.017995)
			(xy 35.875615 -24.032311) (xy 60.524128 -24.032311) (xy 60.524128 -23.960989) (xy 60.532114 -23.890115)
			(xy 60.547984 -23.82058) (xy 60.571541 -23.75326) (xy 60.602486 -23.689001) (xy 60.640432 -23.62861)
			(xy 60.684901 -23.572848) (xy 60.735334 -23.522415) (xy 60.791096 -23.477946) (xy 60.851487 -23.44)
			(xy 60.915746 -23.409055) (xy 60.983066 -23.385498) (xy 61.052601 -23.369628) (xy 61.123475 -23.361642)
			(xy 61.194797 -23.361642) (xy 61.265671 -23.369628) (xy 61.335206 -23.385498) (xy 61.402526 -23.409055)
			(xy 61.466785 -23.44) (xy 61.527176 -23.477946) (xy 61.582938 -23.522415) (xy 61.633371 -23.572848)
			(xy 61.67784 -23.62861) (xy 61.715786 -23.689001) (xy 61.746731 -23.75326) (xy 61.770288 -23.82058)
			(xy 61.786158 -23.890115) (xy 61.794144 -23.960989) (xy 61.794644 -23.99665) (xy 61.794144 -24.032311)
			(xy 62.428112 -24.032311) (xy 62.428112 -23.960989) (xy 62.436098 -23.890115) (xy 62.451968 -23.82058)
			(xy 62.475525 -23.75326) (xy 62.50647 -23.689001) (xy 62.544416 -23.62861) (xy 62.588885 -23.572848)
			(xy 62.639318 -23.522415) (xy 62.69508 -23.477946) (xy 62.755471 -23.44) (xy 62.81973 -23.409055)
			(xy 62.88705 -23.385498) (xy 62.956585 -23.369628) (xy 63.027459 -23.361642) (xy 63.098781 -23.361642)
			(xy 63.169655 -23.369628) (xy 63.23919 -23.385498) (xy 63.30651 -23.409055) (xy 63.370769 -23.44)
			(xy 63.43116 -23.477946) (xy 63.486922 -23.522415) (xy 63.537355 -23.572848) (xy 63.581824 -23.62861)
			(xy 63.61977 -23.689001) (xy 63.650715 -23.75326) (xy 63.674272 -23.82058) (xy 63.690142 -23.890115)
			(xy 63.698128 -23.960989) (xy 63.698628 -23.99665) (xy 63.698128 -24.032311) (xy 63.690142 -24.103185)
			(xy 63.674272 -24.17272) (xy 63.650715 -24.24004) (xy 63.61977 -24.304299) (xy 63.581824 -24.36469)
			(xy 63.537355 -24.420452) (xy 63.486922 -24.470885) (xy 63.43116 -24.515354) (xy 63.370769 -24.5533)
			(xy 63.30651 -24.584245) (xy 63.23919 -24.607802) (xy 63.169655 -24.623672) (xy 63.098781 -24.631658)
			(xy 63.027459 -24.631658) (xy 62.956585 -24.623672) (xy 62.88705 -24.607802) (xy 62.81973 -24.584245)
			(xy 62.755471 -24.5533) (xy 62.69508 -24.515354) (xy 62.639318 -24.470885) (xy 62.588885 -24.420452)
			(xy 62.544416 -24.36469) (xy 62.50647 -24.304299) (xy 62.475525 -24.24004) (xy 62.451968 -24.17272)
			(xy 62.436098 -24.103185) (xy 62.428112 -24.032311) (xy 61.794144 -24.032311) (xy 61.786158 -24.103185)
			(xy 61.770288 -24.17272) (xy 61.746731 -24.24004) (xy 61.715786 -24.304299) (xy 61.67784 -24.36469)
			(xy 61.633371 -24.420452) (xy 61.582938 -24.470885) (xy 61.527176 -24.515354) (xy 61.466785 -24.5533)
			(xy 61.402526 -24.584245) (xy 61.335206 -24.607802) (xy 61.265671 -24.623672) (xy 61.194797 -24.631658)
			(xy 61.123475 -24.631658) (xy 61.052601 -24.623672) (xy 60.983066 -24.607802) (xy 60.915746 -24.584245)
			(xy 60.851487 -24.5533) (xy 60.791096 -24.515354) (xy 60.735334 -24.470885) (xy 60.684901 -24.420452)
			(xy 60.640432 -24.36469) (xy 60.602486 -24.304299) (xy 60.571541 -24.24004) (xy 60.547984 -24.17272)
			(xy 60.532114 -24.103185) (xy 60.524128 -24.032311) (xy 35.875615 -24.032311) (xy 35.919693 -24.049387)
			(xy 35.997482 -24.088121) (xy 36.071366 -24.133868) (xy 36.140713 -24.186237) (xy 36.204933 -24.244781)
			(xy 36.263477 -24.309001) (xy 36.315846 -24.378348) (xy 36.361593 -24.452232) (xy 36.400327 -24.530021)
			(xy 36.431719 -24.611053) (xy 36.4555 -24.694635) (xy 36.471468 -24.780055) (xy 36.479486 -24.866584)
			(xy 36.479988 -24.910034) (xy 36.479486 -24.953484) (xy 36.471468 -25.040013) (xy 36.4555 -25.125433)
			(xy 36.431719 -25.209015) (xy 36.400327 -25.290047) (xy 36.361593 -25.367836) (xy 36.315846 -25.44172)
			(xy 36.263477 -25.511067) (xy 36.204933 -25.575287) (xy 36.140713 -25.633831) (xy 36.071366 -25.6862)
			(xy 35.997482 -25.731947) (xy 35.919693 -25.770681) (xy 35.838661 -25.802073) (xy 35.755079 -25.825854)
			(xy 35.669659 -25.841822) (xy 35.58313 -25.84984) (xy 35.49623 -25.84984) (xy 35.409701 -25.841822)
			(xy 35.324281 -25.825854) (xy 35.240699 -25.802073) (xy 35.159667 -25.770681) (xy 35.081878 -25.731947)
			(xy 35.007994 -25.6862) (xy 34.938647 -25.633831) (xy 34.874427 -25.575287) (xy 34.815883 -25.511067)
			(xy 34.763514 -25.44172) (xy 34.717767 -25.367836) (xy 34.679033 -25.290047) (xy 34.647641 -25.209015)
			(xy 34.62386 -25.125433) (xy 34.607892 -25.040013) (xy 34.599874 -24.953484) (xy 31.399486 -24.953484)
			(xy 31.391468 -25.040013) (xy 31.3755 -25.125433) (xy 31.351719 -25.209015) (xy 31.320327 -25.290047)
			(xy 31.281593 -25.367836) (xy 31.235846 -25.44172) (xy 31.183477 -25.511067) (xy 31.124933 -25.575287)
			(xy 31.060713 -25.633831) (xy 30.991366 -25.6862) (xy 30.917482 -25.731947) (xy 30.839693 -25.770681)
			(xy 30.758661 -25.802073) (xy 30.675079 -25.825854) (xy 30.589659 -25.841822) (xy 30.50313 -25.84984)
			(xy 30.41623 -25.84984) (xy 30.329701 -25.841822) (xy 30.244281 -25.825854) (xy 30.160699 -25.802073)
			(xy 30.079667 -25.770681) (xy 30.001878 -25.731947) (xy 29.927994 -25.6862) (xy 29.858647 -25.633831)
			(xy 29.794427 -25.575287) (xy 29.735883 -25.511067) (xy 29.683514 -25.44172) (xy 29.637767 -25.367836)
			(xy 29.599033 -25.290047) (xy 29.567641 -25.209015) (xy 29.54386 -25.125433) (xy 29.527892 -25.040013)
			(xy 29.519874 -24.953484) (xy 29.24048 -24.953484) (xy 29.24048 -25.942137) (xy 60.524128 -25.942137)
			(xy 60.524128 -25.870815) (xy 60.532114 -25.799941) (xy 60.547984 -25.730406) (xy 60.571541 -25.663086)
			(xy 60.602486 -25.598827) (xy 60.640432 -25.538436) (xy 60.684901 -25.482674) (xy 60.735334 -25.432241)
			(xy 60.791096 -25.387772) (xy 60.851487 -25.349826) (xy 60.915746 -25.318881) (xy 60.983066 -25.295324)
			(xy 61.052601 -25.279454) (xy 61.123475 -25.271468) (xy 61.194797 -25.271468) (xy 61.265671 -25.279454)
			(xy 61.335206 -25.295324) (xy 61.402526 -25.318881) (xy 61.466785 -25.349826) (xy 61.527176 -25.387772)
			(xy 61.582938 -25.432241) (xy 61.633371 -25.482674) (xy 61.67784 -25.538436) (xy 61.715786 -25.598827)
			(xy 61.746731 -25.663086) (xy 61.770288 -25.730406) (xy 61.786158 -25.799941) (xy 61.794144 -25.870815)
			(xy 61.794644 -25.906476) (xy 61.794144 -25.942137) (xy 62.428112 -25.942137) (xy 62.428112 -25.870815)
			(xy 62.436098 -25.799941) (xy 62.451968 -25.730406) (xy 62.475525 -25.663086) (xy 62.50647 -25.598827)
			(xy 62.544416 -25.538436) (xy 62.588885 -25.482674) (xy 62.639318 -25.432241) (xy 62.69508 -25.387772)
			(xy 62.755471 -25.349826) (xy 62.81973 -25.318881) (xy 62.88705 -25.295324) (xy 62.956585 -25.279454)
			(xy 63.027459 -25.271468) (xy 63.098781 -25.271468) (xy 63.169655 -25.279454) (xy 63.23919 -25.295324)
			(xy 63.30651 -25.318881) (xy 63.370769 -25.349826) (xy 63.43116 -25.387772) (xy 63.486922 -25.432241)
			(xy 63.537355 -25.482674) (xy 63.581824 -25.538436) (xy 63.61977 -25.598827) (xy 63.650715 -25.663086)
			(xy 63.674272 -25.730406) (xy 63.690142 -25.799941) (xy 63.698128 -25.870815) (xy 63.698628 -25.906476)
			(xy 63.698128 -25.942137) (xy 63.690142 -26.013011) (xy 63.674272 -26.082546) (xy 63.650715 -26.149866)
			(xy 63.61977 -26.214125) (xy 63.581824 -26.274516) (xy 63.537355 -26.330278) (xy 63.486922 -26.380711)
			(xy 63.43116 -26.42518) (xy 63.370769 -26.463126) (xy 63.30651 -26.494071) (xy 63.23919 -26.517628)
			(xy 63.169655 -26.533498) (xy 63.098781 -26.541484) (xy 63.027459 -26.541484) (xy 62.956585 -26.533498)
			(xy 62.88705 -26.517628) (xy 62.81973 -26.494071) (xy 62.755471 -26.463126) (xy 62.69508 -26.42518)
			(xy 62.639318 -26.380711) (xy 62.588885 -26.330278) (xy 62.544416 -26.274516) (xy 62.50647 -26.214125)
			(xy 62.475525 -26.149866) (xy 62.451968 -26.082546) (xy 62.436098 -26.013011) (xy 62.428112 -25.942137)
			(xy 61.794144 -25.942137) (xy 61.786158 -26.013011) (xy 61.770288 -26.082546) (xy 61.746731 -26.149866)
			(xy 61.715786 -26.214125) (xy 61.67784 -26.274516) (xy 61.633371 -26.330278) (xy 61.582938 -26.380711)
			(xy 61.527176 -26.42518) (xy 61.466785 -26.463126) (xy 61.402526 -26.494071) (xy 61.335206 -26.517628)
			(xy 61.265671 -26.533498) (xy 61.194797 -26.541484) (xy 61.123475 -26.541484) (xy 61.052601 -26.533498)
			(xy 60.983066 -26.517628) (xy 60.915746 -26.494071) (xy 60.851487 -26.463126) (xy 60.791096 -26.42518)
			(xy 60.735334 -26.380711) (xy 60.684901 -26.330278) (xy 60.640432 -26.274516) (xy 60.602486 -26.214125)
			(xy 60.571541 -26.149866) (xy 60.547984 -26.082546) (xy 60.532114 -26.013011) (xy 60.524128 -25.942137)
			(xy 29.24048 -25.942137) (xy 29.24048 -27.493484) (xy 29.519874 -27.493484) (xy 29.519874 -27.406584)
			(xy 29.527892 -27.320055) (xy 29.54386 -27.234635) (xy 29.567641 -27.151053) (xy 29.599033 -27.070021)
			(xy 29.637767 -26.992232) (xy 29.683514 -26.918348) (xy 29.735883 -26.849001) (xy 29.794427 -26.784781)
			(xy 29.858647 -26.726237) (xy 29.927994 -26.673868) (xy 30.001878 -26.628121) (xy 30.079667 -26.589387)
			(xy 30.160699 -26.557995) (xy 30.244281 -26.534214) (xy 30.329701 -26.518246) (xy 30.41623 -26.510228)
			(xy 30.50313 -26.510228) (xy 30.589659 -26.518246) (xy 30.675079 -26.534214) (xy 30.758661 -26.557995)
			(xy 30.839693 -26.589387) (xy 30.917482 -26.628121) (xy 30.991366 -26.673868) (xy 31.060713 -26.726237)
			(xy 31.124933 -26.784781) (xy 31.183477 -26.849001) (xy 31.235846 -26.918348) (xy 31.281593 -26.992232)
			(xy 31.320327 -27.070021) (xy 31.351719 -27.151053) (xy 31.3755 -27.234635) (xy 31.391468 -27.320055)
			(xy 31.399486 -27.406584) (xy 31.399988 -27.450034) (xy 31.399486 -27.493484) (xy 34.599874 -27.493484)
			(xy 34.599874 -27.406584) (xy 34.607892 -27.320055) (xy 34.62386 -27.234635) (xy 34.647641 -27.151053)
			(xy 34.679033 -27.070021) (xy 34.717767 -26.992232) (xy 34.763514 -26.918348) (xy 34.815883 -26.849001)
			(xy 34.874427 -26.784781) (xy 34.938647 -26.726237) (xy 35.007994 -26.673868) (xy 35.081878 -26.628121)
			(xy 35.159667 -26.589387) (xy 35.240699 -26.557995) (xy 35.324281 -26.534214) (xy 35.409701 -26.518246)
			(xy 35.49623 -26.510228) (xy 35.58313 -26.510228) (xy 35.669659 -26.518246) (xy 35.755079 -26.534214)
			(xy 35.838661 -26.557995) (xy 35.919693 -26.589387) (xy 35.997482 -26.628121) (xy 36.071366 -26.673868)
			(xy 36.140713 -26.726237) (xy 36.204933 -26.784781) (xy 36.263477 -26.849001) (xy 36.315846 -26.918348)
			(xy 36.361593 -26.992232) (xy 36.400327 -27.070021) (xy 36.431719 -27.151053) (xy 36.4555 -27.234635)
			(xy 36.471468 -27.320055) (xy 36.479486 -27.406584) (xy 36.479988 -27.450034) (xy 36.479486 -27.493484)
			(xy 36.471468 -27.580013) (xy 36.4555 -27.665433) (xy 36.431719 -27.749015) (xy 36.400327 -27.830047)
			(xy 36.361593 -27.907836) (xy 36.315846 -27.98172) (xy 36.263477 -28.051067) (xy 36.204933 -28.115287)
			(xy 36.140713 -28.173831) (xy 36.071366 -28.2262) (xy 35.997482 -28.271947) (xy 35.919693 -28.310681)
			(xy 35.86198 -28.333039) (xy 41.655992 -28.333039) (xy 41.655992 -28.261717) (xy 41.663978 -28.190843)
			(xy 41.679848 -28.121308) (xy 41.703405 -28.053988) (xy 41.73435 -27.989729) (xy 41.772296 -27.929338)
			(xy 41.816765 -27.873576) (xy 41.867198 -27.823143) (xy 41.92296 -27.778674) (xy 41.983351 -27.740728)
			(xy 42.04761 -27.709783) (xy 42.11493 -27.686226) (xy 42.184465 -27.670356) (xy 42.255339 -27.66237)
			(xy 42.326661 -27.66237) (xy 42.397535 -27.670356) (xy 42.46707 -27.686226) (xy 42.53439 -27.709783)
			(xy 42.598649 -27.740728) (xy 42.65904 -27.778674) (xy 42.714802 -27.823143) (xy 42.765235 -27.873576)
			(xy 42.809704 -27.929338) (xy 42.84765 -27.989729) (xy 42.878595 -28.053988) (xy 42.902152 -28.121308)
			(xy 42.918022 -28.190843) (xy 42.926008 -28.261717) (xy 42.926508 -28.297378) (xy 42.926008 -28.333039)
			(xy 43.542704 -28.333039) (xy 43.542704 -28.261717) (xy 43.55069 -28.190843) (xy 43.56656 -28.121308)
			(xy 43.590117 -28.053988) (xy 43.621062 -27.989729) (xy 43.659008 -27.929338) (xy 43.703477 -27.873576)
			(xy 43.75391 -27.823143) (xy 43.809672 -27.778674) (xy 43.870063 -27.740728) (xy 43.934322 -27.709783)
			(xy 44.001642 -27.686226) (xy 44.071177 -27.670356) (xy 44.142051 -27.66237) (xy 44.213373 -27.66237)
			(xy 44.284247 -27.670356) (xy 44.353782 -27.686226) (xy 44.421102 -27.709783) (xy 44.485361 -27.740728)
			(xy 44.545752 -27.778674) (xy 44.601514 -27.823143) (xy 44.651947 -27.873576) (xy 44.696416 -27.929338)
			(xy 44.734362 -27.989729) (xy 44.765307 -28.053988) (xy 44.788864 -28.121308) (xy 44.804734 -28.190843)
			(xy 44.81272 -28.261717) (xy 44.81322 -28.297378) (xy 44.81272 -28.333039) (xy 44.804734 -28.403913)
			(xy 44.788864 -28.473448) (xy 44.765307 -28.540768) (xy 44.734362 -28.605027) (xy 44.696416 -28.665418)
			(xy 44.651947 -28.72118) (xy 44.601514 -28.771613) (xy 44.545752 -28.816082) (xy 44.485361 -28.854028)
			(xy 44.421102 -28.884973) (xy 44.353782 -28.90853) (xy 44.284247 -28.9244) (xy 44.213373 -28.932386)
			(xy 44.142051 -28.932386) (xy 44.071177 -28.9244) (xy 44.001642 -28.90853) (xy 43.934322 -28.884973)
			(xy 43.870063 -28.854028) (xy 43.809672 -28.816082) (xy 43.75391 -28.771613) (xy 43.703477 -28.72118)
			(xy 43.659008 -28.665418) (xy 43.621062 -28.605027) (xy 43.590117 -28.540768) (xy 43.56656 -28.473448)
			(xy 43.55069 -28.403913) (xy 43.542704 -28.333039) (xy 42.926008 -28.333039) (xy 42.918022 -28.403913)
			(xy 42.902152 -28.473448) (xy 42.878595 -28.540768) (xy 42.84765 -28.605027) (xy 42.809704 -28.665418)
			(xy 42.765235 -28.72118) (xy 42.714802 -28.771613) (xy 42.65904 -28.816082) (xy 42.598649 -28.854028)
			(xy 42.53439 -28.884973) (xy 42.46707 -28.90853) (xy 42.397535 -28.9244) (xy 42.326661 -28.932386)
			(xy 42.255339 -28.932386) (xy 42.184465 -28.9244) (xy 42.11493 -28.90853) (xy 42.04761 -28.884973)
			(xy 41.983351 -28.854028) (xy 41.92296 -28.816082) (xy 41.867198 -28.771613) (xy 41.816765 -28.72118)
			(xy 41.772296 -28.665418) (xy 41.73435 -28.605027) (xy 41.703405 -28.540768) (xy 41.679848 -28.473448)
			(xy 41.663978 -28.403913) (xy 41.655992 -28.333039) (xy 35.86198 -28.333039) (xy 35.838661 -28.342073)
			(xy 35.755079 -28.365854) (xy 35.669659 -28.381822) (xy 35.58313 -28.38984) (xy 35.49623 -28.38984)
			(xy 35.409701 -28.381822) (xy 35.324281 -28.365854) (xy 35.240699 -28.342073) (xy 35.159667 -28.310681)
			(xy 35.081878 -28.271947) (xy 35.007994 -28.2262) (xy 34.938647 -28.173831) (xy 34.874427 -28.115287)
			(xy 34.815883 -28.051067) (xy 34.763514 -27.98172) (xy 34.717767 -27.907836) (xy 34.679033 -27.830047)
			(xy 34.647641 -27.749015) (xy 34.62386 -27.665433) (xy 34.607892 -27.580013) (xy 34.599874 -27.493484)
			(xy 31.399486 -27.493484) (xy 31.391468 -27.580013) (xy 31.3755 -27.665433) (xy 31.351719 -27.749015)
			(xy 31.320327 -27.830047) (xy 31.281593 -27.907836) (xy 31.235846 -27.98172) (xy 31.183477 -28.051067)
			(xy 31.124933 -28.115287) (xy 31.060713 -28.173831) (xy 30.991366 -28.2262) (xy 30.917482 -28.271947)
			(xy 30.839693 -28.310681) (xy 30.758661 -28.342073) (xy 30.675079 -28.365854) (xy 30.589659 -28.381822)
			(xy 30.50313 -28.38984) (xy 30.41623 -28.38984) (xy 30.329701 -28.381822) (xy 30.244281 -28.365854)
			(xy 30.160699 -28.342073) (xy 30.079667 -28.310681) (xy 30.001878 -28.271947) (xy 29.927994 -28.2262)
			(xy 29.858647 -28.173831) (xy 29.794427 -28.115287) (xy 29.735883 -28.051067) (xy 29.683514 -27.98172)
			(xy 29.637767 -27.907836) (xy 29.599033 -27.830047) (xy 29.567641 -27.749015) (xy 29.54386 -27.665433)
			(xy 29.527892 -27.580013) (xy 29.519874 -27.493484) (xy 29.24048 -27.493484) (xy 29.24048 -30.033484)
			(xy 29.519874 -30.033484) (xy 29.519874 -29.946584) (xy 29.527892 -29.860055) (xy 29.54386 -29.774635)
			(xy 29.567641 -29.691053) (xy 29.599033 -29.610021) (xy 29.637767 -29.532232) (xy 29.683514 -29.458348)
			(xy 29.735883 -29.389001) (xy 29.794427 -29.324781) (xy 29.858647 -29.266237) (xy 29.927994 -29.213868)
			(xy 30.001878 -29.168121) (xy 30.079667 -29.129387) (xy 30.160699 -29.097995) (xy 30.244281 -29.074214)
			(xy 30.329701 -29.058246) (xy 30.41623 -29.050228) (xy 30.50313 -29.050228) (xy 30.589659 -29.058246)
			(xy 30.675079 -29.074214) (xy 30.758661 -29.097995) (xy 30.839693 -29.129387) (xy 30.917482 -29.168121)
			(xy 30.991366 -29.213868) (xy 31.060713 -29.266237) (xy 31.124933 -29.324781) (xy 31.183477 -29.389001)
			(xy 31.235846 -29.458348) (xy 31.281593 -29.532232) (xy 31.320327 -29.610021) (xy 31.351719 -29.691053)
			(xy 31.3755 -29.774635) (xy 31.391468 -29.860055) (xy 31.399486 -29.946584) (xy 31.399988 -29.990034)
			(xy 31.399486 -30.033484) (xy 34.599874 -30.033484) (xy 34.599874 -29.946584) (xy 34.607892 -29.860055)
			(xy 34.62386 -29.774635) (xy 34.647641 -29.691053) (xy 34.679033 -29.610021) (xy 34.717767 -29.532232)
			(xy 34.763514 -29.458348) (xy 34.815883 -29.389001) (xy 34.874427 -29.324781) (xy 34.938647 -29.266237)
			(xy 35.007994 -29.213868) (xy 35.081878 -29.168121) (xy 35.159667 -29.129387) (xy 35.240699 -29.097995)
			(xy 35.324281 -29.074214) (xy 35.409701 -29.058246) (xy 35.49623 -29.050228) (xy 35.58313 -29.050228)
			(xy 35.669659 -29.058246) (xy 35.755079 -29.074214) (xy 35.838661 -29.097995) (xy 35.919693 -29.129387)
			(xy 35.997482 -29.168121) (xy 36.071366 -29.213868) (xy 36.140713 -29.266237) (xy 36.204933 -29.324781)
			(xy 36.258565 -29.383613) (xy 64.827449 -29.383613) (xy 64.827449 -29.320387) (xy 64.835701 -29.257702)
			(xy 64.852064 -29.196631) (xy 64.876258 -29.138217) (xy 64.907869 -29.083461) (xy 64.946356 -29.033299)
			(xy 64.991061 -28.988589) (xy 65.041219 -28.950097) (xy 65.095972 -28.91848) (xy 65.154383 -28.89428)
			(xy 65.215453 -28.877911) (xy 65.278137 -28.869652) (xy 65.30975 -28.869132) (xy 66.491866 -28.869132)
			(xy 66.520129 -28.869525) (xy 66.576271 -28.876096) (xy 66.631259 -28.889186) (xy 66.68434 -28.908616)
			(xy 66.734784 -28.93412) (xy 66.758566 -28.949396) (xy 66.79057 -28.970478) (xy 66.993262 -28.970478)
			(xy 67.025266 -28.949396) (xy 67.049065 -28.934151) (xy 67.099516 -28.908672) (xy 67.152593 -28.889248)
			(xy 67.207573 -28.876145) (xy 67.263706 -28.86954) (xy 67.291966 -28.869132) (xy 67.977258 -28.869132)
			(xy 68.008874 -28.869652) (xy 68.071567 -28.8779) (xy 68.132646 -28.894262) (xy 68.191067 -28.918456)
			(xy 68.24583 -28.950069) (xy 68.295998 -28.98856) (xy 68.340712 -29.033271) (xy 68.379207 -29.083435)
			(xy 68.410825 -29.138195) (xy 68.435025 -29.196614) (xy 68.451391 -29.257692) (xy 68.459645 -29.320384)
			(xy 68.459645 -29.383616) (xy 68.451391 -29.446308) (xy 68.435025 -29.507386) (xy 68.410825 -29.565805)
			(xy 68.379207 -29.620565) (xy 68.340712 -29.670729) (xy 68.295998 -29.71544) (xy 68.24583 -29.753931)
			(xy 68.191067 -29.785544) (xy 68.132646 -29.809738) (xy 68.071567 -29.8261) (xy 68.008874 -29.834348)
			(xy 67.977258 -29.83484) (xy 67.291966 -29.83484) (xy 67.263703 -29.834468) (xy 67.20756 -29.827891)
			(xy 67.152572 -29.814795) (xy 67.099492 -29.795361) (xy 67.049047 -29.769854) (xy 67.025266 -29.754576)
			(xy 66.993262 -29.733494) (xy 66.79057 -29.733494) (xy 66.758566 -29.754576) (xy 66.734783 -29.769847)
			(xy 66.684328 -29.795322) (xy 66.631246 -29.814741) (xy 66.576263 -29.827838) (xy 66.520127 -29.834436)
			(xy 66.491866 -29.83484) (xy 65.30975 -29.83484) (xy 65.278137 -29.834348) (xy 65.215453 -29.826089)
			(xy 65.154383 -29.80972) (xy 65.095972 -29.78552) (xy 65.041219 -29.753903) (xy 64.991061 -29.715411)
			(xy 64.946356 -29.670701) (xy 64.907869 -29.620539) (xy 64.876258 -29.565783) (xy 64.852064 -29.507369)
			(xy 64.835701 -29.446298) (xy 64.827449 -29.383613) (xy 36.258565 -29.383613) (xy 36.263477 -29.389001)
			(xy 36.315846 -29.458348) (xy 36.361593 -29.532232) (xy 36.400327 -29.610021) (xy 36.431719 -29.691053)
			(xy 36.4555 -29.774635) (xy 36.471468 -29.860055) (xy 36.479486 -29.946584) (xy 36.479988 -29.990034)
			(xy 36.479486 -30.033484) (xy 36.471468 -30.120013) (xy 36.462747 -30.166665) (xy 41.655992 -30.166665)
			(xy 41.655992 -30.095343) (xy 41.663978 -30.024469) (xy 41.679848 -29.954934) (xy 41.703405 -29.887614)
			(xy 41.73435 -29.823355) (xy 41.772296 -29.762964) (xy 41.816765 -29.707202) (xy 41.867198 -29.656769)
			(xy 41.92296 -29.6123) (xy 41.983351 -29.574354) (xy 42.04761 -29.543409) (xy 42.11493 -29.519852)
			(xy 42.184465 -29.503982) (xy 42.255339 -29.495996) (xy 42.326661 -29.495996) (xy 42.397535 -29.503982)
			(xy 42.46707 -29.519852) (xy 42.53439 -29.543409) (xy 42.598649 -29.574354) (xy 42.65904 -29.6123)
			(xy 42.714802 -29.656769) (xy 42.765235 -29.707202) (xy 42.809704 -29.762964) (xy 42.84765 -29.823355)
			(xy 42.878595 -29.887614) (xy 42.902152 -29.954934) (xy 42.918022 -30.024469) (xy 42.926008 -30.095343)
			(xy 42.926508 -30.131004) (xy 42.926008 -30.166665) (xy 43.542704 -30.166665) (xy 43.542704 -30.095343)
			(xy 43.55069 -30.024469) (xy 43.56656 -29.954934) (xy 43.590117 -29.887614) (xy 43.621062 -29.823355)
			(xy 43.659008 -29.762964) (xy 43.703477 -29.707202) (xy 43.75391 -29.656769) (xy 43.809672 -29.6123)
			(xy 43.870063 -29.574354) (xy 43.934322 -29.543409) (xy 44.001642 -29.519852) (xy 44.071177 -29.503982)
			(xy 44.142051 -29.495996) (xy 44.213373 -29.495996) (xy 44.284247 -29.503982) (xy 44.353782 -29.519852)
			(xy 44.421102 -29.543409) (xy 44.485361 -29.574354) (xy 44.545752 -29.6123) (xy 44.601514 -29.656769)
			(xy 44.651947 -29.707202) (xy 44.696416 -29.762964) (xy 44.734362 -29.823355) (xy 44.765307 -29.887614)
			(xy 44.788864 -29.954934) (xy 44.804734 -30.024469) (xy 44.81272 -30.095343) (xy 44.81322 -30.131004)
			(xy 44.81272 -30.166665) (xy 44.804734 -30.237539) (xy 44.788864 -30.307074) (xy 44.765307 -30.374394)
			(xy 44.734362 -30.438653) (xy 44.696416 -30.499044) (xy 44.651947 -30.554806) (xy 44.601514 -30.605239)
			(xy 44.545752 -30.649708) (xy 44.485361 -30.687654) (xy 44.421102 -30.718599) (xy 44.353782 -30.742156)
			(xy 44.284247 -30.758026) (xy 44.213373 -30.766012) (xy 44.142051 -30.766012) (xy 44.071177 -30.758026)
			(xy 44.001642 -30.742156) (xy 43.934322 -30.718599) (xy 43.870063 -30.687654) (xy 43.809672 -30.649708)
			(xy 43.75391 -30.605239) (xy 43.703477 -30.554806) (xy 43.659008 -30.499044) (xy 43.621062 -30.438653)
			(xy 43.590117 -30.374394) (xy 43.56656 -30.307074) (xy 43.55069 -30.237539) (xy 43.542704 -30.166665)
			(xy 42.926008 -30.166665) (xy 42.918022 -30.237539) (xy 42.902152 -30.307074) (xy 42.878595 -30.374394)
			(xy 42.84765 -30.438653) (xy 42.809704 -30.499044) (xy 42.765235 -30.554806) (xy 42.714802 -30.605239)
			(xy 42.65904 -30.649708) (xy 42.598649 -30.687654) (xy 42.53439 -30.718599) (xy 42.46707 -30.742156)
			(xy 42.397535 -30.758026) (xy 42.326661 -30.766012) (xy 42.255339 -30.766012) (xy 42.184465 -30.758026)
			(xy 42.11493 -30.742156) (xy 42.04761 -30.718599) (xy 41.983351 -30.687654) (xy 41.92296 -30.649708)
			(xy 41.867198 -30.605239) (xy 41.816765 -30.554806) (xy 41.772296 -30.499044) (xy 41.73435 -30.438653)
			(xy 41.703405 -30.374394) (xy 41.679848 -30.307074) (xy 41.663978 -30.237539) (xy 41.655992 -30.166665)
			(xy 36.462747 -30.166665) (xy 36.4555 -30.205433) (xy 36.431719 -30.289015) (xy 36.400327 -30.370047)
			(xy 36.361593 -30.447836) (xy 36.315846 -30.52172) (xy 36.263477 -30.591067) (xy 36.204933 -30.655287)
			(xy 36.140713 -30.713831) (xy 36.071366 -30.7662) (xy 35.997482 -30.811947) (xy 35.919693 -30.850681)
			(xy 35.838661 -30.882073) (xy 35.755079 -30.905854) (xy 35.669659 -30.921822) (xy 35.58313 -30.92984)
			(xy 35.49623 -30.92984) (xy 35.409701 -30.921822) (xy 35.324281 -30.905854) (xy 35.240699 -30.882073)
			(xy 35.159667 -30.850681) (xy 35.081878 -30.811947) (xy 35.007994 -30.7662) (xy 34.938647 -30.713831)
			(xy 34.874427 -30.655287) (xy 34.815883 -30.591067) (xy 34.763514 -30.52172) (xy 34.717767 -30.447836)
			(xy 34.679033 -30.370047) (xy 34.647641 -30.289015) (xy 34.62386 -30.205433) (xy 34.607892 -30.120013)
			(xy 34.599874 -30.033484) (xy 31.399486 -30.033484) (xy 31.391468 -30.120013) (xy 31.3755 -30.205433)
			(xy 31.351719 -30.289015) (xy 31.320327 -30.370047) (xy 31.281593 -30.447836) (xy 31.235846 -30.52172)
			(xy 31.183477 -30.591067) (xy 31.124933 -30.655287) (xy 31.060713 -30.713831) (xy 30.991366 -30.7662)
			(xy 30.917482 -30.811947) (xy 30.839693 -30.850681) (xy 30.758661 -30.882073) (xy 30.675079 -30.905854)
			(xy 30.589659 -30.921822) (xy 30.50313 -30.92984) (xy 30.41623 -30.92984) (xy 30.329701 -30.921822)
			(xy 30.244281 -30.905854) (xy 30.160699 -30.882073) (xy 30.079667 -30.850681) (xy 30.001878 -30.811947)
			(xy 29.927994 -30.7662) (xy 29.858647 -30.713831) (xy 29.794427 -30.655287) (xy 29.735883 -30.591067)
			(xy 29.683514 -30.52172) (xy 29.637767 -30.447836) (xy 29.599033 -30.370047) (xy 29.567641 -30.289015)
			(xy 29.54386 -30.205433) (xy 29.527892 -30.120013) (xy 29.519874 -30.033484) (xy 29.24048 -30.033484)
			(xy 29.24048 -32.573484) (xy 29.519874 -32.573484) (xy 29.519874 -32.486584) (xy 29.527892 -32.400055)
			(xy 29.54386 -32.314635) (xy 29.567641 -32.231053) (xy 29.599033 -32.150021) (xy 29.637767 -32.072232)
			(xy 29.683514 -31.998348) (xy 29.735883 -31.929001) (xy 29.794427 -31.864781) (xy 29.858647 -31.806237)
			(xy 29.927994 -31.753868) (xy 30.001878 -31.708121) (xy 30.079667 -31.669387) (xy 30.160699 -31.637995)
			(xy 30.244281 -31.614214) (xy 30.329701 -31.598246) (xy 30.41623 -31.590228) (xy 30.50313 -31.590228)
			(xy 30.589659 -31.598246) (xy 30.675079 -31.614214) (xy 30.758661 -31.637995) (xy 30.839693 -31.669387)
			(xy 30.917482 -31.708121) (xy 30.991366 -31.753868) (xy 31.060713 -31.806237) (xy 31.124933 -31.864781)
			(xy 31.183477 -31.929001) (xy 31.235846 -31.998348) (xy 31.281593 -32.072232) (xy 31.320327 -32.150021)
			(xy 31.351719 -32.231053) (xy 31.3755 -32.314635) (xy 31.391468 -32.400055) (xy 31.399486 -32.486584)
			(xy 31.399988 -32.530034) (xy 31.399486 -32.573484) (xy 34.599874 -32.573484) (xy 34.599874 -32.486584)
			(xy 34.607892 -32.400055) (xy 34.62386 -32.314635) (xy 34.647641 -32.231053) (xy 34.679033 -32.150021)
			(xy 34.717767 -32.072232) (xy 34.763514 -31.998348) (xy 34.815883 -31.929001) (xy 34.874427 -31.864781)
			(xy 34.938647 -31.806237) (xy 35.007994 -31.753868) (xy 35.081878 -31.708121) (xy 35.159667 -31.669387)
			(xy 35.240699 -31.637995) (xy 35.324281 -31.614214) (xy 35.409701 -31.598246) (xy 35.49623 -31.590228)
			(xy 35.58313 -31.590228) (xy 35.669659 -31.598246) (xy 35.755079 -31.614214) (xy 35.838661 -31.637995)
			(xy 35.919693 -31.669387) (xy 35.997482 -31.708121) (xy 36.071366 -31.753868) (xy 36.140713 -31.806237)
			(xy 36.204933 -31.864781) (xy 36.263477 -31.929001) (xy 36.315846 -31.998348) (xy 36.358726 -32.067601)
			(xy 41.655992 -32.067601) (xy 41.655992 -31.996279) (xy 41.663978 -31.925405) (xy 41.679848 -31.85587)
			(xy 41.703405 -31.78855) (xy 41.73435 -31.724291) (xy 41.772296 -31.6639) (xy 41.816765 -31.608138)
			(xy 41.867198 -31.557705) (xy 41.92296 -31.513236) (xy 41.983351 -31.47529) (xy 42.04761 -31.444345)
			(xy 42.11493 -31.420788) (xy 42.184465 -31.404918) (xy 42.255339 -31.396932) (xy 42.326661 -31.396932)
			(xy 42.397535 -31.404918) (xy 42.46707 -31.420788) (xy 42.53439 -31.444345) (xy 42.598649 -31.47529)
			(xy 42.65904 -31.513236) (xy 42.714802 -31.557705) (xy 42.765235 -31.608138) (xy 42.809704 -31.6639)
			(xy 42.84765 -31.724291) (xy 42.878595 -31.78855) (xy 42.902152 -31.85587) (xy 42.918022 -31.925405)
			(xy 42.926008 -31.996279) (xy 42.926508 -32.03194) (xy 42.926008 -32.067601) (xy 43.542704 -32.067601)
			(xy 43.542704 -31.996279) (xy 43.55069 -31.925405) (xy 43.56656 -31.85587) (xy 43.590117 -31.78855)
			(xy 43.621062 -31.724291) (xy 43.659008 -31.6639) (xy 43.703477 -31.608138) (xy 43.75391 -31.557705)
			(xy 43.809672 -31.513236) (xy 43.870063 -31.47529) (xy 43.934322 -31.444345) (xy 44.001642 -31.420788)
			(xy 44.071177 -31.404918) (xy 44.142051 -31.396932) (xy 44.213373 -31.396932) (xy 44.284247 -31.404918)
			(xy 44.353782 -31.420788) (xy 44.421102 -31.444345) (xy 44.485361 -31.47529) (xy 44.545752 -31.513236)
			(xy 44.601514 -31.557705) (xy 44.651947 -31.608138) (xy 44.696416 -31.6639) (xy 44.734362 -31.724291)
			(xy 44.765307 -31.78855) (xy 44.788864 -31.85587) (xy 44.804734 -31.925405) (xy 44.81272 -31.996279)
			(xy 44.81322 -32.03194) (xy 44.81272 -32.067601) (xy 44.804734 -32.138475) (xy 44.788864 -32.20801)
			(xy 44.765307 -32.27533) (xy 44.734362 -32.339589) (xy 44.696416 -32.39998) (xy 44.651947 -32.455742)
			(xy 44.601514 -32.506175) (xy 44.545752 -32.550644) (xy 44.485361 -32.58859) (xy 44.43315 -32.613733)
			(xy 64.781891 -32.613733) (xy 64.781891 -32.550467) (xy 64.79015 -32.487741) (xy 64.806525 -32.42663)
			(xy 64.830737 -32.36818) (xy 64.862372 -32.31339) (xy 64.900888 -32.263198) (xy 64.945627 -32.218463)
			(xy 64.995821 -32.179951) (xy 65.050614 -32.148321) (xy 65.109066 -32.124113) (xy 65.170178 -32.107742)
			(xy 65.232905 -32.099489) (xy 65.264538 -32.098996) (xy 65.567306 -32.098996) (xy 65.579498 -32.086804)
			(xy 66.42989 -32.086804) (xy 66.458185 -32.087197) (xy 66.514386 -32.09382) (xy 66.569428 -32.106965)
			(xy 66.622556 -32.126453) (xy 66.673044 -32.152015) (xy 66.696844 -32.167322) (xy 66.728594 -32.188404)
			(xy 66.785744 -32.188404) (xy 66.785744 -32.243522) (xy 66.805622 -32.265832) (xy 66.829875 -32.29991)
			(xy 69.997584 -32.29991) (xy 70.001572 -32.04729) (xy 70.013533 -31.794922) (xy 70.033455 -31.543058)
			(xy 70.061319 -31.291948) (xy 70.097095 -31.041842) (xy 70.140749 -30.792991) (xy 70.192238 -30.545642)
			(xy 70.251509 -30.300041) (xy 70.318504 -30.056434) (xy 70.393155 -29.815064) (xy 70.47539 -29.57617)
			(xy 70.565124 -29.339992) (xy 70.66227 -29.106764) (xy 70.76673 -28.876718) (xy 70.878401 -28.650086)
			(xy 70.99717 -28.427091) (xy 71.122919 -28.207957) (xy 71.255524 -27.992902) (xy 71.394851 -27.78214)
			(xy 71.540763 -27.575882) (xy 71.693113 -27.374333) (xy 71.851749 -27.177693) (xy 72.016514 -26.98616)
			(xy 72.187244 -26.799923) (xy 72.363768 -26.619169) (xy 72.54591 -26.444078) (xy 72.733488 -26.274824)
			(xy 72.926316 -26.111575) (xy 73.124201 -25.954496) (xy 73.326947 -25.803741) (xy 73.534351 -25.659463)
			(xy 73.746206 -25.521803) (xy 73.962301 -25.3909) (xy 74.182421 -25.266884) (xy 74.406346 -25.149879)
			(xy 74.633853 -25.040001) (xy 74.864715 -24.93736) (xy 75.098703 -24.842058) (xy 75.335582 -24.754191)
			(xy 75.575118 -24.673844) (xy 75.81707 -24.6011) (xy 76.061198 -24.53603) (xy 76.307259 -24.4787)
			(xy 76.555007 -24.429166) (xy 76.804195 -24.387477) (xy 77.054575 -24.353676) (xy 77.305897 -24.327795)
			(xy 77.557911 -24.309862) (xy 77.810365 -24.299893) (xy 78.063009 -24.297899) (xy 78.315589 -24.303881)
			(xy 78.567855 -24.317834) (xy 78.819554 -24.339744) (xy 79.070437 -24.369588) (xy 79.320252 -24.407338)
			(xy 79.568751 -24.452955) (xy 79.815686 -24.506394) (xy 80.060811 -24.567602) (xy 80.303881 -24.636517)
			(xy 80.544655 -24.713072) (xy 80.782892 -24.797189) (xy 81.018355 -24.888786) (xy 81.250809 -24.98777)
			(xy 81.480023 -25.094042) (xy 81.705767 -25.207498) (xy 81.927817 -25.328023) (xy 82.145951 -25.455499)
			(xy 82.359953 -25.589797) (xy 82.569609 -25.730783) (xy 82.774709 -25.878318) (xy 82.975049 -26.032254)
			(xy 83.17043 -26.192438) (xy 83.360657 -26.35871) (xy 83.54554 -26.530905) (xy 83.724896 -26.708849)
			(xy 83.898544 -26.892368) (xy 84.066312 -27.081276) (xy 84.228033 -27.275387) (xy 84.383546 -27.474506)
			(xy 84.532695 -27.678435) (xy 84.675332 -27.886971) (xy 84.811315 -28.099906) (xy 84.940508 -28.317028)
			(xy 85.062783 -28.53812) (xy 85.178017 -28.762961) (xy 85.286096 -28.991329) (xy 85.386911 -29.222994)
			(xy 85.480363 -29.457727) (xy 85.566358 -29.695292) (xy 85.644811 -29.935454) (xy 85.715643 -30.177973)
			(xy 85.778784 -30.422608) (xy 85.834171 -30.669113) (xy 85.881748 -30.917244) (xy 85.921468 -31.166754)
			(xy 85.953292 -31.417393) (xy 85.977188 -31.668911) (xy 85.993132 -31.921059) (xy 86.001107 -32.173584)
			(xy 86.001606 -32.29991) (xy 86.001107 -32.426236) (xy 85.993132 -32.678761) (xy 85.977188 -32.930909)
			(xy 85.953292 -33.182427) (xy 85.921468 -33.433066) (xy 85.881748 -33.682576) (xy 85.834171 -33.930707)
			(xy 85.778784 -34.177212) (xy 85.715643 -34.421847) (xy 85.644811 -34.664366) (xy 85.566358 -34.904528)
			(xy 85.480363 -35.142093) (xy 85.386911 -35.376826) (xy 85.286096 -35.608491) (xy 85.178017 -35.836859)
			(xy 85.062783 -36.0617) (xy 84.940508 -36.282792) (xy 84.811315 -36.499914) (xy 84.675332 -36.712849)
			(xy 84.532695 -36.921385) (xy 84.383546 -37.125314) (xy 84.228033 -37.324433) (xy 84.066312 -37.518544)
			(xy 83.898544 -37.707452) (xy 83.724896 -37.890971) (xy 83.54554 -38.068915) (xy 83.360657 -38.24111)
			(xy 83.17043 -38.407382) (xy 82.975049 -38.567566) (xy 82.774709 -38.721502) (xy 82.569609 -38.869037)
			(xy 82.359953 -39.010023) (xy 82.145951 -39.144321) (xy 81.927817 -39.271797) (xy 81.705767 -39.392322)
			(xy 81.480023 -39.505778) (xy 81.250809 -39.61205) (xy 81.018355 -39.711034) (xy 80.782892 -39.802631)
			(xy 80.544655 -39.886748) (xy 80.303881 -39.963303) (xy 80.060811 -40.032218) (xy 79.815686 -40.093426)
			(xy 79.568751 -40.146865) (xy 79.320252 -40.192482) (xy 79.070437 -40.230232) (xy 78.819554 -40.260076)
			(xy 78.567855 -40.281986) (xy 78.315589 -40.295939) (xy 78.063009 -40.301921) (xy 77.810365 -40.299927)
			(xy 77.557911 -40.289958) (xy 77.305897 -40.272025) (xy 77.054575 -40.246144) (xy 76.804195 -40.212343)
			(xy 76.555007 -40.170654) (xy 76.307259 -40.12112) (xy 76.061198 -40.06379) (xy 75.81707 -39.99872)
			(xy 75.575118 -39.925976) (xy 75.335582 -39.845629) (xy 75.098703 -39.757762) (xy 74.864715 -39.66246)
			(xy 74.633853 -39.559819) (xy 74.406346 -39.449941) (xy 74.182421 -39.332936) (xy 73.962301 -39.20892)
			(xy 73.746206 -39.078017) (xy 73.534351 -38.940357) (xy 73.326947 -38.796079) (xy 73.124201 -38.645324)
			(xy 72.926316 -38.488245) (xy 72.733488 -38.324996) (xy 72.54591 -38.155742) (xy 72.363768 -37.980651)
			(xy 72.187244 -37.799897) (xy 72.016514 -37.61366) (xy 71.851749 -37.422127) (xy 71.693113 -37.225487)
			(xy 71.540763 -37.023938) (xy 71.394851 -36.81768) (xy 71.255524 -36.606918) (xy 71.122919 -36.391863)
			(xy 70.99717 -36.172729) (xy 70.878401 -35.949734) (xy 70.76673 -35.723102) (xy 70.66227 -35.493056)
			(xy 70.565124 -35.259828) (xy 70.47539 -35.02365) (xy 70.393155 -34.784756) (xy 70.318504 -34.543386)
			(xy 70.251509 -34.299779) (xy 70.192238 -34.054178) (xy 70.140749 -33.806829) (xy 70.097095 -33.557978)
			(xy 70.061319 -33.307872) (xy 70.033455 -33.056762) (xy 70.013533 -32.804898) (xy 70.001572 -32.55253)
			(xy 69.997584 -32.29991) (xy 66.829875 -32.29991) (xy 66.840271 -32.314517) (xy 66.868647 -32.367106)
			(xy 66.890318 -32.422794) (xy 66.904951 -32.480731) (xy 66.912323 -32.540031) (xy 66.912322 -32.599787)
			(xy 66.904948 -32.659086) (xy 66.890312 -32.717022) (xy 66.86864 -32.77271) (xy 66.840262 -32.825298)
			(xy 66.805611 -32.873982) (xy 66.785744 -32.896302) (xy 66.785744 -32.95142) (xy 66.728594 -32.95142)
			(xy 66.696844 -32.972502) (xy 66.673041 -32.987805) (xy 66.622556 -33.013371) (xy 66.569428 -33.032859)
			(xy 66.514386 -33.046) (xy 66.458185 -33.052616) (xy 66.42989 -33.05302) (xy 65.979802 -33.05302)
			(xy 65.96761 -33.065212) (xy 65.264538 -33.065212) (xy 65.232905 -33.064711) (xy 65.170178 -33.056458)
			(xy 65.109066 -33.040087) (xy 65.050614 -33.015879) (xy 64.995821 -32.984249) (xy 64.945627 -32.945737)
			(xy 64.900888 -32.901002) (xy 64.862372 -32.85081) (xy 64.830737 -32.79602) (xy 64.806525 -32.73757)
			(xy 64.79015 -32.676459) (xy 64.781891 -32.613733) (xy 44.43315 -32.613733) (xy 44.421102 -32.619535)
			(xy 44.353782 -32.643092) (xy 44.284247 -32.658962) (xy 44.213373 -32.666948) (xy 44.142051 -32.666948)
			(xy 44.071177 -32.658962) (xy 44.001642 -32.643092) (xy 43.934322 -32.619535) (xy 43.870063 -32.58859)
			(xy 43.809672 -32.550644) (xy 43.75391 -32.506175) (xy 43.703477 -32.455742) (xy 43.659008 -32.39998)
			(xy 43.621062 -32.339589) (xy 43.590117 -32.27533) (xy 43.56656 -32.20801) (xy 43.55069 -32.138475)
			(xy 43.542704 -32.067601) (xy 42.926008 -32.067601) (xy 42.918022 -32.138475) (xy 42.902152 -32.20801)
			(xy 42.878595 -32.27533) (xy 42.84765 -32.339589) (xy 42.809704 -32.39998) (xy 42.765235 -32.455742)
			(xy 42.714802 -32.506175) (xy 42.65904 -32.550644) (xy 42.598649 -32.58859) (xy 42.53439 -32.619535)
			(xy 42.46707 -32.643092) (xy 42.397535 -32.658962) (xy 42.326661 -32.666948) (xy 42.255339 -32.666948)
			(xy 42.184465 -32.658962) (xy 42.11493 -32.643092) (xy 42.04761 -32.619535) (xy 41.983351 -32.58859)
			(xy 41.92296 -32.550644) (xy 41.867198 -32.506175) (xy 41.816765 -32.455742) (xy 41.772296 -32.39998)
			(xy 41.73435 -32.339589) (xy 41.703405 -32.27533) (xy 41.679848 -32.20801) (xy 41.663978 -32.138475)
			(xy 41.655992 -32.067601) (xy 36.358726 -32.067601) (xy 36.361593 -32.072232) (xy 36.400327 -32.150021)
			(xy 36.431719 -32.231053) (xy 36.4555 -32.314635) (xy 36.471468 -32.400055) (xy 36.479486 -32.486584)
			(xy 36.479988 -32.530034) (xy 36.479486 -32.573484) (xy 36.471468 -32.660013) (xy 36.4555 -32.745433)
			(xy 36.431719 -32.829015) (xy 36.400327 -32.910047) (xy 36.361593 -32.987836) (xy 36.315846 -33.06172)
			(xy 36.263477 -33.131067) (xy 36.204933 -33.195287) (xy 36.140713 -33.253831) (xy 36.071366 -33.3062)
			(xy 35.997482 -33.351947) (xy 35.919693 -33.390681) (xy 35.838661 -33.422073) (xy 35.755079 -33.445854)
			(xy 35.669659 -33.461822) (xy 35.58313 -33.46984) (xy 35.49623 -33.46984) (xy 35.409701 -33.461822)
			(xy 35.324281 -33.445854) (xy 35.240699 -33.422073) (xy 35.159667 -33.390681) (xy 35.081878 -33.351947)
			(xy 35.007994 -33.3062) (xy 34.938647 -33.253831) (xy 34.874427 -33.195287) (xy 34.815883 -33.131067)
			(xy 34.763514 -33.06172) (xy 34.717767 -32.987836) (xy 34.679033 -32.910047) (xy 34.647641 -32.829015)
			(xy 34.62386 -32.745433) (xy 34.607892 -32.660013) (xy 34.599874 -32.573484) (xy 31.399486 -32.573484)
			(xy 31.391468 -32.660013) (xy 31.3755 -32.745433) (xy 31.351719 -32.829015) (xy 31.320327 -32.910047)
			(xy 31.281593 -32.987836) (xy 31.235846 -33.06172) (xy 31.183477 -33.131067) (xy 31.124933 -33.195287)
			(xy 31.060713 -33.253831) (xy 30.991366 -33.3062) (xy 30.917482 -33.351947) (xy 30.839693 -33.390681)
			(xy 30.758661 -33.422073) (xy 30.675079 -33.445854) (xy 30.589659 -33.461822) (xy 30.50313 -33.46984)
			(xy 30.41623 -33.46984) (xy 30.329701 -33.461822) (xy 30.244281 -33.445854) (xy 30.160699 -33.422073)
			(xy 30.079667 -33.390681) (xy 30.001878 -33.351947) (xy 29.927994 -33.3062) (xy 29.858647 -33.253831)
			(xy 29.794427 -33.195287) (xy 29.735883 -33.131067) (xy 29.683514 -33.06172) (xy 29.637767 -32.987836)
			(xy 29.599033 -32.910047) (xy 29.567641 -32.829015) (xy 29.54386 -32.745433) (xy 29.527892 -32.660013)
			(xy 29.519874 -32.573484) (xy 29.24048 -32.573484) (xy 29.24048 -33.742731) (xy 41.655992 -33.742731)
			(xy 41.655992 -33.671409) (xy 41.663978 -33.600535) (xy 41.679848 -33.531) (xy 41.703405 -33.46368)
			(xy 41.73435 -33.399421) (xy 41.772296 -33.33903) (xy 41.816765 -33.283268) (xy 41.867198 -33.232835)
			(xy 41.92296 -33.188366) (xy 41.983351 -33.15042) (xy 42.04761 -33.119475) (xy 42.11493 -33.095918)
			(xy 42.184465 -33.080048) (xy 42.255339 -33.072062) (xy 42.326661 -33.072062) (xy 42.397535 -33.080048)
			(xy 42.46707 -33.095918) (xy 42.53439 -33.119475) (xy 42.598649 -33.15042) (xy 42.65904 -33.188366)
			(xy 42.714802 -33.232835) (xy 42.765235 -33.283268) (xy 42.809704 -33.33903) (xy 42.84765 -33.399421)
			(xy 42.878595 -33.46368) (xy 42.902152 -33.531) (xy 42.918022 -33.600535) (xy 42.926008 -33.671409)
			(xy 42.926508 -33.70707) (xy 42.926008 -33.742731) (xy 43.542704 -33.742731) (xy 43.542704 -33.671409)
			(xy 43.55069 -33.600535) (xy 43.56656 -33.531) (xy 43.590117 -33.46368) (xy 43.621062 -33.399421)
			(xy 43.659008 -33.33903) (xy 43.703477 -33.283268) (xy 43.75391 -33.232835) (xy 43.809672 -33.188366)
			(xy 43.870063 -33.15042) (xy 43.934322 -33.119475) (xy 44.001642 -33.095918) (xy 44.071177 -33.080048)
			(xy 44.142051 -33.072062) (xy 44.213373 -33.072062) (xy 44.284247 -33.080048) (xy 44.353782 -33.095918)
			(xy 44.421102 -33.119475) (xy 44.485361 -33.15042) (xy 44.545752 -33.188366) (xy 44.601514 -33.232835)
			(xy 44.651947 -33.283268) (xy 44.696416 -33.33903) (xy 44.734362 -33.399421) (xy 44.765307 -33.46368)
			(xy 44.788864 -33.531) (xy 44.804734 -33.600535) (xy 44.81272 -33.671409) (xy 44.81322 -33.70707)
			(xy 44.81272 -33.742731) (xy 44.804734 -33.813605) (xy 44.788864 -33.88314) (xy 44.765307 -33.95046)
			(xy 44.734362 -34.014719) (xy 44.696416 -34.07511) (xy 44.651947 -34.130872) (xy 44.601514 -34.181305)
			(xy 44.545752 -34.225774) (xy 44.485361 -34.26372) (xy 44.421102 -34.294665) (xy 44.353782 -34.318222)
			(xy 44.284247 -34.334092) (xy 44.213373 -34.342078) (xy 44.142051 -34.342078) (xy 44.071177 -34.334092)
			(xy 44.001642 -34.318222) (xy 43.934322 -34.294665) (xy 43.870063 -34.26372) (xy 43.809672 -34.225774)
			(xy 43.75391 -34.181305) (xy 43.703477 -34.130872) (xy 43.659008 -34.07511) (xy 43.621062 -34.014719)
			(xy 43.590117 -33.95046) (xy 43.56656 -33.88314) (xy 43.55069 -33.813605) (xy 43.542704 -33.742731)
			(xy 42.926008 -33.742731) (xy 42.918022 -33.813605) (xy 42.902152 -33.88314) (xy 42.878595 -33.95046)
			(xy 42.84765 -34.014719) (xy 42.809704 -34.07511) (xy 42.765235 -34.130872) (xy 42.714802 -34.181305)
			(xy 42.65904 -34.225774) (xy 42.598649 -34.26372) (xy 42.53439 -34.294665) (xy 42.46707 -34.318222)
			(xy 42.397535 -34.334092) (xy 42.326661 -34.342078) (xy 42.255339 -34.342078) (xy 42.184465 -34.334092)
			(xy 42.11493 -34.318222) (xy 42.04761 -34.294665) (xy 41.983351 -34.26372) (xy 41.92296 -34.225774)
			(xy 41.867198 -34.181305) (xy 41.816765 -34.130872) (xy 41.772296 -34.07511) (xy 41.73435 -34.014719)
			(xy 41.703405 -33.95046) (xy 41.679848 -33.88314) (xy 41.663978 -33.813605) (xy 41.655992 -33.742731)
			(xy 29.24048 -33.742731) (xy 29.24048 -35.113484) (xy 29.519874 -35.113484) (xy 29.519874 -35.026584)
			(xy 29.527892 -34.940055) (xy 29.54386 -34.854635) (xy 29.567641 -34.771053) (xy 29.599033 -34.690021)
			(xy 29.637767 -34.612232) (xy 29.683514 -34.538348) (xy 29.735883 -34.469001) (xy 29.794427 -34.404781)
			(xy 29.858647 -34.346237) (xy 29.927994 -34.293868) (xy 30.001878 -34.248121) (xy 30.079667 -34.209387)
			(xy 30.160699 -34.177995) (xy 30.244281 -34.154214) (xy 30.329701 -34.138246) (xy 30.41623 -34.130228)
			(xy 30.50313 -34.130228) (xy 30.589659 -34.138246) (xy 30.675079 -34.154214) (xy 30.758661 -34.177995)
			(xy 30.839693 -34.209387) (xy 30.917482 -34.248121) (xy 30.991366 -34.293868) (xy 31.060713 -34.346237)
			(xy 31.124933 -34.404781) (xy 31.183477 -34.469001) (xy 31.235846 -34.538348) (xy 31.281593 -34.612232)
			(xy 31.320327 -34.690021) (xy 31.351719 -34.771053) (xy 31.3755 -34.854635) (xy 31.391468 -34.940055)
			(xy 31.399486 -35.026584) (xy 31.399988 -35.070034) (xy 31.399486 -35.113484) (xy 34.599874 -35.113484)
			(xy 34.599874 -35.026584) (xy 34.607892 -34.940055) (xy 34.62386 -34.854635) (xy 34.647641 -34.771053)
			(xy 34.679033 -34.690021) (xy 34.717767 -34.612232) (xy 34.763514 -34.538348) (xy 34.815883 -34.469001)
			(xy 34.874427 -34.404781) (xy 34.938647 -34.346237) (xy 35.007994 -34.293868) (xy 35.081878 -34.248121)
			(xy 35.159667 -34.209387) (xy 35.240699 -34.177995) (xy 35.324281 -34.154214) (xy 35.409701 -34.138246)
			(xy 35.49623 -34.130228) (xy 35.58313 -34.130228) (xy 35.669659 -34.138246) (xy 35.755079 -34.154214)
			(xy 35.838661 -34.177995) (xy 35.919693 -34.209387) (xy 35.997482 -34.248121) (xy 36.071366 -34.293868)
			(xy 36.140713 -34.346237) (xy 36.204933 -34.404781) (xy 36.263477 -34.469001) (xy 36.315846 -34.538348)
			(xy 36.361593 -34.612232) (xy 36.400327 -34.690021) (xy 36.431719 -34.771053) (xy 36.4555 -34.854635)
			(xy 36.471468 -34.940055) (xy 36.479486 -35.026584) (xy 36.479988 -35.070034) (xy 36.479486 -35.113484)
			(xy 36.471468 -35.200013) (xy 36.4555 -35.285433) (xy 36.431719 -35.369015) (xy 36.400327 -35.450047)
			(xy 36.361593 -35.527836) (xy 36.315846 -35.60172) (xy 36.263477 -35.671067) (xy 36.204933 -35.735287)
			(xy 36.184512 -35.753903) (xy 41.612558 -35.753903) (xy 41.612558 -35.682581) (xy 41.620544 -35.611707)
			(xy 41.636414 -35.542172) (xy 41.659971 -35.474852) (xy 41.690916 -35.410593) (xy 41.728862 -35.350202)
			(xy 41.773331 -35.29444) (xy 41.823764 -35.244007) (xy 41.879526 -35.199538) (xy 41.939917 -35.161592)
			(xy 42.004176 -35.130647) (xy 42.071496 -35.10709) (xy 42.141031 -35.09122) (xy 42.211905 -35.083234)
			(xy 42.283227 -35.083234) (xy 42.354101 -35.09122) (xy 42.423636 -35.10709) (xy 42.490956 -35.130647)
			(xy 42.555215 -35.161592) (xy 42.615606 -35.199538) (xy 42.671368 -35.244007) (xy 42.721801 -35.29444)
			(xy 42.76627 -35.350202) (xy 42.804216 -35.410593) (xy 42.835161 -35.474852) (xy 42.858718 -35.542172)
			(xy 42.874588 -35.611707) (xy 42.882574 -35.682581) (xy 42.883074 -35.718242) (xy 42.882574 -35.753903)
			(xy 43.49927 -35.753903) (xy 43.49927 -35.682581) (xy 43.507256 -35.611707) (xy 43.523126 -35.542172)
			(xy 43.546683 -35.474852) (xy 43.577628 -35.410593) (xy 43.615574 -35.350202) (xy 43.660043 -35.29444)
			(xy 43.710476 -35.244007) (xy 43.766238 -35.199538) (xy 43.826629 -35.161592) (xy 43.890888 -35.130647)
			(xy 43.958208 -35.10709) (xy 44.027743 -35.09122) (xy 44.098617 -35.083234) (xy 44.169939 -35.083234)
			(xy 44.240813 -35.09122) (xy 44.310348 -35.10709) (xy 44.377668 -35.130647) (xy 44.441927 -35.161592)
			(xy 44.502318 -35.199538) (xy 44.55808 -35.244007) (xy 44.608513 -35.29444) (xy 44.652982 -35.350202)
			(xy 44.690928 -35.410593) (xy 44.721873 -35.474852) (xy 44.74543 -35.542172) (xy 44.7613 -35.611707)
			(xy 44.769286 -35.682581) (xy 44.769786 -35.718242) (xy 44.769286 -35.753903) (xy 44.7613 -35.824777)
			(xy 44.74543 -35.894312) (xy 44.721873 -35.961632) (xy 44.690928 -36.025891) (xy 44.652982 -36.086282)
			(xy 44.608513 -36.142044) (xy 44.55808 -36.192477) (xy 44.502318 -36.236946) (xy 44.441927 -36.274892)
			(xy 44.377668 -36.305837) (xy 44.310348 -36.329394) (xy 44.240813 -36.345264) (xy 44.169939 -36.35325)
			(xy 44.098617 -36.35325) (xy 44.027743 -36.345264) (xy 43.958208 -36.329394) (xy 43.890888 -36.305837)
			(xy 43.826629 -36.274892) (xy 43.766238 -36.236946) (xy 43.710476 -36.192477) (xy 43.660043 -36.142044)
			(xy 43.615574 -36.086282) (xy 43.577628 -36.025891) (xy 43.546683 -35.961632) (xy 43.523126 -35.894312)
			(xy 43.507256 -35.824777) (xy 43.49927 -35.753903) (xy 42.882574 -35.753903) (xy 42.874588 -35.824777)
			(xy 42.858718 -35.894312) (xy 42.835161 -35.961632) (xy 42.804216 -36.025891) (xy 42.76627 -36.086282)
			(xy 42.721801 -36.142044) (xy 42.671368 -36.192477) (xy 42.615606 -36.236946) (xy 42.555215 -36.274892)
			(xy 42.490956 -36.305837) (xy 42.423636 -36.329394) (xy 42.354101 -36.345264) (xy 42.283227 -36.35325)
			(xy 42.211905 -36.35325) (xy 42.141031 -36.345264) (xy 42.071496 -36.329394) (xy 42.004176 -36.305837)
			(xy 41.939917 -36.274892) (xy 41.879526 -36.236946) (xy 41.823764 -36.192477) (xy 41.773331 -36.142044)
			(xy 41.728862 -36.086282) (xy 41.690916 -36.025891) (xy 41.659971 -35.961632) (xy 41.636414 -35.894312)
			(xy 41.620544 -35.824777) (xy 41.612558 -35.753903) (xy 36.184512 -35.753903) (xy 36.140713 -35.793831)
			(xy 36.071366 -35.8462) (xy 35.997482 -35.891947) (xy 35.919693 -35.930681) (xy 35.838661 -35.962073)
			(xy 35.755079 -35.985854) (xy 35.669659 -36.001822) (xy 35.58313 -36.00984) (xy 35.49623 -36.00984)
			(xy 35.409701 -36.001822) (xy 35.324281 -35.985854) (xy 35.240699 -35.962073) (xy 35.159667 -35.930681)
			(xy 35.081878 -35.891947) (xy 35.007994 -35.8462) (xy 34.938647 -35.793831) (xy 34.874427 -35.735287)
			(xy 34.815883 -35.671067) (xy 34.763514 -35.60172) (xy 34.717767 -35.527836) (xy 34.679033 -35.450047)
			(xy 34.647641 -35.369015) (xy 34.62386 -35.285433) (xy 34.607892 -35.200013) (xy 34.599874 -35.113484)
			(xy 31.399486 -35.113484) (xy 31.391468 -35.200013) (xy 31.3755 -35.285433) (xy 31.351719 -35.369015)
			(xy 31.320327 -35.450047) (xy 31.281593 -35.527836) (xy 31.235846 -35.60172) (xy 31.183477 -35.671067)
			(xy 31.124933 -35.735287) (xy 31.060713 -35.793831) (xy 30.991366 -35.8462) (xy 30.917482 -35.891947)
			(xy 30.839693 -35.930681) (xy 30.758661 -35.962073) (xy 30.675079 -35.985854) (xy 30.589659 -36.001822)
			(xy 30.50313 -36.00984) (xy 30.41623 -36.00984) (xy 30.329701 -36.001822) (xy 30.244281 -35.985854)
			(xy 30.160699 -35.962073) (xy 30.079667 -35.930681) (xy 30.001878 -35.891947) (xy 29.927994 -35.8462)
			(xy 29.858647 -35.793831) (xy 29.794427 -35.735287) (xy 29.735883 -35.671067) (xy 29.683514 -35.60172)
			(xy 29.637767 -35.527836) (xy 29.599033 -35.450047) (xy 29.567641 -35.369015) (xy 29.54386 -35.285433)
			(xy 29.527892 -35.200013) (xy 29.519874 -35.113484) (xy 29.24048 -35.113484) (xy 29.24048 -37.653484)
			(xy 29.519874 -37.653484) (xy 29.519874 -37.566584) (xy 29.527892 -37.480055) (xy 29.54386 -37.394635)
			(xy 29.567641 -37.311053) (xy 29.599033 -37.230021) (xy 29.637767 -37.152232) (xy 29.683514 -37.078348)
			(xy 29.735883 -37.009001) (xy 29.794427 -36.944781) (xy 29.858647 -36.886237) (xy 29.927994 -36.833868)
			(xy 30.001878 -36.788121) (xy 30.079667 -36.749387) (xy 30.160699 -36.717995) (xy 30.244281 -36.694214)
			(xy 30.329701 -36.678246) (xy 30.41623 -36.670228) (xy 30.50313 -36.670228) (xy 30.589659 -36.678246)
			(xy 30.675079 -36.694214) (xy 30.758661 -36.717995) (xy 30.839693 -36.749387) (xy 30.917482 -36.788121)
			(xy 30.991366 -36.833868) (xy 31.060713 -36.886237) (xy 31.124933 -36.944781) (xy 31.183477 -37.009001)
			(xy 31.235846 -37.078348) (xy 31.281593 -37.152232) (xy 31.320327 -37.230021) (xy 31.351719 -37.311053)
			(xy 31.3755 -37.394635) (xy 31.391468 -37.480055) (xy 31.399486 -37.566584) (xy 31.399988 -37.610034)
			(xy 31.399486 -37.653484) (xy 34.599874 -37.653484) (xy 34.599874 -37.566584) (xy 34.607892 -37.480055)
			(xy 34.62386 -37.394635) (xy 34.647641 -37.311053) (xy 34.679033 -37.230021) (xy 34.717767 -37.152232)
			(xy 34.763514 -37.078348) (xy 34.815883 -37.009001) (xy 34.874427 -36.944781) (xy 34.938647 -36.886237)
			(xy 35.007994 -36.833868) (xy 35.081878 -36.788121) (xy 35.159667 -36.749387) (xy 35.240699 -36.717995)
			(xy 35.324281 -36.694214) (xy 35.409701 -36.678246) (xy 35.49623 -36.670228) (xy 35.58313 -36.670228)
			(xy 35.669659 -36.678246) (xy 35.755079 -36.694214) (xy 35.838661 -36.717995) (xy 35.919693 -36.749387)
			(xy 35.997482 -36.788121) (xy 36.071366 -36.833868) (xy 36.140713 -36.886237) (xy 36.204933 -36.944781)
			(xy 36.263477 -37.009001) (xy 36.315846 -37.078348) (xy 36.361593 -37.152232) (xy 36.400327 -37.230021)
			(xy 36.431719 -37.311053) (xy 36.4555 -37.394635) (xy 36.471468 -37.480055) (xy 36.479486 -37.566584)
			(xy 36.479988 -37.610034) (xy 36.479591 -37.644425) (xy 41.612558 -37.644425) (xy 41.612558 -37.573103)
			(xy 41.620544 -37.502229) (xy 41.636414 -37.432694) (xy 41.659971 -37.365374) (xy 41.690916 -37.301115)
			(xy 41.728862 -37.240724) (xy 41.773331 -37.184962) (xy 41.823764 -37.134529) (xy 41.879526 -37.09006)
			(xy 41.939917 -37.052114) (xy 42.004176 -37.021169) (xy 42.071496 -36.997612) (xy 42.141031 -36.981742)
			(xy 42.211905 -36.973756) (xy 42.283227 -36.973756) (xy 42.354101 -36.981742) (xy 42.423636 -36.997612)
			(xy 42.490956 -37.021169) (xy 42.555215 -37.052114) (xy 42.615606 -37.09006) (xy 42.671368 -37.134529)
			(xy 42.721801 -37.184962) (xy 42.76627 -37.240724) (xy 42.804216 -37.301115) (xy 42.835161 -37.365374)
			(xy 42.858718 -37.432694) (xy 42.874588 -37.502229) (xy 42.882574 -37.573103) (xy 42.883074 -37.608764)
			(xy 42.882574 -37.644425) (xy 43.49927 -37.644425) (xy 43.49927 -37.573103) (xy 43.507256 -37.502229)
			(xy 43.523126 -37.432694) (xy 43.546683 -37.365374) (xy 43.577628 -37.301115) (xy 43.615574 -37.240724)
			(xy 43.660043 -37.184962) (xy 43.710476 -37.134529) (xy 43.766238 -37.09006) (xy 43.826629 -37.052114)
			(xy 43.890888 -37.021169) (xy 43.958208 -36.997612) (xy 44.027743 -36.981742) (xy 44.098617 -36.973756)
			(xy 44.169939 -36.973756) (xy 44.240813 -36.981742) (xy 44.310348 -36.997612) (xy 44.377668 -37.021169)
			(xy 44.441927 -37.052114) (xy 44.502318 -37.09006) (xy 44.55808 -37.134529) (xy 44.608513 -37.184962)
			(xy 44.652982 -37.240724) (xy 44.690928 -37.301115) (xy 44.721873 -37.365374) (xy 44.74543 -37.432694)
			(xy 44.7613 -37.502229) (xy 44.769286 -37.573103) (xy 44.769786 -37.608764) (xy 44.769286 -37.644425)
			(xy 44.7613 -37.715299) (xy 44.74543 -37.784834) (xy 44.721873 -37.852154) (xy 44.690928 -37.916413)
			(xy 44.652982 -37.976804) (xy 44.608513 -38.032566) (xy 44.55808 -38.082999) (xy 44.502318 -38.127468)
			(xy 44.441927 -38.165414) (xy 44.377668 -38.196359) (xy 44.310348 -38.219916) (xy 44.240813 -38.235786)
			(xy 44.169939 -38.243772) (xy 44.098617 -38.243772) (xy 44.027743 -38.235786) (xy 43.958208 -38.219916)
			(xy 43.890888 -38.196359) (xy 43.826629 -38.165414) (xy 43.766238 -38.127468) (xy 43.710476 -38.082999)
			(xy 43.660043 -38.032566) (xy 43.615574 -37.976804) (xy 43.577628 -37.916413) (xy 43.546683 -37.852154)
			(xy 43.523126 -37.784834) (xy 43.507256 -37.715299) (xy 43.49927 -37.644425) (xy 42.882574 -37.644425)
			(xy 42.874588 -37.715299) (xy 42.858718 -37.784834) (xy 42.835161 -37.852154) (xy 42.804216 -37.916413)
			(xy 42.76627 -37.976804) (xy 42.721801 -38.032566) (xy 42.671368 -38.082999) (xy 42.615606 -38.127468)
			(xy 42.555215 -38.165414) (xy 42.490956 -38.196359) (xy 42.423636 -38.219916) (xy 42.354101 -38.235786)
			(xy 42.283227 -38.243772) (xy 42.211905 -38.243772) (xy 42.141031 -38.235786) (xy 42.071496 -38.219916)
			(xy 42.004176 -38.196359) (xy 41.939917 -38.165414) (xy 41.879526 -38.127468) (xy 41.823764 -38.082999)
			(xy 41.773331 -38.032566) (xy 41.728862 -37.976804) (xy 41.690916 -37.916413) (xy 41.659971 -37.852154)
			(xy 41.636414 -37.784834) (xy 41.620544 -37.715299) (xy 41.612558 -37.644425) (xy 36.479591 -37.644425)
			(xy 36.479486 -37.653484) (xy 36.471468 -37.740013) (xy 36.4555 -37.825433) (xy 36.431719 -37.909015)
			(xy 36.400327 -37.990047) (xy 36.361593 -38.067836) (xy 36.315846 -38.14172) (xy 36.263477 -38.211067)
			(xy 36.204933 -38.275287) (xy 36.140713 -38.333831) (xy 36.071366 -38.3862) (xy 35.997482 -38.431947)
			(xy 35.919693 -38.470681) (xy 35.838661 -38.502073) (xy 35.755079 -38.525854) (xy 35.669659 -38.541822)
			(xy 35.58313 -38.54984) (xy 35.49623 -38.54984) (xy 35.409701 -38.541822) (xy 35.324281 -38.525854)
			(xy 35.240699 -38.502073) (xy 35.159667 -38.470681) (xy 35.081878 -38.431947) (xy 35.007994 -38.3862)
			(xy 34.938647 -38.333831) (xy 34.874427 -38.275287) (xy 34.815883 -38.211067) (xy 34.763514 -38.14172)
			(xy 34.717767 -38.067836) (xy 34.679033 -37.990047) (xy 34.647641 -37.909015) (xy 34.62386 -37.825433)
			(xy 34.607892 -37.740013) (xy 34.599874 -37.653484) (xy 31.399486 -37.653484) (xy 31.391468 -37.740013)
			(xy 31.3755 -37.825433) (xy 31.351719 -37.909015) (xy 31.320327 -37.990047) (xy 31.281593 -38.067836)
			(xy 31.235846 -38.14172) (xy 31.183477 -38.211067) (xy 31.124933 -38.275287) (xy 31.060713 -38.333831)
			(xy 30.991366 -38.3862) (xy 30.917482 -38.431947) (xy 30.839693 -38.470681) (xy 30.758661 -38.502073)
			(xy 30.675079 -38.525854) (xy 30.589659 -38.541822) (xy 30.50313 -38.54984) (xy 30.41623 -38.54984)
			(xy 30.329701 -38.541822) (xy 30.244281 -38.525854) (xy 30.160699 -38.502073) (xy 30.079667 -38.470681)
			(xy 30.001878 -38.431947) (xy 29.927994 -38.3862) (xy 29.858647 -38.333831) (xy 29.794427 -38.275287)
			(xy 29.735883 -38.211067) (xy 29.683514 -38.14172) (xy 29.637767 -38.067836) (xy 29.599033 -37.990047)
			(xy 29.567641 -37.909015) (xy 29.54386 -37.825433) (xy 29.527892 -37.740013) (xy 29.519874 -37.653484)
			(xy 29.24048 -37.653484) (xy 29.24048 -38.661255) (xy 47.507896 -38.661255) (xy 47.507896 -38.580145)
			(xy 47.515846 -38.499426) (xy 47.531669 -38.419875) (xy 47.555214 -38.342259) (xy 47.586253 -38.267323)
			(xy 47.624488 -38.195791) (xy 47.66955 -38.128351) (xy 47.721005 -38.065652) (xy 47.778358 -38.008299)
			(xy 47.841057 -37.956844) (xy 47.908497 -37.911782) (xy 47.980029 -37.873547) (xy 48.054965 -37.842508)
			(xy 48.132581 -37.818963) (xy 48.212132 -37.80314) (xy 48.292851 -37.79519) (xy 48.373961 -37.79519)
			(xy 48.45468 -37.80314) (xy 48.534231 -37.818963) (xy 48.611847 -37.842508) (xy 48.686783 -37.873547)
			(xy 48.758315 -37.911782) (xy 48.825755 -37.956844) (xy 48.888454 -38.008299) (xy 48.945807 -38.065652)
			(xy 48.997262 -38.128351) (xy 49.042324 -38.195791) (xy 49.080559 -38.267323) (xy 49.111598 -38.342259)
			(xy 49.135143 -38.419875) (xy 49.150966 -38.499426) (xy 49.158916 -38.580145) (xy 49.159414 -38.6207)
			(xy 49.158916 -38.661255) (xy 49.150966 -38.741974) (xy 49.135143 -38.821525) (xy 49.111598 -38.899141)
			(xy 49.080559 -38.974077) (xy 49.042324 -39.045609) (xy 48.997262 -39.113049) (xy 48.945807 -39.175748)
			(xy 48.888454 -39.233101) (xy 48.825755 -39.284556) (xy 48.758315 -39.329618) (xy 48.686783 -39.367853)
			(xy 48.611847 -39.398892) (xy 48.534231 -39.422437) (xy 48.45468 -39.43826) (xy 48.373961 -39.44621)
			(xy 48.292851 -39.44621) (xy 48.212132 -39.43826) (xy 48.132581 -39.422437) (xy 48.054965 -39.398892)
			(xy 47.980029 -39.367853) (xy 47.908497 -39.329618) (xy 47.841057 -39.284556) (xy 47.778358 -39.233101)
			(xy 47.721005 -39.175748) (xy 47.66955 -39.113049) (xy 47.624488 -39.045609) (xy 47.586253 -38.974077)
			(xy 47.555214 -38.899141) (xy 47.531669 -38.821525) (xy 47.515846 -38.741974) (xy 47.507896 -38.661255)
			(xy 29.24048 -38.661255) (xy 29.24048 -40.193484) (xy 29.519874 -40.193484) (xy 29.519874 -40.106584)
			(xy 29.527892 -40.020055) (xy 29.54386 -39.934635) (xy 29.567641 -39.851053) (xy 29.599033 -39.770021)
			(xy 29.637767 -39.692232) (xy 29.683514 -39.618348) (xy 29.735883 -39.549001) (xy 29.794427 -39.484781)
			(xy 29.858647 -39.426237) (xy 29.927994 -39.373868) (xy 30.001878 -39.328121) (xy 30.079667 -39.289387)
			(xy 30.160699 -39.257995) (xy 30.244281 -39.234214) (xy 30.329701 -39.218246) (xy 30.41623 -39.210228)
			(xy 30.50313 -39.210228) (xy 30.589659 -39.218246) (xy 30.675079 -39.234214) (xy 30.758661 -39.257995)
			(xy 30.839693 -39.289387) (xy 30.917482 -39.328121) (xy 30.991366 -39.373868) (xy 31.060713 -39.426237)
			(xy 31.124933 -39.484781) (xy 31.183477 -39.549001) (xy 31.235846 -39.618348) (xy 31.281593 -39.692232)
			(xy 31.320327 -39.770021) (xy 31.351719 -39.851053) (xy 31.3755 -39.934635) (xy 31.391468 -40.020055)
			(xy 31.399486 -40.106584) (xy 31.399988 -40.150034) (xy 31.399486 -40.193484) (xy 34.599874 -40.193484)
			(xy 34.599874 -40.106584) (xy 34.607892 -40.020055) (xy 34.62386 -39.934635) (xy 34.647641 -39.851053)
			(xy 34.679033 -39.770021) (xy 34.717767 -39.692232) (xy 34.763514 -39.618348) (xy 34.815883 -39.549001)
			(xy 34.874427 -39.484781) (xy 34.938647 -39.426237) (xy 35.007994 -39.373868) (xy 35.081878 -39.328121)
			(xy 35.159667 -39.289387) (xy 35.240699 -39.257995) (xy 35.324281 -39.234214) (xy 35.409701 -39.218246)
			(xy 35.49623 -39.210228) (xy 35.58313 -39.210228) (xy 35.669659 -39.218246) (xy 35.755079 -39.234214)
			(xy 35.838661 -39.257995) (xy 35.919693 -39.289387) (xy 35.997482 -39.328121) (xy 36.071366 -39.373868)
			(xy 36.140713 -39.426237) (xy 36.204933 -39.484781) (xy 36.263477 -39.549001) (xy 36.315846 -39.618348)
			(xy 36.357467 -39.685569) (xy 41.612558 -39.685569) (xy 41.612558 -39.614247) (xy 41.620544 -39.543373)
			(xy 41.636414 -39.473838) (xy 41.659971 -39.406518) (xy 41.690916 -39.342259) (xy 41.728862 -39.281868)
			(xy 41.773331 -39.226106) (xy 41.823764 -39.175673) (xy 41.879526 -39.131204) (xy 41.939917 -39.093258)
			(xy 42.004176 -39.062313) (xy 42.071496 -39.038756) (xy 42.141031 -39.022886) (xy 42.211905 -39.0149)
			(xy 42.283227 -39.0149) (xy 42.354101 -39.022886) (xy 42.423636 -39.038756) (xy 42.490956 -39.062313)
			(xy 42.555215 -39.093258) (xy 42.615606 -39.131204) (xy 42.671368 -39.175673) (xy 42.721801 -39.226106)
			(xy 42.76627 -39.281868) (xy 42.804216 -39.342259) (xy 42.835161 -39.406518) (xy 42.858718 -39.473838)
			(xy 42.874588 -39.543373) (xy 42.882574 -39.614247) (xy 42.883074 -39.649908) (xy 42.882574 -39.685569)
			(xy 43.49927 -39.685569) (xy 43.49927 -39.614247) (xy 43.507256 -39.543373) (xy 43.523126 -39.473838)
			(xy 43.546683 -39.406518) (xy 43.577628 -39.342259) (xy 43.615574 -39.281868) (xy 43.660043 -39.226106)
			(xy 43.710476 -39.175673) (xy 43.766238 -39.131204) (xy 43.826629 -39.093258) (xy 43.890888 -39.062313)
			(xy 43.958208 -39.038756) (xy 44.027743 -39.022886) (xy 44.098617 -39.0149) (xy 44.169939 -39.0149)
			(xy 44.240813 -39.022886) (xy 44.310348 -39.038756) (xy 44.377668 -39.062313) (xy 44.441927 -39.093258)
			(xy 44.502318 -39.131204) (xy 44.55808 -39.175673) (xy 44.608513 -39.226106) (xy 44.652982 -39.281868)
			(xy 44.690928 -39.342259) (xy 44.721873 -39.406518) (xy 44.74543 -39.473838) (xy 44.7613 -39.543373)
			(xy 44.769286 -39.614247) (xy 44.769786 -39.649908) (xy 44.769286 -39.685569) (xy 44.7613 -39.756443)
			(xy 44.74543 -39.825978) (xy 44.721873 -39.893298) (xy 44.690928 -39.957557) (xy 44.652982 -40.017948)
			(xy 44.608513 -40.07371) (xy 44.55808 -40.124143) (xy 44.502318 -40.168612) (xy 44.441927 -40.206558)
			(xy 44.377668 -40.237503) (xy 44.310348 -40.26106) (xy 44.240813 -40.27693) (xy 44.169939 -40.284916)
			(xy 44.098617 -40.284916) (xy 44.027743 -40.27693) (xy 43.958208 -40.26106) (xy 43.890888 -40.237503)
			(xy 43.826629 -40.206558) (xy 43.766238 -40.168612) (xy 43.710476 -40.124143) (xy 43.660043 -40.07371)
			(xy 43.615574 -40.017948) (xy 43.577628 -39.957557) (xy 43.546683 -39.893298) (xy 43.523126 -39.825978)
			(xy 43.507256 -39.756443) (xy 43.49927 -39.685569) (xy 42.882574 -39.685569) (xy 42.874588 -39.756443)
			(xy 42.858718 -39.825978) (xy 42.835161 -39.893298) (xy 42.804216 -39.957557) (xy 42.76627 -40.017948)
			(xy 42.721801 -40.07371) (xy 42.671368 -40.124143) (xy 42.615606 -40.168612) (xy 42.555215 -40.206558)
			(xy 42.490956 -40.237503) (xy 42.423636 -40.26106) (xy 42.354101 -40.27693) (xy 42.283227 -40.284916)
			(xy 42.211905 -40.284916) (xy 42.141031 -40.27693) (xy 42.071496 -40.26106) (xy 42.004176 -40.237503)
			(xy 41.939917 -40.206558) (xy 41.879526 -40.168612) (xy 41.823764 -40.124143) (xy 41.773331 -40.07371)
			(xy 41.728862 -40.017948) (xy 41.690916 -39.957557) (xy 41.659971 -39.893298) (xy 41.636414 -39.825978)
			(xy 41.620544 -39.756443) (xy 41.612558 -39.685569) (xy 36.357467 -39.685569) (xy 36.361593 -39.692232)
			(xy 36.400327 -39.770021) (xy 36.431719 -39.851053) (xy 36.4555 -39.934635) (xy 36.471468 -40.020055)
			(xy 36.479486 -40.106584) (xy 36.479988 -40.150034) (xy 36.479486 -40.193484) (xy 36.471468 -40.280013)
			(xy 36.4555 -40.365433) (xy 36.431719 -40.449015) (xy 36.400327 -40.530047) (xy 36.361593 -40.607836)
			(xy 36.315846 -40.68172) (xy 36.263477 -40.751067) (xy 36.204933 -40.815287) (xy 36.140713 -40.873831)
			(xy 36.071366 -40.9262) (xy 35.997482 -40.971947) (xy 35.919693 -41.010681) (xy 35.838661 -41.042073)
			(xy 35.755079 -41.065854) (xy 35.669659 -41.081822) (xy 35.58313 -41.08984) (xy 35.49623 -41.08984)
			(xy 35.409701 -41.081822) (xy 35.324281 -41.065854) (xy 35.240699 -41.042073) (xy 35.159667 -41.010681)
			(xy 35.081878 -40.971947) (xy 35.007994 -40.9262) (xy 34.938647 -40.873831) (xy 34.874427 -40.815287)
			(xy 34.815883 -40.751067) (xy 34.763514 -40.68172) (xy 34.717767 -40.607836) (xy 34.679033 -40.530047)
			(xy 34.647641 -40.449015) (xy 34.62386 -40.365433) (xy 34.607892 -40.280013) (xy 34.599874 -40.193484)
			(xy 31.399486 -40.193484) (xy 31.391468 -40.280013) (xy 31.3755 -40.365433) (xy 31.351719 -40.449015)
			(xy 31.320327 -40.530047) (xy 31.281593 -40.607836) (xy 31.235846 -40.68172) (xy 31.183477 -40.751067)
			(xy 31.124933 -40.815287) (xy 31.060713 -40.873831) (xy 30.991366 -40.9262) (xy 30.917482 -40.971947)
			(xy 30.839693 -41.010681) (xy 30.758661 -41.042073) (xy 30.675079 -41.065854) (xy 30.589659 -41.081822)
			(xy 30.50313 -41.08984) (xy 30.41623 -41.08984) (xy 30.329701 -41.081822) (xy 30.244281 -41.065854)
			(xy 30.160699 -41.042073) (xy 30.079667 -41.010681) (xy 30.001878 -40.971947) (xy 29.927994 -40.9262)
			(xy 29.858647 -40.873831) (xy 29.794427 -40.815287) (xy 29.735883 -40.751067) (xy 29.683514 -40.68172)
			(xy 29.637767 -40.607836) (xy 29.599033 -40.530047) (xy 29.567641 -40.449015) (xy 29.54386 -40.365433)
			(xy 29.527892 -40.280013) (xy 29.519874 -40.193484) (xy 29.24048 -40.193484) (xy 29.24048 -41.595395)
			(xy 41.612558 -41.595395) (xy 41.612558 -41.524073) (xy 41.620544 -41.453199) (xy 41.636414 -41.383664)
			(xy 41.659971 -41.316344) (xy 41.690916 -41.252085) (xy 41.728862 -41.191694) (xy 41.773331 -41.135932)
			(xy 41.823764 -41.085499) (xy 41.879526 -41.04103) (xy 41.939917 -41.003084) (xy 42.004176 -40.972139)
			(xy 42.071496 -40.948582) (xy 42.141031 -40.932712) (xy 42.211905 -40.924726) (xy 42.283227 -40.924726)
			(xy 42.354101 -40.932712) (xy 42.423636 -40.948582) (xy 42.490956 -40.972139) (xy 42.555215 -41.003084)
			(xy 42.615606 -41.04103) (xy 42.671368 -41.085499) (xy 42.721801 -41.135932) (xy 42.76627 -41.191694)
			(xy 42.804216 -41.252085) (xy 42.835161 -41.316344) (xy 42.858718 -41.383664) (xy 42.874588 -41.453199)
			(xy 42.882574 -41.524073) (xy 42.883074 -41.559734) (xy 42.882574 -41.595395) (xy 43.49927 -41.595395)
			(xy 43.49927 -41.524073) (xy 43.507256 -41.453199) (xy 43.523126 -41.383664) (xy 43.546683 -41.316344)
			(xy 43.577628 -41.252085) (xy 43.615574 -41.191694) (xy 43.660043 -41.135932) (xy 43.710476 -41.085499)
			(xy 43.766238 -41.04103) (xy 43.826629 -41.003084) (xy 43.890888 -40.972139) (xy 43.958208 -40.948582)
			(xy 44.027743 -40.932712) (xy 44.098617 -40.924726) (xy 44.169939 -40.924726) (xy 44.240813 -40.932712)
			(xy 44.310348 -40.948582) (xy 44.377668 -40.972139) (xy 44.441927 -41.003084) (xy 44.502318 -41.04103)
			(xy 44.55808 -41.085499) (xy 44.608513 -41.135932) (xy 44.652982 -41.191694) (xy 44.690928 -41.252085)
			(xy 44.721873 -41.316344) (xy 44.74543 -41.383664) (xy 44.7613 -41.453199) (xy 44.769286 -41.524073)
			(xy 44.769786 -41.559734) (xy 44.769286 -41.595395) (xy 44.7613 -41.666269) (xy 44.74543 -41.735804)
			(xy 44.721873 -41.803124) (xy 44.690928 -41.867383) (xy 44.652982 -41.927774) (xy 44.608513 -41.983536)
			(xy 44.55808 -42.033969) (xy 44.502318 -42.078438) (xy 44.441927 -42.116384) (xy 44.377668 -42.147329)
			(xy 44.310348 -42.170886) (xy 44.240813 -42.186756) (xy 44.169939 -42.194742) (xy 44.098617 -42.194742)
			(xy 44.027743 -42.186756) (xy 43.958208 -42.170886) (xy 43.890888 -42.147329) (xy 43.826629 -42.116384)
			(xy 43.766238 -42.078438) (xy 43.710476 -42.033969) (xy 43.660043 -41.983536) (xy 43.615574 -41.927774)
			(xy 43.577628 -41.867383) (xy 43.546683 -41.803124) (xy 43.523126 -41.735804) (xy 43.507256 -41.666269)
			(xy 43.49927 -41.595395) (xy 42.882574 -41.595395) (xy 42.874588 -41.666269) (xy 42.858718 -41.735804)
			(xy 42.835161 -41.803124) (xy 42.804216 -41.867383) (xy 42.76627 -41.927774) (xy 42.721801 -41.983536)
			(xy 42.671368 -42.033969) (xy 42.615606 -42.078438) (xy 42.555215 -42.116384) (xy 42.490956 -42.147329)
			(xy 42.423636 -42.170886) (xy 42.354101 -42.186756) (xy 42.283227 -42.194742) (xy 42.211905 -42.194742)
			(xy 42.141031 -42.186756) (xy 42.071496 -42.170886) (xy 42.004176 -42.147329) (xy 41.939917 -42.116384)
			(xy 41.879526 -42.078438) (xy 41.823764 -42.033969) (xy 41.773331 -41.983536) (xy 41.728862 -41.927774)
			(xy 41.690916 -41.867383) (xy 41.659971 -41.803124) (xy 41.636414 -41.735804) (xy 41.620544 -41.666269)
			(xy 41.612558 -41.595395) (xy 29.24048 -41.595395) (xy 29.24048 -42.733484) (xy 29.519874 -42.733484)
			(xy 29.519874 -42.646584) (xy 29.527892 -42.560055) (xy 29.54386 -42.474635) (xy 29.567641 -42.391053)
			(xy 29.599033 -42.310021) (xy 29.637767 -42.232232) (xy 29.683514 -42.158348) (xy 29.735883 -42.089001)
			(xy 29.794427 -42.024781) (xy 29.858647 -41.966237) (xy 29.927994 -41.913868) (xy 30.001878 -41.868121)
			(xy 30.079667 -41.829387) (xy 30.160699 -41.797995) (xy 30.244281 -41.774214) (xy 30.329701 -41.758246)
			(xy 30.41623 -41.750228) (xy 30.50313 -41.750228) (xy 30.589659 -41.758246) (xy 30.675079 -41.774214)
			(xy 30.758661 -41.797995) (xy 30.839693 -41.829387) (xy 30.917482 -41.868121) (xy 30.991366 -41.913868)
			(xy 31.060713 -41.966237) (xy 31.124933 -42.024781) (xy 31.183477 -42.089001) (xy 31.235846 -42.158348)
			(xy 31.281593 -42.232232) (xy 31.320327 -42.310021) (xy 31.351719 -42.391053) (xy 31.3755 -42.474635)
			(xy 31.391468 -42.560055) (xy 31.399486 -42.646584) (xy 31.399988 -42.690034) (xy 31.399486 -42.733484)
			(xy 34.599874 -42.733484) (xy 34.599874 -42.646584) (xy 34.607892 -42.560055) (xy 34.62386 -42.474635)
			(xy 34.647641 -42.391053) (xy 34.679033 -42.310021) (xy 34.717767 -42.232232) (xy 34.763514 -42.158348)
			(xy 34.815883 -42.089001) (xy 34.874427 -42.024781) (xy 34.938647 -41.966237) (xy 35.007994 -41.913868)
			(xy 35.081878 -41.868121) (xy 35.159667 -41.829387) (xy 35.240699 -41.797995) (xy 35.324281 -41.774214)
			(xy 35.409701 -41.758246) (xy 35.49623 -41.750228) (xy 35.58313 -41.750228) (xy 35.669659 -41.758246)
			(xy 35.755079 -41.774214) (xy 35.838661 -41.797995) (xy 35.919693 -41.829387) (xy 35.997482 -41.868121)
			(xy 36.071366 -41.913868) (xy 36.140713 -41.966237) (xy 36.204933 -42.024781) (xy 36.263477 -42.089001)
			(xy 36.315846 -42.158348) (xy 36.360865 -42.231056) (xy 71.395336 -42.231056) (xy 71.395336 -41.31945)
			(xy 71.395835 -41.288042) (xy 71.403592 -41.225706) (xy 71.418969 -41.164801) (xy 71.441731 -41.106254)
			(xy 71.471533 -41.050956) (xy 71.507919 -40.999752) (xy 71.550337 -40.95342) (xy 71.598139 -40.912666)
			(xy 71.650597 -40.878111) (xy 71.706913 -40.850282) (xy 71.766228 -40.829602) (xy 71.827638 -40.816387)
			(xy 71.890209 -40.810837) (xy 71.952987 -40.813038) (xy 72.015016 -40.822956) (xy 72.07535 -40.840439)
			(xy 72.133071 -40.865222) (xy 72.1873 -40.896927) (xy 72.237209 -40.935071) (xy 72.259952 -40.956738)
			(xy 72.276599 -40.972322) (xy 72.314306 -40.997956) (xy 72.355982 -41.016446) (xy 72.40029 -41.027201)
			(xy 72.445805 -41.029874) (xy 72.491067 -41.024379) (xy 72.534621 -41.010892) (xy 72.575069 -40.989848)
			(xy 72.61111 -40.961922) (xy 72.626728 -40.945308) (xy 72.647884 -40.922528) (xy 72.694782 -40.881716)
			(xy 72.746308 -40.846928) (xy 72.801692 -40.818685) (xy 72.860108 -40.797408) (xy 72.920682 -40.783414)
			(xy 72.982511 -40.776913) (xy 73.044671 -40.778001) (xy 73.106235 -40.786663) (xy 73.166282 -40.802769)
			(xy 73.223916 -40.826078) (xy 73.278278 -40.856244) (xy 73.328554 -40.892814) (xy 73.373995 -40.935243)
			(xy 73.394316 -40.95877) (xy 73.408559 -40.97514) (xy 73.441681 -41.00317) (xy 73.479081 -41.025169)
			(xy 73.519674 -41.040497) (xy 73.56228 -41.048711) (xy 73.605662 -41.049571) (xy 73.64856 -41.043053)
			(xy 73.689729 -41.029345) (xy 73.727972 -41.008846) (xy 73.762179 -40.982151) (xy 73.777094 -40.96639)
			(xy 73.799686 -40.942207) (xy 73.850146 -40.899386) (xy 73.905737 -40.863475) (xy 73.965517 -40.835082)
			(xy 74.028477 -40.814687) (xy 74.093551 -40.802634) (xy 74.159639 -40.799128) (xy 74.225623 -40.804227)
			(xy 74.290387 -40.817846) (xy 74.352836 -40.839754) (xy 74.411914 -40.869581) (xy 74.466622 -40.906823)
			(xy 74.516035 -40.950849) (xy 74.538078 -40.975534) (xy 74.552907 -40.991866) (xy 74.587092 -41.019739)
			(xy 74.625574 -41.041294) (xy 74.667199 -41.055885) (xy 74.710717 -41.063073) (xy 74.754823 -41.062644)
			(xy 74.798193 -41.054609) (xy 74.839525 -41.039211) (xy 74.87758 -41.016911) (xy 74.911216 -40.988377)
			(xy 74.925682 -40.971724) (xy 74.945965 -40.948112) (xy 74.991299 -40.905456) (xy 75.041501 -40.868654)
			(xy 75.095821 -40.838257) (xy 75.153446 -40.814719) (xy 75.213513 -40.798392) (xy 75.275125 -40.789522)
			(xy 75.337359 -40.78824) (xy 75.399283 -40.794567) (xy 75.459972 -40.808406) (xy 75.518517 -40.829552)
			(xy 75.574043 -40.857687) (xy 75.625717 -40.892391) (xy 75.672769 -40.933144) (xy 75.714492 -40.979337)
			(xy 75.750264 -41.030279) (xy 75.779548 -41.085207) (xy 75.801907 -41.143299) (xy 75.817006 -41.203687)
			(xy 75.82462 -41.265467) (xy 75.825096 -41.29659) (xy 75.825096 -42.231056) (xy 75.824579 -42.263782)
			(xy 75.816189 -42.328693) (xy 75.799543 -42.391993) (xy 75.774915 -42.452634) (xy 75.742713 -42.509616)
			(xy 75.723496 -42.53611) (xy 75.698096 -42.569892) (xy 75.698096 -42.587164) (xy 75.682856 -42.587164)
			(xy 75.647042 -42.61739) (xy 75.621865 -42.638243) (xy 75.567133 -42.673994) (xy 75.508268 -42.702433)
			(xy 75.446243 -42.723088) (xy 75.382081 -42.735619) (xy 75.316842 -42.739819) (xy 75.251603 -42.735619)
			(xy 75.187441 -42.723088) (xy 75.125416 -42.702433) (xy 75.066551 -42.673994) (xy 75.011819 -42.638243)
			(xy 74.986642 -42.61739) (xy 74.950828 -42.587164) (xy 74.935588 -42.587164) (xy 74.935588 -42.569892)
			(xy 74.910188 -42.53611) (xy 74.893021 -42.512506) (xy 74.86361 -42.462089) (xy 74.851514 -42.435526)
			(xy 74.844457 -42.420771) (xy 74.824099 -42.395186) (xy 74.79791 -42.375611) (xy 74.767609 -42.363327)
			(xy 74.735182 -42.359141) (xy 74.702755 -42.363327) (xy 74.672454 -42.375611) (xy 74.646265 -42.395186)
			(xy 74.625907 -42.420771) (xy 74.61885 -42.435526) (xy 74.606757 -42.46209) (xy 74.577347 -42.512508)
			(xy 74.560176 -42.53611) (xy 74.534776 -42.569892) (xy 74.534776 -42.587164) (xy 74.519536 -42.587164)
			(xy 74.483722 -42.61739) (xy 74.458545 -42.638243) (xy 74.403813 -42.673994) (xy 74.344948 -42.702433)
			(xy 74.282923 -42.723088) (xy 74.218761 -42.735619) (xy 74.153522 -42.739819) (xy 74.088283 -42.735619)
			(xy 74.024121 -42.723088) (xy 73.962096 -42.702433) (xy 73.903231 -42.673994) (xy 73.848499 -42.638243)
			(xy 73.823322 -42.61739) (xy 73.787508 -42.587164) (xy 73.772268 -42.587164) (xy 73.772268 -42.569892)
			(xy 73.746868 -42.53611) (xy 73.731744 -42.515348) (xy 73.705278 -42.471322) (xy 73.694036 -42.448226)
			(xy 73.686772 -42.433983) (xy 73.66639 -42.409365) (xy 73.640528 -42.390587) (xy 73.61081 -42.378826)
			(xy 73.579101 -42.374822) (xy 73.547392 -42.378826) (xy 73.517674 -42.390587) (xy 73.491812 -42.409365)
			(xy 73.47143 -42.433983) (xy 73.464166 -42.448226) (xy 73.45295 -42.471336) (xy 73.426478 -42.515361)
			(xy 73.411334 -42.53611) (xy 73.386188 -42.569892) (xy 73.386188 -42.587164) (xy 73.370694 -42.587164)
			(xy 73.33488 -42.61739) (xy 73.309703 -42.638243) (xy 73.254971 -42.673994) (xy 73.196106 -42.702433)
			(xy 73.134081 -42.723088) (xy 73.069919 -42.735619) (xy 73.00468 -42.739819) (xy 72.939441 -42.735619)
			(xy 72.875279 -42.723088) (xy 72.813254 -42.702433) (xy 72.754389 -42.673994) (xy 72.699657 -42.638243)
			(xy 72.67448 -42.61739) (xy 72.638666 -42.587164) (xy 72.623172 -42.587164) (xy 72.623172 -42.569892)
			(xy 72.598026 -42.53611) (xy 72.58891 -42.523803) (xy 72.572008 -42.498258) (xy 72.564244 -42.485056)
			(xy 72.55545 -42.47091) (xy 72.531906 -42.447367) (xy 72.503071 -42.430719) (xy 72.47091 -42.422102)
			(xy 72.437614 -42.422102) (xy 72.405453 -42.430719) (xy 72.376618 -42.447367) (xy 72.353074 -42.47091)
			(xy 72.34428 -42.485056) (xy 72.336513 -42.498256) (xy 72.31961 -42.5238) (xy 72.310498 -42.53611)
			(xy 72.285352 -42.569892) (xy 72.285352 -42.587164) (xy 72.269858 -42.587164) (xy 72.234044 -42.61739)
			(xy 72.208867 -42.638243) (xy 72.154135 -42.673994) (xy 72.09527 -42.702433) (xy 72.033245 -42.723088)
			(xy 71.969083 -42.735619) (xy 71.903844 -42.739819) (xy 71.838605 -42.735619) (xy 71.774443 -42.723088)
			(xy 71.712418 -42.702433) (xy 71.653553 -42.673994) (xy 71.598821 -42.638243) (xy 71.573644 -42.61739)
			(xy 71.53783 -42.587164) (xy 71.522336 -42.587164) (xy 71.522336 -42.569892) (xy 71.49719 -42.53611)
			(xy 71.477949 -42.509622) (xy 71.445683 -42.452655) (xy 71.420996 -42.392018) (xy 71.404297 -42.328714)
			(xy 71.395861 -42.263791) (xy 71.395336 -42.231056) (xy 36.360865 -42.231056) (xy 36.361593 -42.232232)
			(xy 36.400327 -42.310021) (xy 36.431719 -42.391053) (xy 36.4555 -42.474635) (xy 36.471468 -42.560055)
			(xy 36.479486 -42.646584) (xy 36.479988 -42.690034) (xy 36.479486 -42.733484) (xy 36.471468 -42.820013)
			(xy 36.4555 -42.905433) (xy 36.431719 -42.989015) (xy 36.400327 -43.070047) (xy 36.361593 -43.147836)
			(xy 36.315846 -43.22172) (xy 36.263477 -43.291067) (xy 36.204933 -43.355287) (xy 36.140713 -43.413831)
			(xy 36.071366 -43.4662) (xy 35.997482 -43.511947) (xy 35.919693 -43.550681) (xy 35.838661 -43.582073)
			(xy 35.755079 -43.605854) (xy 35.669659 -43.621822) (xy 35.58313 -43.62984) (xy 35.49623 -43.62984)
			(xy 35.409701 -43.621822) (xy 35.324281 -43.605854) (xy 35.240699 -43.582073) (xy 35.159667 -43.550681)
			(xy 35.081878 -43.511947) (xy 35.007994 -43.4662) (xy 34.938647 -43.413831) (xy 34.874427 -43.355287)
			(xy 34.815883 -43.291067) (xy 34.763514 -43.22172) (xy 34.717767 -43.147836) (xy 34.679033 -43.070047)
			(xy 34.647641 -42.989015) (xy 34.62386 -42.905433) (xy 34.607892 -42.820013) (xy 34.599874 -42.733484)
			(xy 31.399486 -42.733484) (xy 31.391468 -42.820013) (xy 31.3755 -42.905433) (xy 31.351719 -42.989015)
			(xy 31.320327 -43.070047) (xy 31.281593 -43.147836) (xy 31.235846 -43.22172) (xy 31.183477 -43.291067)
			(xy 31.124933 -43.355287) (xy 31.060713 -43.413831) (xy 30.991366 -43.4662) (xy 30.917482 -43.511947)
			(xy 30.839693 -43.550681) (xy 30.758661 -43.582073) (xy 30.675079 -43.605854) (xy 30.589659 -43.621822)
			(xy 30.50313 -43.62984) (xy 30.41623 -43.62984) (xy 30.329701 -43.621822) (xy 30.244281 -43.605854)
			(xy 30.160699 -43.582073) (xy 30.079667 -43.550681) (xy 30.001878 -43.511947) (xy 29.927994 -43.4662)
			(xy 29.858647 -43.413831) (xy 29.794427 -43.355287) (xy 29.735883 -43.291067) (xy 29.683514 -43.22172)
			(xy 29.637767 -43.147836) (xy 29.599033 -43.070047) (xy 29.567641 -42.989015) (xy 29.54386 -42.905433)
			(xy 29.527892 -42.820013) (xy 29.519874 -42.733484) (xy 29.24048 -42.733484) (xy 29.24048 -45.273484)
			(xy 29.519874 -45.273484) (xy 29.519874 -45.186584) (xy 29.527892 -45.100055) (xy 29.54386 -45.014635)
			(xy 29.567641 -44.931053) (xy 29.599033 -44.850021) (xy 29.637767 -44.772232) (xy 29.683514 -44.698348)
			(xy 29.735883 -44.629001) (xy 29.794427 -44.564781) (xy 29.858647 -44.506237) (xy 29.927994 -44.453868)
			(xy 30.001878 -44.408121) (xy 30.079667 -44.369387) (xy 30.160699 -44.337995) (xy 30.244281 -44.314214)
			(xy 30.329701 -44.298246) (xy 30.41623 -44.290228) (xy 30.50313 -44.290228) (xy 30.589659 -44.298246)
			(xy 30.675079 -44.314214) (xy 30.758661 -44.337995) (xy 30.839693 -44.369387) (xy 30.917482 -44.408121)
			(xy 30.991366 -44.453868) (xy 31.060713 -44.506237) (xy 31.124933 -44.564781) (xy 31.183477 -44.629001)
			(xy 31.235846 -44.698348) (xy 31.281593 -44.772232) (xy 31.320327 -44.850021) (xy 31.351719 -44.931053)
			(xy 31.3755 -45.014635) (xy 31.391468 -45.100055) (xy 31.399486 -45.186584) (xy 31.399988 -45.230034)
			(xy 31.399486 -45.273484) (xy 34.599874 -45.273484) (xy 34.599874 -45.186584) (xy 34.607892 -45.100055)
			(xy 34.62386 -45.014635) (xy 34.647641 -44.931053) (xy 34.679033 -44.850021) (xy 34.717767 -44.772232)
			(xy 34.763514 -44.698348) (xy 34.815883 -44.629001) (xy 34.874427 -44.564781) (xy 34.938647 -44.506237)
			(xy 35.007994 -44.453868) (xy 35.081878 -44.408121) (xy 35.159667 -44.369387) (xy 35.240699 -44.337995)
			(xy 35.324281 -44.314214) (xy 35.409701 -44.298246) (xy 35.49623 -44.290228) (xy 35.58313 -44.290228)
			(xy 35.669659 -44.298246) (xy 35.755079 -44.314214) (xy 35.838661 -44.337995) (xy 35.919693 -44.369387)
			(xy 35.997482 -44.408121) (xy 36.071366 -44.453868) (xy 36.140713 -44.506237) (xy 36.204933 -44.564781)
			(xy 36.263477 -44.629001) (xy 36.315846 -44.698348) (xy 36.361593 -44.772232) (xy 36.400327 -44.850021)
			(xy 36.431719 -44.931053) (xy 36.4555 -45.014635) (xy 36.471468 -45.100055) (xy 36.479486 -45.186584)
			(xy 36.479988 -45.230034) (xy 36.479486 -45.273484) (xy 36.471468 -45.360013) (xy 36.4555 -45.445433)
			(xy 36.431719 -45.529015) (xy 36.400327 -45.610047) (xy 36.361593 -45.687836) (xy 36.315846 -45.76172)
			(xy 36.263477 -45.831067) (xy 36.204933 -45.895287) (xy 36.140713 -45.953831) (xy 36.071366 -46.0062)
			(xy 35.997482 -46.051947) (xy 35.919693 -46.090681) (xy 35.838661 -46.122073) (xy 35.755079 -46.145854)
			(xy 35.669659 -46.161822) (xy 35.58313 -46.16984) (xy 35.49623 -46.16984) (xy 35.409701 -46.161822)
			(xy 35.324281 -46.145854) (xy 35.240699 -46.122073) (xy 35.159667 -46.090681) (xy 35.081878 -46.051947)
			(xy 35.007994 -46.0062) (xy 34.938647 -45.953831) (xy 34.874427 -45.895287) (xy 34.815883 -45.831067)
			(xy 34.763514 -45.76172) (xy 34.717767 -45.687836) (xy 34.679033 -45.610047) (xy 34.647641 -45.529015)
			(xy 34.62386 -45.445433) (xy 34.607892 -45.360013) (xy 34.599874 -45.273484) (xy 31.399486 -45.273484)
			(xy 31.391468 -45.360013) (xy 31.3755 -45.445433) (xy 31.351719 -45.529015) (xy 31.320327 -45.610047)
			(xy 31.281593 -45.687836) (xy 31.235846 -45.76172) (xy 31.183477 -45.831067) (xy 31.124933 -45.895287)
			(xy 31.060713 -45.953831) (xy 30.991366 -46.0062) (xy 30.917482 -46.051947) (xy 30.839693 -46.090681)
			(xy 30.758661 -46.122073) (xy 30.675079 -46.145854) (xy 30.589659 -46.161822) (xy 30.50313 -46.16984)
			(xy 30.41623 -46.16984) (xy 30.329701 -46.161822) (xy 30.244281 -46.145854) (xy 30.160699 -46.122073)
			(xy 30.079667 -46.090681) (xy 30.001878 -46.051947) (xy 29.927994 -46.0062) (xy 29.858647 -45.953831)
			(xy 29.794427 -45.895287) (xy 29.735883 -45.831067) (xy 29.683514 -45.76172) (xy 29.637767 -45.687836)
			(xy 29.599033 -45.610047) (xy 29.567641 -45.529015) (xy 29.54386 -45.445433) (xy 29.527892 -45.360013)
			(xy 29.519874 -45.273484) (xy 29.24048 -45.273484) (xy 29.24048 -47.813484) (xy 29.519874 -47.813484)
			(xy 29.519874 -47.726584) (xy 29.527892 -47.640055) (xy 29.54386 -47.554635) (xy 29.567641 -47.471053)
			(xy 29.599033 -47.390021) (xy 29.637767 -47.312232) (xy 29.683514 -47.238348) (xy 29.735883 -47.169001)
			(xy 29.794427 -47.104781) (xy 29.858647 -47.046237) (xy 29.927994 -46.993868) (xy 30.001878 -46.948121)
			(xy 30.079667 -46.909387) (xy 30.160699 -46.877995) (xy 30.244281 -46.854214) (xy 30.329701 -46.838246)
			(xy 30.41623 -46.830228) (xy 30.50313 -46.830228) (xy 30.589659 -46.838246) (xy 30.675079 -46.854214)
			(xy 30.758661 -46.877995) (xy 30.839693 -46.909387) (xy 30.917482 -46.948121) (xy 30.991366 -46.993868)
			(xy 31.060713 -47.046237) (xy 31.124933 -47.104781) (xy 31.183477 -47.169001) (xy 31.235846 -47.238348)
			(xy 31.281593 -47.312232) (xy 31.320327 -47.390021) (xy 31.351719 -47.471053) (xy 31.3755 -47.554635)
			(xy 31.391468 -47.640055) (xy 31.399486 -47.726584) (xy 31.399988 -47.770034) (xy 31.399486 -47.813484)
			(xy 34.599874 -47.813484) (xy 34.599874 -47.726584) (xy 34.607892 -47.640055) (xy 34.62386 -47.554635)
			(xy 34.647641 -47.471053) (xy 34.679033 -47.390021) (xy 34.717767 -47.312232) (xy 34.763514 -47.238348)
			(xy 34.815883 -47.169001) (xy 34.874427 -47.104781) (xy 34.938647 -47.046237) (xy 35.007994 -46.993868)
			(xy 35.081878 -46.948121) (xy 35.159667 -46.909387) (xy 35.240699 -46.877995) (xy 35.324281 -46.854214)
			(xy 35.409701 -46.838246) (xy 35.49623 -46.830228) (xy 35.58313 -46.830228) (xy 35.669659 -46.838246)
			(xy 35.755079 -46.854214) (xy 35.838661 -46.877995) (xy 35.919693 -46.909387) (xy 35.997482 -46.948121)
			(xy 36.071366 -46.993868) (xy 36.140713 -47.046237) (xy 36.204933 -47.104781) (xy 36.263477 -47.169001)
			(xy 36.315846 -47.238348) (xy 36.361593 -47.312232) (xy 36.400327 -47.390021) (xy 36.431719 -47.471053)
			(xy 36.4555 -47.554635) (xy 36.471468 -47.640055) (xy 36.479486 -47.726584) (xy 36.479988 -47.770034)
			(xy 36.479486 -47.813484) (xy 36.471468 -47.900013) (xy 36.4555 -47.985433) (xy 36.431719 -48.069015)
			(xy 36.400327 -48.150047) (xy 36.361593 -48.227836) (xy 36.315846 -48.30172) (xy 36.263477 -48.371067)
			(xy 36.204933 -48.435287) (xy 36.140713 -48.493831) (xy 36.071366 -48.5462) (xy 35.997482 -48.591947)
			(xy 35.919693 -48.630681) (xy 35.838661 -48.662073) (xy 35.755079 -48.685854) (xy 35.669659 -48.701822)
			(xy 35.58313 -48.70984) (xy 35.49623 -48.70984) (xy 35.409701 -48.701822) (xy 35.324281 -48.685854)
			(xy 35.240699 -48.662073) (xy 35.159667 -48.630681) (xy 35.081878 -48.591947) (xy 35.007994 -48.5462)
			(xy 34.938647 -48.493831) (xy 34.874427 -48.435287) (xy 34.815883 -48.371067) (xy 34.763514 -48.30172)
			(xy 34.717767 -48.227836) (xy 34.679033 -48.150047) (xy 34.647641 -48.069015) (xy 34.62386 -47.985433)
			(xy 34.607892 -47.900013) (xy 34.599874 -47.813484) (xy 31.399486 -47.813484) (xy 31.391468 -47.900013)
			(xy 31.3755 -47.985433) (xy 31.351719 -48.069015) (xy 31.320327 -48.150047) (xy 31.281593 -48.227836)
			(xy 31.235846 -48.30172) (xy 31.183477 -48.371067) (xy 31.124933 -48.435287) (xy 31.060713 -48.493831)
			(xy 30.991366 -48.5462) (xy 30.917482 -48.591947) (xy 30.839693 -48.630681) (xy 30.758661 -48.662073)
			(xy 30.675079 -48.685854) (xy 30.589659 -48.701822) (xy 30.50313 -48.70984) (xy 30.41623 -48.70984)
			(xy 30.329701 -48.701822) (xy 30.244281 -48.685854) (xy 30.160699 -48.662073) (xy 30.079667 -48.630681)
			(xy 30.001878 -48.591947) (xy 29.927994 -48.5462) (xy 29.858647 -48.493831) (xy 29.794427 -48.435287)
			(xy 29.735883 -48.371067) (xy 29.683514 -48.30172) (xy 29.637767 -48.227836) (xy 29.599033 -48.150047)
			(xy 29.567641 -48.069015) (xy 29.54386 -47.985433) (xy 29.527892 -47.900013) (xy 29.519874 -47.813484)
			(xy 29.24048 -47.813484) (xy 29.24048 -50.353484) (xy 29.519874 -50.353484) (xy 29.519874 -50.266584)
			(xy 29.527892 -50.180055) (xy 29.54386 -50.094635) (xy 29.567641 -50.011053) (xy 29.599033 -49.930021)
			(xy 29.637767 -49.852232) (xy 29.683514 -49.778348) (xy 29.735883 -49.709001) (xy 29.794427 -49.644781)
			(xy 29.858647 -49.586237) (xy 29.927994 -49.533868) (xy 30.001878 -49.488121) (xy 30.079667 -49.449387)
			(xy 30.160699 -49.417995) (xy 30.244281 -49.394214) (xy 30.329701 -49.378246) (xy 30.41623 -49.370228)
			(xy 30.50313 -49.370228) (xy 30.589659 -49.378246) (xy 30.675079 -49.394214) (xy 30.758661 -49.417995)
			(xy 30.839693 -49.449387) (xy 30.917482 -49.488121) (xy 30.991366 -49.533868) (xy 31.060713 -49.586237)
			(xy 31.124933 -49.644781) (xy 31.183477 -49.709001) (xy 31.235846 -49.778348) (xy 31.281593 -49.852232)
			(xy 31.320327 -49.930021) (xy 31.351719 -50.011053) (xy 31.3755 -50.094635) (xy 31.391468 -50.180055)
			(xy 31.399486 -50.266584) (xy 31.399988 -50.310034) (xy 31.399486 -50.353484) (xy 34.599874 -50.353484)
			(xy 34.599874 -50.266584) (xy 34.607892 -50.180055) (xy 34.62386 -50.094635) (xy 34.647641 -50.011053)
			(xy 34.679033 -49.930021) (xy 34.717767 -49.852232) (xy 34.763514 -49.778348) (xy 34.815883 -49.709001)
			(xy 34.874427 -49.644781) (xy 34.938647 -49.586237) (xy 35.007994 -49.533868) (xy 35.081878 -49.488121)
			(xy 35.159667 -49.449387) (xy 35.240699 -49.417995) (xy 35.324281 -49.394214) (xy 35.409701 -49.378246)
			(xy 35.49623 -49.370228) (xy 35.58313 -49.370228) (xy 35.669659 -49.378246) (xy 35.755079 -49.394214)
			(xy 35.838661 -49.417995) (xy 35.919693 -49.449387) (xy 35.997482 -49.488121) (xy 36.071366 -49.533868)
			(xy 36.140713 -49.586237) (xy 36.204933 -49.644781) (xy 36.263477 -49.709001) (xy 36.315846 -49.778348)
			(xy 36.361593 -49.852232) (xy 36.400327 -49.930021) (xy 36.431719 -50.011053) (xy 36.4555 -50.094635)
			(xy 36.471468 -50.180055) (xy 36.479486 -50.266584) (xy 36.479988 -50.310034) (xy 36.479486 -50.353484)
			(xy 36.471468 -50.440013) (xy 36.4555 -50.525433) (xy 36.431719 -50.609015) (xy 36.400327 -50.690047)
			(xy 36.361593 -50.767836) (xy 36.315846 -50.84172) (xy 36.263477 -50.911067) (xy 36.204933 -50.975287)
			(xy 36.140713 -51.033831) (xy 36.071366 -51.0862) (xy 35.997482 -51.131947) (xy 35.919693 -51.170681)
			(xy 35.838661 -51.202073) (xy 35.755079 -51.225854) (xy 35.669659 -51.241822) (xy 35.58313 -51.24984)
			(xy 35.49623 -51.24984) (xy 35.409701 -51.241822) (xy 35.324281 -51.225854) (xy 35.240699 -51.202073)
			(xy 35.159667 -51.170681) (xy 35.081878 -51.131947) (xy 35.007994 -51.0862) (xy 34.938647 -51.033831)
			(xy 34.874427 -50.975287) (xy 34.815883 -50.911067) (xy 34.763514 -50.84172) (xy 34.717767 -50.767836)
			(xy 34.679033 -50.690047) (xy 34.647641 -50.609015) (xy 34.62386 -50.525433) (xy 34.607892 -50.440013)
			(xy 34.599874 -50.353484) (xy 31.399486 -50.353484) (xy 31.391468 -50.440013) (xy 31.3755 -50.525433)
			(xy 31.351719 -50.609015) (xy 31.320327 -50.690047) (xy 31.281593 -50.767836) (xy 31.235846 -50.84172)
			(xy 31.183477 -50.911067) (xy 31.124933 -50.975287) (xy 31.060713 -51.033831) (xy 30.991366 -51.0862)
			(xy 30.917482 -51.131947) (xy 30.839693 -51.170681) (xy 30.758661 -51.202073) (xy 30.675079 -51.225854)
			(xy 30.589659 -51.241822) (xy 30.50313 -51.24984) (xy 30.41623 -51.24984) (xy 30.329701 -51.241822)
			(xy 30.244281 -51.225854) (xy 30.160699 -51.202073) (xy 30.079667 -51.170681) (xy 30.001878 -51.131947)
			(xy 29.927994 -51.0862) (xy 29.858647 -51.033831) (xy 29.794427 -50.975287) (xy 29.735883 -50.911067)
			(xy 29.683514 -50.84172) (xy 29.637767 -50.767836) (xy 29.599033 -50.690047) (xy 29.567641 -50.609015)
			(xy 29.54386 -50.525433) (xy 29.527892 -50.440013) (xy 29.519874 -50.353484) (xy 29.24048 -50.353484)
			(xy 29.24048 -51.36007) (xy 39.818063 -51.36007) (xy 39.82207 -51.244046) (xy 39.834072 -51.128574)
			(xy 39.854012 -51.014206) (xy 39.881795 -50.901486) (xy 39.917289 -50.790952) (xy 39.960324 -50.683129)
			(xy 40.010695 -50.578532) (xy 40.068162 -50.47766) (xy 40.132452 -50.380993) (xy 40.203257 -50.288992)
			(xy 40.280241 -50.202095) (xy 40.363037 -50.120716) (xy 40.45125 -50.045243) (xy 40.54446 -49.976036)
			(xy 40.642223 -49.913424) (xy 40.744072 -49.857707) (xy 40.849522 -49.809149) (xy 40.958071 -49.767981)
			(xy 41.069202 -49.734401) (xy 41.182385 -49.708568) (xy 41.29708 -49.690605) (xy 41.412742 -49.680597)
			(xy 41.528818 -49.678594) (xy 41.644756 -49.684603) (xy 41.760003 -49.698596) (xy 41.874009 -49.720507)
			(xy 41.986233 -49.750232) (xy 42.096139 -49.787628) (xy 42.203202 -49.832517) (xy 42.306914 -49.884686)
			(xy 42.406779 -49.943886) (xy 42.502322 -50.009835) (xy 42.502604 -50.01006) (xy 43.327577 -50.01006)
			(xy 43.331612 -49.934356) (xy 43.343671 -49.859511) (xy 43.363617 -49.78637) (xy 43.391224 -49.715765)
			(xy 43.42618 -49.648494) (xy 43.468088 -49.585319) (xy 43.516474 -49.526957) (xy 43.57079 -49.474069)
			(xy 43.630419 -49.427254) (xy 43.694687 -49.387042) (xy 43.762864 -49.35389) (xy 43.83418 -49.328172)
			(xy 43.907825 -49.31018) (xy 43.982965 -49.300118) (xy 44.058749 -49.298099) (xy 44.134319 -49.304148)
			(xy 44.208817 -49.318195) (xy 44.2814 -49.340081) (xy 44.351246 -49.369558) (xy 44.417563 -49.406293)
			(xy 44.479599 -49.449868) (xy 44.536652 -49.49979) (xy 44.588076 -49.555494) (xy 44.633287 -49.616349)
			(xy 44.671774 -49.681664) (xy 44.7031 -49.7507) (xy 44.72691 -49.822675) (xy 44.742935 -49.896773)
			(xy 44.750994 -49.972154) (xy 44.751498 -50.01006) (xy 45.867577 -50.01006) (xy 45.871612 -49.934356)
			(xy 45.883671 -49.859511) (xy 45.903617 -49.78637) (xy 45.931224 -49.715765) (xy 45.96618 -49.648494)
			(xy 46.008088 -49.585319) (xy 46.056474 -49.526957) (xy 46.11079 -49.474069) (xy 46.170419 -49.427254)
			(xy 46.234687 -49.387042) (xy 46.302864 -49.35389) (xy 46.37418 -49.328172) (xy 46.447825 -49.31018)
			(xy 46.522965 -49.300118) (xy 46.598749 -49.298099) (xy 46.674319 -49.304148) (xy 46.748817 -49.318195)
			(xy 46.8214 -49.340081) (xy 46.891246 -49.369558) (xy 46.957563 -49.406293) (xy 47.019599 -49.449868)
			(xy 47.076652 -49.49979) (xy 47.128076 -49.555494) (xy 47.173287 -49.616349) (xy 47.211774 -49.681664)
			(xy 47.2431 -49.7507) (xy 47.26691 -49.822675) (xy 47.282935 -49.896773) (xy 47.290994 -49.972154)
			(xy 47.291498 -50.01006) (xy 48.407577 -50.01006) (xy 48.411612 -49.934356) (xy 48.423671 -49.859511)
			(xy 48.443617 -49.78637) (xy 48.471224 -49.715765) (xy 48.50618 -49.648494) (xy 48.548088 -49.585319)
			(xy 48.596474 -49.526957) (xy 48.65079 -49.474069) (xy 48.710419 -49.427254) (xy 48.774687 -49.387042)
			(xy 48.842864 -49.35389) (xy 48.91418 -49.328172) (xy 48.987825 -49.31018) (xy 49.062965 -49.300118)
			(xy 49.138749 -49.298099) (xy 49.214319 -49.304148) (xy 49.288817 -49.318195) (xy 49.3614 -49.340081)
			(xy 49.431246 -49.369558) (xy 49.497563 -49.406293) (xy 49.559599 -49.449868) (xy 49.616652 -49.49979)
			(xy 49.668076 -49.555494) (xy 49.713287 -49.616349) (xy 49.751774 -49.681664) (xy 49.7831 -49.7507)
			(xy 49.80691 -49.822675) (xy 49.822935 -49.896773) (xy 49.830994 -49.972154) (xy 49.831498 -50.01006)
			(xy 50.947577 -50.01006) (xy 50.951612 -49.934356) (xy 50.963671 -49.859511) (xy 50.983617 -49.78637)
			(xy 51.011224 -49.715765) (xy 51.04618 -49.648494) (xy 51.088088 -49.585319) (xy 51.136474 -49.526957)
			(xy 51.19079 -49.474069) (xy 51.250419 -49.427254) (xy 51.314687 -49.387042) (xy 51.382864 -49.35389)
			(xy 51.45418 -49.328172) (xy 51.527825 -49.31018) (xy 51.602965 -49.300118) (xy 51.678749 -49.298099)
			(xy 51.754319 -49.304148) (xy 51.828817 -49.318195) (xy 51.9014 -49.340081) (xy 51.971246 -49.369558)
			(xy 52.037563 -49.406293) (xy 52.099599 -49.449868) (xy 52.156652 -49.49979) (xy 52.208076 -49.555494)
			(xy 52.253287 -49.616349) (xy 52.291774 -49.681664) (xy 52.3231 -49.7507) (xy 52.34691 -49.822675)
			(xy 52.362935 -49.896773) (xy 52.370994 -49.972154) (xy 52.371498 -50.01006) (xy 53.487577 -50.01006)
			(xy 53.491612 -49.934356) (xy 53.503671 -49.859511) (xy 53.523617 -49.78637) (xy 53.551224 -49.715765)
			(xy 53.58618 -49.648494) (xy 53.628088 -49.585319) (xy 53.676474 -49.526957) (xy 53.73079 -49.474069)
			(xy 53.790419 -49.427254) (xy 53.854687 -49.387042) (xy 53.922864 -49.35389) (xy 53.99418 -49.328172)
			(xy 54.067825 -49.31018) (xy 54.142965 -49.300118) (xy 54.218749 -49.298099) (xy 54.294319 -49.304148)
			(xy 54.368817 -49.318195) (xy 54.4414 -49.340081) (xy 54.511246 -49.369558) (xy 54.577563 -49.406293)
			(xy 54.639599 -49.449868) (xy 54.696652 -49.49979) (xy 54.748076 -49.555494) (xy 54.793287 -49.616349)
			(xy 54.831774 -49.681664) (xy 54.8631 -49.7507) (xy 54.88691 -49.822675) (xy 54.902935 -49.896773)
			(xy 54.910994 -49.972154) (xy 54.911498 -50.01006) (xy 56.027577 -50.01006) (xy 56.031612 -49.934356)
			(xy 56.043671 -49.859511) (xy 56.063617 -49.78637) (xy 56.091224 -49.715765) (xy 56.12618 -49.648494)
			(xy 56.168088 -49.585319) (xy 56.216474 -49.526957) (xy 56.27079 -49.474069) (xy 56.330419 -49.427254)
			(xy 56.394687 -49.387042) (xy 56.462864 -49.35389) (xy 56.53418 -49.328172) (xy 56.607825 -49.31018)
			(xy 56.682965 -49.300118) (xy 56.758749 -49.298099) (xy 56.834319 -49.304148) (xy 56.908817 -49.318195)
			(xy 56.9814 -49.340081) (xy 57.051246 -49.369558) (xy 57.117563 -49.406293) (xy 57.179599 -49.449868)
			(xy 57.236652 -49.49979) (xy 57.288076 -49.555494) (xy 57.333287 -49.616349) (xy 57.371774 -49.681664)
			(xy 57.4031 -49.7507) (xy 57.42691 -49.822675) (xy 57.442935 -49.896773) (xy 57.450994 -49.972154)
			(xy 57.451498 -50.01006) (xy 58.567577 -50.01006) (xy 58.571612 -49.934356) (xy 58.583671 -49.859511)
			(xy 58.603617 -49.78637) (xy 58.631224 -49.715765) (xy 58.66618 -49.648494) (xy 58.708088 -49.585319)
			(xy 58.756474 -49.526957) (xy 58.81079 -49.474069) (xy 58.870419 -49.427254) (xy 58.934687 -49.387042)
			(xy 59.002864 -49.35389) (xy 59.07418 -49.328172) (xy 59.147825 -49.31018) (xy 59.222965 -49.300118)
			(xy 59.298749 -49.298099) (xy 59.374319 -49.304148) (xy 59.448817 -49.318195) (xy 59.5214 -49.340081)
			(xy 59.591246 -49.369558) (xy 59.657563 -49.406293) (xy 59.719599 -49.449868) (xy 59.776652 -49.49979)
			(xy 59.828076 -49.555494) (xy 59.873287 -49.616349) (xy 59.911774 -49.681664) (xy 59.9431 -49.7507)
			(xy 59.96691 -49.822675) (xy 59.982935 -49.896773) (xy 59.990994 -49.972154) (xy 59.991498 -50.01006)
			(xy 61.107577 -50.01006) (xy 61.111612 -49.934356) (xy 61.123671 -49.859511) (xy 61.143617 -49.78637)
			(xy 61.171224 -49.715765) (xy 61.20618 -49.648494) (xy 61.248088 -49.585319) (xy 61.296474 -49.526957)
			(xy 61.35079 -49.474069) (xy 61.410419 -49.427254) (xy 61.474687 -49.387042) (xy 61.542864 -49.35389)
			(xy 61.61418 -49.328172) (xy 61.687825 -49.31018) (xy 61.762965 -49.300118) (xy 61.838749 -49.298099)
			(xy 61.914319 -49.304148) (xy 61.988817 -49.318195) (xy 62.0614 -49.340081) (xy 62.131246 -49.369558)
			(xy 62.197563 -49.406293) (xy 62.259599 -49.449868) (xy 62.265544 -49.45507) (xy 86.197697 -49.45507)
			(xy 86.201732 -49.379366) (xy 86.213791 -49.304521) (xy 86.233737 -49.23138) (xy 86.261344 -49.160775)
			(xy 86.2963 -49.093504) (xy 86.338208 -49.030329) (xy 86.386594 -48.971967) (xy 86.44091 -48.919079)
			(xy 86.500539 -48.872264) (xy 86.564807 -48.832052) (xy 86.632984 -48.7989) (xy 86.7043 -48.773182)
			(xy 86.777945 -48.75519) (xy 86.853085 -48.745128) (xy 86.928869 -48.743109) (xy 87.004439 -48.749158)
			(xy 87.078937 -48.763205) (xy 87.15152 -48.785091) (xy 87.221366 -48.814568) (xy 87.287683 -48.851303)
			(xy 87.349719 -48.894878) (xy 87.406772 -48.9448) (xy 87.458196 -49.000504) (xy 87.503407 -49.061359)
			(xy 87.541894 -49.126674) (xy 87.57322 -49.19571) (xy 87.59703 -49.267685) (xy 87.613055 -49.341783)
			(xy 87.621114 -49.417164) (xy 87.621618 -49.45507) (xy 88.737697 -49.45507) (xy 88.741732 -49.379366)
			(xy 88.753791 -49.304521) (xy 88.773737 -49.23138) (xy 88.801344 -49.160775) (xy 88.8363 -49.093504)
			(xy 88.878208 -49.030329) (xy 88.926594 -48.971967) (xy 88.98091 -48.919079) (xy 89.040539 -48.872264)
			(xy 89.104807 -48.832052) (xy 89.172984 -48.7989) (xy 89.2443 -48.773182) (xy 89.317945 -48.75519)
			(xy 89.393085 -48.745128) (xy 89.468869 -48.743109) (xy 89.544439 -48.749158) (xy 89.618937 -48.763205)
			(xy 89.69152 -48.785091) (xy 89.761366 -48.814568) (xy 89.827683 -48.851303) (xy 89.889719 -48.894878)
			(xy 89.946772 -48.9448) (xy 89.998196 -49.000504) (xy 90.043407 -49.061359) (xy 90.081894 -49.126674)
			(xy 90.11322 -49.19571) (xy 90.13703 -49.267685) (xy 90.153055 -49.341783) (xy 90.161114 -49.417164)
			(xy 90.161618 -49.45507) (xy 91.277697 -49.45507) (xy 91.281732 -49.379366) (xy 91.293791 -49.304521)
			(xy 91.313737 -49.23138) (xy 91.341344 -49.160775) (xy 91.3763 -49.093504) (xy 91.418208 -49.030329)
			(xy 91.466594 -48.971967) (xy 91.52091 -48.919079) (xy 91.580539 -48.872264) (xy 91.644807 -48.832052)
			(xy 91.712984 -48.7989) (xy 91.7843 -48.773182) (xy 91.857945 -48.75519) (xy 91.933085 -48.745128)
			(xy 92.008869 -48.743109) (xy 92.084439 -48.749158) (xy 92.158937 -48.763205) (xy 92.23152 -48.785091)
			(xy 92.301366 -48.814568) (xy 92.367683 -48.851303) (xy 92.429719 -48.894878) (xy 92.486772 -48.9448)
			(xy 92.538196 -49.000504) (xy 92.583407 -49.061359) (xy 92.621894 -49.126674) (xy 92.65322 -49.19571)
			(xy 92.67703 -49.267685) (xy 92.693055 -49.341783) (xy 92.701114 -49.417164) (xy 92.701618 -49.45507)
			(xy 92.701114 -49.492976) (xy 92.693055 -49.568357) (xy 92.67703 -49.642455) (xy 92.65322 -49.71443)
			(xy 92.621894 -49.783466) (xy 92.583407 -49.848781) (xy 92.538196 -49.909636) (xy 92.486772 -49.96534)
			(xy 92.429719 -50.015262) (xy 92.367683 -50.058837) (xy 92.301366 -50.095572) (xy 92.23152 -50.125049)
			(xy 92.158937 -50.146935) (xy 92.084439 -50.160982) (xy 92.008869 -50.167031) (xy 91.933085 -50.165012)
			(xy 91.857945 -50.15495) (xy 91.7843 -50.136958) (xy 91.712984 -50.11124) (xy 91.644807 -50.078088)
			(xy 91.580539 -50.037876) (xy 91.52091 -49.991061) (xy 91.466594 -49.938173) (xy 91.418208 -49.879811)
			(xy 91.3763 -49.816636) (xy 91.341344 -49.749365) (xy 91.313737 -49.67876) (xy 91.293791 -49.605619)
			(xy 91.281732 -49.530774) (xy 91.277697 -49.45507) (xy 90.161618 -49.45507) (xy 90.161114 -49.492976)
			(xy 90.153055 -49.568357) (xy 90.13703 -49.642455) (xy 90.11322 -49.71443) (xy 90.081894 -49.783466)
			(xy 90.043407 -49.848781) (xy 89.998196 -49.909636) (xy 89.946772 -49.96534) (xy 89.889719 -50.015262)
			(xy 89.827683 -50.058837) (xy 89.761366 -50.095572) (xy 89.69152 -50.125049) (xy 89.618937 -50.146935)
			(xy 89.544439 -50.160982) (xy 89.468869 -50.167031) (xy 89.393085 -50.165012) (xy 89.317945 -50.15495)
			(xy 89.2443 -50.136958) (xy 89.172984 -50.11124) (xy 89.104807 -50.078088) (xy 89.040539 -50.037876)
			(xy 88.98091 -49.991061) (xy 88.926594 -49.938173) (xy 88.878208 -49.879811) (xy 88.8363 -49.816636)
			(xy 88.801344 -49.749365) (xy 88.773737 -49.67876) (xy 88.753791 -49.605619) (xy 88.741732 -49.530774)
			(xy 88.737697 -49.45507) (xy 87.621618 -49.45507) (xy 87.621114 -49.492976) (xy 87.613055 -49.568357)
			(xy 87.59703 -49.642455) (xy 87.57322 -49.71443) (xy 87.541894 -49.783466) (xy 87.503407 -49.848781)
			(xy 87.458196 -49.909636) (xy 87.406772 -49.96534) (xy 87.349719 -50.015262) (xy 87.287683 -50.058837)
			(xy 87.221366 -50.095572) (xy 87.15152 -50.125049) (xy 87.078937 -50.146935) (xy 87.004439 -50.160982)
			(xy 86.928869 -50.167031) (xy 86.853085 -50.165012) (xy 86.777945 -50.15495) (xy 86.7043 -50.136958)
			(xy 86.632984 -50.11124) (xy 86.564807 -50.078088) (xy 86.500539 -50.037876) (xy 86.44091 -49.991061)
			(xy 86.386594 -49.938173) (xy 86.338208 -49.879811) (xy 86.2963 -49.816636) (xy 86.261344 -49.749365)
			(xy 86.233737 -49.67876) (xy 86.213791 -49.605619) (xy 86.201732 -49.530774) (xy 86.197697 -49.45507)
			(xy 62.265544 -49.45507) (xy 62.316652 -49.49979) (xy 62.368076 -49.555494) (xy 62.413287 -49.616349)
			(xy 62.451774 -49.681664) (xy 62.4831 -49.7507) (xy 62.50691 -49.822675) (xy 62.522935 -49.896773)
			(xy 62.530994 -49.972154) (xy 62.531498 -50.01006) (xy 62.530994 -50.047966) (xy 62.522935 -50.123347)
			(xy 62.50691 -50.197445) (xy 62.4831 -50.26942) (xy 62.451774 -50.338456) (xy 62.413287 -50.403771)
			(xy 62.368076 -50.464626) (xy 62.316652 -50.52033) (xy 62.259599 -50.570252) (xy 62.197563 -50.613827)
			(xy 62.131246 -50.650562) (xy 62.0614 -50.680039) (xy 61.988817 -50.701925) (xy 61.914319 -50.715972)
			(xy 61.838749 -50.722021) (xy 61.762965 -50.720002) (xy 61.687825 -50.70994) (xy 61.61418 -50.691948)
			(xy 61.542864 -50.66623) (xy 61.474687 -50.633078) (xy 61.410419 -50.592866) (xy 61.35079 -50.546051)
			(xy 61.296474 -50.493163) (xy 61.248088 -50.434801) (xy 61.20618 -50.371626) (xy 61.171224 -50.304355)
			(xy 61.143617 -50.23375) (xy 61.123671 -50.160609) (xy 61.111612 -50.085764) (xy 61.107577 -50.01006)
			(xy 59.991498 -50.01006) (xy 59.990994 -50.047966) (xy 59.982935 -50.123347) (xy 59.96691 -50.197445)
			(xy 59.9431 -50.26942) (xy 59.911774 -50.338456) (xy 59.873287 -50.403771) (xy 59.828076 -50.464626)
			(xy 59.776652 -50.52033) (xy 59.719599 -50.570252) (xy 59.657563 -50.613827) (xy 59.591246 -50.650562)
			(xy 59.5214 -50.680039) (xy 59.448817 -50.701925) (xy 59.374319 -50.715972) (xy 59.298749 -50.722021)
			(xy 59.222965 -50.720002) (xy 59.147825 -50.70994) (xy 59.07418 -50.691948) (xy 59.002864 -50.66623)
			(xy 58.934687 -50.633078) (xy 58.870419 -50.592866) (xy 58.81079 -50.546051) (xy 58.756474 -50.493163)
			(xy 58.708088 -50.434801) (xy 58.66618 -50.371626) (xy 58.631224 -50.304355) (xy 58.603617 -50.23375)
			(xy 58.583671 -50.160609) (xy 58.571612 -50.085764) (xy 58.567577 -50.01006) (xy 57.451498 -50.01006)
			(xy 57.450994 -50.047966) (xy 57.442935 -50.123347) (xy 57.42691 -50.197445) (xy 57.4031 -50.26942)
			(xy 57.371774 -50.338456) (xy 57.333287 -50.403771) (xy 57.288076 -50.464626) (xy 57.236652 -50.52033)
			(xy 57.179599 -50.570252) (xy 57.117563 -50.613827) (xy 57.051246 -50.650562) (xy 56.9814 -50.680039)
			(xy 56.908817 -50.701925) (xy 56.834319 -50.715972) (xy 56.758749 -50.722021) (xy 56.682965 -50.720002)
			(xy 56.607825 -50.70994) (xy 56.53418 -50.691948) (xy 56.462864 -50.66623) (xy 56.394687 -50.633078)
			(xy 56.330419 -50.592866) (xy 56.27079 -50.546051) (xy 56.216474 -50.493163) (xy 56.168088 -50.434801)
			(xy 56.12618 -50.371626) (xy 56.091224 -50.304355) (xy 56.063617 -50.23375) (xy 56.043671 -50.160609)
			(xy 56.031612 -50.085764) (xy 56.027577 -50.01006) (xy 54.911498 -50.01006) (xy 54.910994 -50.047966)
			(xy 54.902935 -50.123347) (xy 54.88691 -50.197445) (xy 54.8631 -50.26942) (xy 54.831774 -50.338456)
			(xy 54.793287 -50.403771) (xy 54.748076 -50.464626) (xy 54.696652 -50.52033) (xy 54.639599 -50.570252)
			(xy 54.577563 -50.613827) (xy 54.511246 -50.650562) (xy 54.4414 -50.680039) (xy 54.368817 -50.701925)
			(xy 54.294319 -50.715972) (xy 54.218749 -50.722021) (xy 54.142965 -50.720002) (xy 54.067825 -50.70994)
			(xy 53.99418 -50.691948) (xy 53.922864 -50.66623) (xy 53.854687 -50.633078) (xy 53.790419 -50.592866)
			(xy 53.73079 -50.546051) (xy 53.676474 -50.493163) (xy 53.628088 -50.434801) (xy 53.58618 -50.371626)
			(xy 53.551224 -50.304355) (xy 53.523617 -50.23375) (xy 53.503671 -50.160609) (xy 53.491612 -50.085764)
			(xy 53.487577 -50.01006) (xy 52.371498 -50.01006) (xy 52.370994 -50.047966) (xy 52.362935 -50.123347)
			(xy 52.34691 -50.197445) (xy 52.3231 -50.26942) (xy 52.291774 -50.338456) (xy 52.253287 -50.403771)
			(xy 52.208076 -50.464626) (xy 52.156652 -50.52033) (xy 52.099599 -50.570252) (xy 52.037563 -50.613827)
			(xy 51.971246 -50.650562) (xy 51.9014 -50.680039) (xy 51.828817 -50.701925) (xy 51.754319 -50.715972)
			(xy 51.678749 -50.722021) (xy 51.602965 -50.720002) (xy 51.527825 -50.70994) (xy 51.45418 -50.691948)
			(xy 51.382864 -50.66623) (xy 51.314687 -50.633078) (xy 51.250419 -50.592866) (xy 51.19079 -50.546051)
			(xy 51.136474 -50.493163) (xy 51.088088 -50.434801) (xy 51.04618 -50.371626) (xy 51.011224 -50.304355)
			(xy 50.983617 -50.23375) (xy 50.963671 -50.160609) (xy 50.951612 -50.085764) (xy 50.947577 -50.01006)
			(xy 49.831498 -50.01006) (xy 49.830994 -50.047966) (xy 49.822935 -50.123347) (xy 49.80691 -50.197445)
			(xy 49.7831 -50.26942) (xy 49.751774 -50.338456) (xy 49.713287 -50.403771) (xy 49.668076 -50.464626)
			(xy 49.616652 -50.52033) (xy 49.559599 -50.570252) (xy 49.497563 -50.613827) (xy 49.431246 -50.650562)
			(xy 49.3614 -50.680039) (xy 49.288817 -50.701925) (xy 49.214319 -50.715972) (xy 49.138749 -50.722021)
			(xy 49.062965 -50.720002) (xy 48.987825 -50.70994) (xy 48.91418 -50.691948) (xy 48.842864 -50.66623)
			(xy 48.774687 -50.633078) (xy 48.710419 -50.592866) (xy 48.65079 -50.546051) (xy 48.596474 -50.493163)
			(xy 48.548088 -50.434801) (xy 48.50618 -50.371626) (xy 48.471224 -50.304355) (xy 48.443617 -50.23375)
			(xy 48.423671 -50.160609) (xy 48.411612 -50.085764) (xy 48.407577 -50.01006) (xy 47.291498 -50.01006)
			(xy 47.290994 -50.047966) (xy 47.282935 -50.123347) (xy 47.26691 -50.197445) (xy 47.2431 -50.26942)
			(xy 47.211774 -50.338456) (xy 47.173287 -50.403771) (xy 47.128076 -50.464626) (xy 47.076652 -50.52033)
			(xy 47.019599 -50.570252) (xy 46.957563 -50.613827) (xy 46.891246 -50.650562) (xy 46.8214 -50.680039)
			(xy 46.748817 -50.701925) (xy 46.674319 -50.715972) (xy 46.598749 -50.722021) (xy 46.522965 -50.720002)
			(xy 46.447825 -50.70994) (xy 46.37418 -50.691948) (xy 46.302864 -50.66623) (xy 46.234687 -50.633078)
			(xy 46.170419 -50.592866) (xy 46.11079 -50.546051) (xy 46.056474 -50.493163) (xy 46.008088 -50.434801)
			(xy 45.96618 -50.371626) (xy 45.931224 -50.304355) (xy 45.903617 -50.23375) (xy 45.883671 -50.160609)
			(xy 45.871612 -50.085764) (xy 45.867577 -50.01006) (xy 44.751498 -50.01006) (xy 44.750994 -50.047966)
			(xy 44.742935 -50.123347) (xy 44.72691 -50.197445) (xy 44.7031 -50.26942) (xy 44.671774 -50.338456)
			(xy 44.633287 -50.403771) (xy 44.588076 -50.464626) (xy 44.536652 -50.52033) (xy 44.479599 -50.570252)
			(xy 44.417563 -50.613827) (xy 44.351246 -50.650562) (xy 44.2814 -50.680039) (xy 44.208817 -50.701925)
			(xy 44.134319 -50.715972) (xy 44.058749 -50.722021) (xy 43.982965 -50.720002) (xy 43.907825 -50.70994)
			(xy 43.83418 -50.691948) (xy 43.762864 -50.66623) (xy 43.694687 -50.633078) (xy 43.630419 -50.592866)
			(xy 43.57079 -50.546051) (xy 43.516474 -50.493163) (xy 43.468088 -50.434801) (xy 43.42618 -50.371626)
			(xy 43.391224 -50.304355) (xy 43.363617 -50.23375) (xy 43.343671 -50.160609) (xy 43.331612 -50.085764)
			(xy 43.327577 -50.01006) (xy 42.502604 -50.01006) (xy 42.593088 -50.082218) (xy 42.678643 -50.160691)
			(xy 42.758581 -50.244879) (xy 42.83252 -50.334381) (xy 42.900108 -50.428772) (xy 42.961022 -50.5276)
			(xy 43.014974 -50.630396) (xy 43.056604 -50.72507) (xy 84.927697 -50.72507) (xy 84.931732 -50.649366)
			(xy 84.943791 -50.574521) (xy 84.963737 -50.50138) (xy 84.991344 -50.430775) (xy 85.0263 -50.363504)
			(xy 85.068208 -50.300329) (xy 85.116594 -50.241967) (xy 85.17091 -50.189079) (xy 85.230539 -50.142264)
			(xy 85.294807 -50.102052) (xy 85.362984 -50.0689) (xy 85.4343 -50.043182) (xy 85.507945 -50.02519)
			(xy 85.583085 -50.015128) (xy 85.658869 -50.013109) (xy 85.734439 -50.019158) (xy 85.808937 -50.033205)
			(xy 85.88152 -50.055091) (xy 85.951366 -50.084568) (xy 86.017683 -50.121303) (xy 86.079719 -50.164878)
			(xy 86.136772 -50.2148) (xy 86.188196 -50.270504) (xy 86.233407 -50.331359) (xy 86.271894 -50.396674)
			(xy 86.30322 -50.46571) (xy 86.32703 -50.537685) (xy 86.343055 -50.611783) (xy 86.351114 -50.687164)
			(xy 86.351618 -50.72507) (xy 87.467697 -50.72507) (xy 87.471732 -50.649366) (xy 87.483791 -50.574521)
			(xy 87.503737 -50.50138) (xy 87.531344 -50.430775) (xy 87.5663 -50.363504) (xy 87.608208 -50.300329)
			(xy 87.656594 -50.241967) (xy 87.71091 -50.189079) (xy 87.770539 -50.142264) (xy 87.834807 -50.102052)
			(xy 87.902984 -50.0689) (xy 87.9743 -50.043182) (xy 88.047945 -50.02519) (xy 88.123085 -50.015128)
			(xy 88.198869 -50.013109) (xy 88.274439 -50.019158) (xy 88.348937 -50.033205) (xy 88.42152 -50.055091)
			(xy 88.491366 -50.084568) (xy 88.557683 -50.121303) (xy 88.619719 -50.164878) (xy 88.676772 -50.2148)
			(xy 88.728196 -50.270504) (xy 88.773407 -50.331359) (xy 88.811894 -50.396674) (xy 88.84322 -50.46571)
			(xy 88.86703 -50.537685) (xy 88.883055 -50.611783) (xy 88.891114 -50.687164) (xy 88.891618 -50.72507)
			(xy 90.007697 -50.72507) (xy 90.011732 -50.649366) (xy 90.023791 -50.574521) (xy 90.043737 -50.50138)
			(xy 90.071344 -50.430775) (xy 90.1063 -50.363504) (xy 90.148208 -50.300329) (xy 90.196594 -50.241967)
			(xy 90.25091 -50.189079) (xy 90.310539 -50.142264) (xy 90.374807 -50.102052) (xy 90.442984 -50.0689)
			(xy 90.5143 -50.043182) (xy 90.587945 -50.02519) (xy 90.663085 -50.015128) (xy 90.738869 -50.013109)
			(xy 90.814439 -50.019158) (xy 90.888937 -50.033205) (xy 90.96152 -50.055091) (xy 91.031366 -50.084568)
			(xy 91.097683 -50.121303) (xy 91.159719 -50.164878) (xy 91.216772 -50.2148) (xy 91.268196 -50.270504)
			(xy 91.313407 -50.331359) (xy 91.351894 -50.396674) (xy 91.38322 -50.46571) (xy 91.40703 -50.537685)
			(xy 91.423055 -50.611783) (xy 91.431114 -50.687164) (xy 91.431618 -50.72507) (xy 91.431114 -50.762976)
			(xy 91.423055 -50.838357) (xy 91.40703 -50.912455) (xy 91.38322 -50.98443) (xy 91.351894 -51.053466)
			(xy 91.313407 -51.118781) (xy 91.268196 -51.179636) (xy 91.216772 -51.23534) (xy 91.159719 -51.285262)
			(xy 91.097683 -51.328837) (xy 91.031366 -51.365572) (xy 90.96152 -51.395049) (xy 90.888937 -51.416935)
			(xy 90.814439 -51.430982) (xy 90.738869 -51.437031) (xy 90.663085 -51.435012) (xy 90.587945 -51.42495)
			(xy 90.5143 -51.406958) (xy 90.442984 -51.38124) (xy 90.374807 -51.348088) (xy 90.310539 -51.307876)
			(xy 90.25091 -51.261061) (xy 90.196594 -51.208173) (xy 90.148208 -51.149811) (xy 90.1063 -51.086636)
			(xy 90.071344 -51.019365) (xy 90.043737 -50.94876) (xy 90.023791 -50.875619) (xy 90.011732 -50.800774)
			(xy 90.007697 -50.72507) (xy 88.891618 -50.72507) (xy 88.891114 -50.762976) (xy 88.883055 -50.838357)
			(xy 88.86703 -50.912455) (xy 88.84322 -50.98443) (xy 88.811894 -51.053466) (xy 88.773407 -51.118781)
			(xy 88.728196 -51.179636) (xy 88.676772 -51.23534) (xy 88.619719 -51.285262) (xy 88.557683 -51.328837)
			(xy 88.491366 -51.365572) (xy 88.42152 -51.395049) (xy 88.348937 -51.416935) (xy 88.274439 -51.430982)
			(xy 88.198869 -51.437031) (xy 88.123085 -51.435012) (xy 88.047945 -51.42495) (xy 87.9743 -51.406958)
			(xy 87.902984 -51.38124) (xy 87.834807 -51.348088) (xy 87.770539 -51.307876) (xy 87.71091 -51.261061)
			(xy 87.656594 -51.208173) (xy 87.608208 -51.149811) (xy 87.5663 -51.086636) (xy 87.531344 -51.019365)
			(xy 87.503737 -50.94876) (xy 87.483791 -50.875619) (xy 87.471732 -50.800774) (xy 87.467697 -50.72507)
			(xy 86.351618 -50.72507) (xy 86.351114 -50.762976) (xy 86.343055 -50.838357) (xy 86.32703 -50.912455)
			(xy 86.30322 -50.98443) (xy 86.271894 -51.053466) (xy 86.233407 -51.118781) (xy 86.188196 -51.179636)
			(xy 86.136772 -51.23534) (xy 86.079719 -51.285262) (xy 86.017683 -51.328837) (xy 85.951366 -51.365572)
			(xy 85.88152 -51.395049) (xy 85.808937 -51.416935) (xy 85.734439 -51.430982) (xy 85.658869 -51.437031)
			(xy 85.583085 -51.435012) (xy 85.507945 -51.42495) (xy 85.4343 -51.406958) (xy 85.362984 -51.38124)
			(xy 85.294807 -51.348088) (xy 85.230539 -51.307876) (xy 85.17091 -51.261061) (xy 85.116594 -51.208173)
			(xy 85.068208 -51.149811) (xy 85.0263 -51.086636) (xy 84.991344 -51.019365) (xy 84.963737 -50.94876)
			(xy 84.943791 -50.875619) (xy 84.931732 -50.800774) (xy 84.927697 -50.72507) (xy 43.056604 -50.72507)
			(xy 43.061704 -50.736669) (xy 43.100992 -50.845913) (xy 43.132649 -50.957606) (xy 43.156525 -51.071218)
			(xy 43.172506 -51.186206) (xy 43.180515 -51.302023) (xy 43.181016 -51.36007) (xy 43.180515 -51.418117)
			(xy 43.172506 -51.533934) (xy 43.156525 -51.648922) (xy 43.132649 -51.762534) (xy 43.100992 -51.874227)
			(xy 43.061704 -51.983471) (xy 43.056604 -51.99507) (xy 86.197697 -51.99507) (xy 86.201732 -51.919366)
			(xy 86.213791 -51.844521) (xy 86.233737 -51.77138) (xy 86.261344 -51.700775) (xy 86.2963 -51.633504)
			(xy 86.338208 -51.570329) (xy 86.386594 -51.511967) (xy 86.44091 -51.459079) (xy 86.500539 -51.412264)
			(xy 86.564807 -51.372052) (xy 86.632984 -51.3389) (xy 86.7043 -51.313182) (xy 86.777945 -51.29519)
			(xy 86.853085 -51.285128) (xy 86.928869 -51.283109) (xy 87.004439 -51.289158) (xy 87.078937 -51.303205)
			(xy 87.15152 -51.325091) (xy 87.221366 -51.354568) (xy 87.287683 -51.391303) (xy 87.349719 -51.434878)
			(xy 87.406772 -51.4848) (xy 87.458196 -51.540504) (xy 87.503407 -51.601359) (xy 87.541894 -51.666674)
			(xy 87.57322 -51.73571) (xy 87.59703 -51.807685) (xy 87.613055 -51.881783) (xy 87.621114 -51.957164)
			(xy 87.621618 -51.99507) (xy 88.737697 -51.99507) (xy 88.741732 -51.919366) (xy 88.753791 -51.844521)
			(xy 88.773737 -51.77138) (xy 88.801344 -51.700775) (xy 88.8363 -51.633504) (xy 88.878208 -51.570329)
			(xy 88.926594 -51.511967) (xy 88.98091 -51.459079) (xy 89.040539 -51.412264) (xy 89.104807 -51.372052)
			(xy 89.172984 -51.3389) (xy 89.2443 -51.313182) (xy 89.317945 -51.29519) (xy 89.393085 -51.285128)
			(xy 89.468869 -51.283109) (xy 89.544439 -51.289158) (xy 89.618937 -51.303205) (xy 89.69152 -51.325091)
			(xy 89.761366 -51.354568) (xy 89.827683 -51.391303) (xy 89.889719 -51.434878) (xy 89.946772 -51.4848)
			(xy 89.998196 -51.540504) (xy 90.043407 -51.601359) (xy 90.081894 -51.666674) (xy 90.11322 -51.73571)
			(xy 90.13703 -51.807685) (xy 90.153055 -51.881783) (xy 90.161114 -51.957164) (xy 90.161618 -51.99507)
			(xy 91.277697 -51.99507) (xy 91.281732 -51.919366) (xy 91.293791 -51.844521) (xy 91.313737 -51.77138)
			(xy 91.341344 -51.700775) (xy 91.3763 -51.633504) (xy 91.418208 -51.570329) (xy 91.466594 -51.511967)
			(xy 91.52091 -51.459079) (xy 91.580539 -51.412264) (xy 91.644807 -51.372052) (xy 91.712984 -51.3389)
			(xy 91.7843 -51.313182) (xy 91.857945 -51.29519) (xy 91.933085 -51.285128) (xy 92.008869 -51.283109)
			(xy 92.084439 -51.289158) (xy 92.158937 -51.303205) (xy 92.23152 -51.325091) (xy 92.301366 -51.354568)
			(xy 92.367683 -51.391303) (xy 92.429719 -51.434878) (xy 92.486772 -51.4848) (xy 92.538196 -51.540504)
			(xy 92.583407 -51.601359) (xy 92.621894 -51.666674) (xy 92.65322 -51.73571) (xy 92.67703 -51.807685)
			(xy 92.693055 -51.881783) (xy 92.701114 -51.957164) (xy 92.701618 -51.99507) (xy 92.701114 -52.032976)
			(xy 92.693055 -52.108357) (xy 92.67703 -52.182455) (xy 92.65322 -52.25443) (xy 92.621894 -52.323466)
			(xy 92.583407 -52.388781) (xy 92.538196 -52.449636) (xy 92.486772 -52.50534) (xy 92.429719 -52.555262)
			(xy 92.367683 -52.598837) (xy 92.301366 -52.635572) (xy 92.23152 -52.665049) (xy 92.158937 -52.686935)
			(xy 92.084439 -52.700982) (xy 92.008869 -52.707031) (xy 91.933085 -52.705012) (xy 91.857945 -52.69495)
			(xy 91.7843 -52.676958) (xy 91.712984 -52.65124) (xy 91.644807 -52.618088) (xy 91.580539 -52.577876)
			(xy 91.52091 -52.531061) (xy 91.466594 -52.478173) (xy 91.418208 -52.419811) (xy 91.3763 -52.356636)
			(xy 91.341344 -52.289365) (xy 91.313737 -52.21876) (xy 91.293791 -52.145619) (xy 91.281732 -52.070774)
			(xy 91.277697 -51.99507) (xy 90.161618 -51.99507) (xy 90.161114 -52.032976) (xy 90.153055 -52.108357)
			(xy 90.13703 -52.182455) (xy 90.11322 -52.25443) (xy 90.081894 -52.323466) (xy 90.043407 -52.388781)
			(xy 89.998196 -52.449636) (xy 89.946772 -52.50534) (xy 89.889719 -52.555262) (xy 89.827683 -52.598837)
			(xy 89.761366 -52.635572) (xy 89.69152 -52.665049) (xy 89.618937 -52.686935) (xy 89.544439 -52.700982)
			(xy 89.468869 -52.707031) (xy 89.393085 -52.705012) (xy 89.317945 -52.69495) (xy 89.2443 -52.676958)
			(xy 89.172984 -52.65124) (xy 89.104807 -52.618088) (xy 89.040539 -52.577876) (xy 88.98091 -52.531061)
			(xy 88.926594 -52.478173) (xy 88.878208 -52.419811) (xy 88.8363 -52.356636) (xy 88.801344 -52.289365)
			(xy 88.773737 -52.21876) (xy 88.753791 -52.145619) (xy 88.741732 -52.070774) (xy 88.737697 -51.99507)
			(xy 87.621618 -51.99507) (xy 87.621114 -52.032976) (xy 87.613055 -52.108357) (xy 87.59703 -52.182455)
			(xy 87.57322 -52.25443) (xy 87.541894 -52.323466) (xy 87.503407 -52.388781) (xy 87.458196 -52.449636)
			(xy 87.406772 -52.50534) (xy 87.349719 -52.555262) (xy 87.287683 -52.598837) (xy 87.221366 -52.635572)
			(xy 87.15152 -52.665049) (xy 87.078937 -52.686935) (xy 87.004439 -52.700982) (xy 86.928869 -52.707031)
			(xy 86.853085 -52.705012) (xy 86.777945 -52.69495) (xy 86.7043 -52.676958) (xy 86.632984 -52.65124)
			(xy 86.564807 -52.618088) (xy 86.500539 -52.577876) (xy 86.44091 -52.531061) (xy 86.386594 -52.478173)
			(xy 86.338208 -52.419811) (xy 86.2963 -52.356636) (xy 86.261344 -52.289365) (xy 86.233737 -52.21876)
			(xy 86.213791 -52.145619) (xy 86.201732 -52.070774) (xy 86.197697 -51.99507) (xy 43.056604 -51.99507)
			(xy 43.055152 -51.998372) (xy 43.328336 -51.998372) (xy 44.751244 -51.998372) (xy 44.751244 -52.71008)
			(xy 45.867577 -52.71008) (xy 45.871612 -52.634376) (xy 45.883671 -52.559531) (xy 45.903617 -52.48639)
			(xy 45.931224 -52.415785) (xy 45.96618 -52.348514) (xy 46.008088 -52.285339) (xy 46.056474 -52.226977)
			(xy 46.11079 -52.174089) (xy 46.170419 -52.127274) (xy 46.234687 -52.087062) (xy 46.302864 -52.05391)
			(xy 46.37418 -52.028192) (xy 46.447825 -52.0102) (xy 46.522965 -52.000138) (xy 46.598749 -51.998119)
			(xy 46.674319 -52.004168) (xy 46.748817 -52.018215) (xy 46.8214 -52.040101) (xy 46.891246 -52.069578)
			(xy 46.957563 -52.106313) (xy 47.019599 -52.149888) (xy 47.076652 -52.19981) (xy 47.128076 -52.255514)
			(xy 47.173287 -52.316369) (xy 47.211774 -52.381684) (xy 47.2431 -52.45072) (xy 47.26691 -52.522695)
			(xy 47.282935 -52.596793) (xy 47.290994 -52.672174) (xy 47.291498 -52.71008) (xy 48.407577 -52.71008)
			(xy 48.411612 -52.634376) (xy 48.423671 -52.559531) (xy 48.443617 -52.48639) (xy 48.471224 -52.415785)
			(xy 48.50618 -52.348514) (xy 48.548088 -52.285339) (xy 48.596474 -52.226977) (xy 48.65079 -52.174089)
			(xy 48.710419 -52.127274) (xy 48.774687 -52.087062) (xy 48.842864 -52.05391) (xy 48.91418 -52.028192)
			(xy 48.987825 -52.0102) (xy 49.062965 -52.000138) (xy 49.138749 -51.998119) (xy 49.214319 -52.004168)
			(xy 49.288817 -52.018215) (xy 49.3614 -52.040101) (xy 49.431246 -52.069578) (xy 49.497563 -52.106313)
			(xy 49.559599 -52.149888) (xy 49.616652 -52.19981) (xy 49.668076 -52.255514) (xy 49.713287 -52.316369)
			(xy 49.751774 -52.381684) (xy 49.7831 -52.45072) (xy 49.80691 -52.522695) (xy 49.822935 -52.596793)
			(xy 49.830994 -52.672174) (xy 49.831498 -52.71008) (xy 50.947577 -52.71008) (xy 50.951612 -52.634376)
			(xy 50.963671 -52.559531) (xy 50.983617 -52.48639) (xy 51.011224 -52.415785) (xy 51.04618 -52.348514)
			(xy 51.088088 -52.285339) (xy 51.136474 -52.226977) (xy 51.19079 -52.174089) (xy 51.250419 -52.127274)
			(xy 51.314687 -52.087062) (xy 51.382864 -52.05391) (xy 51.45418 -52.028192) (xy 51.527825 -52.0102)
			(xy 51.602965 -52.000138) (xy 51.678749 -51.998119) (xy 51.754319 -52.004168) (xy 51.828817 -52.018215)
			(xy 51.9014 -52.040101) (xy 51.971246 -52.069578) (xy 52.037563 -52.106313) (xy 52.099599 -52.149888)
			(xy 52.156652 -52.19981) (xy 52.208076 -52.255514) (xy 52.253287 -52.316369) (xy 52.291774 -52.381684)
			(xy 52.3231 -52.45072) (xy 52.34691 -52.522695) (xy 52.362935 -52.596793) (xy 52.370994 -52.672174)
			(xy 52.371498 -52.71008) (xy 53.487577 -52.71008) (xy 53.491612 -52.634376) (xy 53.503671 -52.559531)
			(xy 53.523617 -52.48639) (xy 53.551224 -52.415785) (xy 53.58618 -52.348514) (xy 53.628088 -52.285339)
			(xy 53.676474 -52.226977) (xy 53.73079 -52.174089) (xy 53.790419 -52.127274) (xy 53.854687 -52.087062)
			(xy 53.922864 -52.05391) (xy 53.99418 -52.028192) (xy 54.067825 -52.0102) (xy 54.142965 -52.000138)
			(xy 54.218749 -51.998119) (xy 54.294319 -52.004168) (xy 54.368817 -52.018215) (xy 54.4414 -52.040101)
			(xy 54.511246 -52.069578) (xy 54.577563 -52.106313) (xy 54.639599 -52.149888) (xy 54.696652 -52.19981)
			(xy 54.748076 -52.255514) (xy 54.793287 -52.316369) (xy 54.831774 -52.381684) (xy 54.8631 -52.45072)
			(xy 54.88691 -52.522695) (xy 54.902935 -52.596793) (xy 54.910994 -52.672174) (xy 54.911498 -52.71008)
			(xy 56.027577 -52.71008) (xy 56.031612 -52.634376) (xy 56.043671 -52.559531) (xy 56.063617 -52.48639)
			(xy 56.091224 -52.415785) (xy 56.12618 -52.348514) (xy 56.168088 -52.285339) (xy 56.216474 -52.226977)
			(xy 56.27079 -52.174089) (xy 56.330419 -52.127274) (xy 56.394687 -52.087062) (xy 56.462864 -52.05391)
			(xy 56.53418 -52.028192) (xy 56.607825 -52.0102) (xy 56.682965 -52.000138) (xy 56.758749 -51.998119)
			(xy 56.834319 -52.004168) (xy 56.908817 -52.018215) (xy 56.9814 -52.040101) (xy 57.051246 -52.069578)
			(xy 57.117563 -52.106313) (xy 57.179599 -52.149888) (xy 57.236652 -52.19981) (xy 57.288076 -52.255514)
			(xy 57.333287 -52.316369) (xy 57.371774 -52.381684) (xy 57.4031 -52.45072) (xy 57.42691 -52.522695)
			(xy 57.442935 -52.596793) (xy 57.450994 -52.672174) (xy 57.451498 -52.71008) (xy 58.567577 -52.71008)
			(xy 58.571612 -52.634376) (xy 58.583671 -52.559531) (xy 58.603617 -52.48639) (xy 58.631224 -52.415785)
			(xy 58.66618 -52.348514) (xy 58.708088 -52.285339) (xy 58.756474 -52.226977) (xy 58.81079 -52.174089)
			(xy 58.870419 -52.127274) (xy 58.934687 -52.087062) (xy 59.002864 -52.05391) (xy 59.07418 -52.028192)
			(xy 59.147825 -52.0102) (xy 59.222965 -52.000138) (xy 59.298749 -51.998119) (xy 59.374319 -52.004168)
			(xy 59.448817 -52.018215) (xy 59.5214 -52.040101) (xy 59.591246 -52.069578) (xy 59.657563 -52.106313)
			(xy 59.719599 -52.149888) (xy 59.776652 -52.19981) (xy 59.828076 -52.255514) (xy 59.873287 -52.316369)
			(xy 59.911774 -52.381684) (xy 59.9431 -52.45072) (xy 59.96691 -52.522695) (xy 59.982935 -52.596793)
			(xy 59.990994 -52.672174) (xy 59.991498 -52.71008) (xy 61.107577 -52.71008) (xy 61.111612 -52.634376)
			(xy 61.123671 -52.559531) (xy 61.143617 -52.48639) (xy 61.171224 -52.415785) (xy 61.20618 -52.348514)
			(xy 61.248088 -52.285339) (xy 61.296474 -52.226977) (xy 61.35079 -52.174089) (xy 61.410419 -52.127274)
			(xy 61.474687 -52.087062) (xy 61.542864 -52.05391) (xy 61.61418 -52.028192) (xy 61.687825 -52.0102)
			(xy 61.762965 -52.000138) (xy 61.838749 -51.998119) (xy 61.914319 -52.004168) (xy 61.988817 -52.018215)
			(xy 62.0614 -52.040101) (xy 62.131246 -52.069578) (xy 62.197563 -52.106313) (xy 62.259599 -52.149888)
			(xy 62.316652 -52.19981) (xy 62.368076 -52.255514) (xy 62.413287 -52.316369) (xy 62.451774 -52.381684)
			(xy 62.4831 -52.45072) (xy 62.50691 -52.522695) (xy 62.522935 -52.596793) (xy 62.530994 -52.672174)
			(xy 62.531498 -52.71008) (xy 62.530994 -52.747986) (xy 62.522935 -52.823367) (xy 62.50691 -52.897465)
			(xy 62.4831 -52.96944) (xy 62.451774 -53.038476) (xy 62.413287 -53.103791) (xy 62.368076 -53.164646)
			(xy 62.316652 -53.22035) (xy 62.265544 -53.26507) (xy 84.927697 -53.26507) (xy 84.931732 -53.189366)
			(xy 84.943791 -53.114521) (xy 84.963737 -53.04138) (xy 84.991344 -52.970775) (xy 85.0263 -52.903504)
			(xy 85.068208 -52.840329) (xy 85.116594 -52.781967) (xy 85.17091 -52.729079) (xy 85.230539 -52.682264)
			(xy 85.294807 -52.642052) (xy 85.362984 -52.6089) (xy 85.4343 -52.583182) (xy 85.507945 -52.56519)
			(xy 85.583085 -52.555128) (xy 85.658869 -52.553109) (xy 85.734439 -52.559158) (xy 85.808937 -52.573205)
			(xy 85.88152 -52.595091) (xy 85.951366 -52.624568) (xy 86.017683 -52.661303) (xy 86.079719 -52.704878)
			(xy 86.136772 -52.7548) (xy 86.188196 -52.810504) (xy 86.233407 -52.871359) (xy 86.271894 -52.936674)
			(xy 86.30322 -53.00571) (xy 86.32703 -53.077685) (xy 86.343055 -53.151783) (xy 86.351114 -53.227164)
			(xy 86.351618 -53.26507) (xy 87.467697 -53.26507) (xy 87.471732 -53.189366) (xy 87.483791 -53.114521)
			(xy 87.503737 -53.04138) (xy 87.531344 -52.970775) (xy 87.5663 -52.903504) (xy 87.608208 -52.840329)
			(xy 87.656594 -52.781967) (xy 87.71091 -52.729079) (xy 87.770539 -52.682264) (xy 87.834807 -52.642052)
			(xy 87.902984 -52.6089) (xy 87.9743 -52.583182) (xy 88.047945 -52.56519) (xy 88.123085 -52.555128)
			(xy 88.198869 -52.553109) (xy 88.274439 -52.559158) (xy 88.348937 -52.573205) (xy 88.42152 -52.595091)
			(xy 88.491366 -52.624568) (xy 88.557683 -52.661303) (xy 88.619719 -52.704878) (xy 88.676772 -52.7548)
			(xy 88.728196 -52.810504) (xy 88.773407 -52.871359) (xy 88.811894 -52.936674) (xy 88.84322 -53.00571)
			(xy 88.86703 -53.077685) (xy 88.883055 -53.151783) (xy 88.891114 -53.227164) (xy 88.891618 -53.26507)
			(xy 90.007697 -53.26507) (xy 90.011732 -53.189366) (xy 90.023791 -53.114521) (xy 90.043737 -53.04138)
			(xy 90.071344 -52.970775) (xy 90.1063 -52.903504) (xy 90.148208 -52.840329) (xy 90.196594 -52.781967)
			(xy 90.25091 -52.729079) (xy 90.310539 -52.682264) (xy 90.374807 -52.642052) (xy 90.442984 -52.6089)
			(xy 90.5143 -52.583182) (xy 90.587945 -52.56519) (xy 90.663085 -52.555128) (xy 90.738869 -52.553109)
			(xy 90.814439 -52.559158) (xy 90.888937 -52.573205) (xy 90.96152 -52.595091) (xy 91.031366 -52.624568)
			(xy 91.097683 -52.661303) (xy 91.159719 -52.704878) (xy 91.165664 -52.71008) (xy 93.154506 -52.71008)
			(xy 93.158522 -52.59381) (xy 93.170549 -52.478095) (xy 93.190531 -52.363485) (xy 93.218373 -52.250526)
			(xy 93.253942 -52.139758) (xy 93.297068 -52.031707) (xy 93.347545 -51.926889) (xy 93.405134 -51.825804)
			(xy 93.46956 -51.728932) (xy 93.540515 -51.636736) (xy 93.617662 -51.549655) (xy 93.700633 -51.468104)
			(xy 93.789033 -51.392472) (xy 93.88244 -51.323118) (xy 93.980409 -51.260375) (xy 94.082473 -51.204539)
			(xy 94.188147 -51.155878) (xy 94.296926 -51.114624) (xy 94.408291 -51.080973) (xy 94.521714 -51.055085)
			(xy 94.636651 -51.037084) (xy 94.752557 -51.027055) (xy 94.868879 -51.025047) (xy 94.985062 -51.031069)
			(xy 95.100553 -51.045092) (xy 95.214801 -51.06705) (xy 95.327262 -51.096837) (xy 95.4374 -51.134312)
			(xy 95.54469 -51.179297) (xy 95.648621 -51.231576) (xy 95.748697 -51.290901) (xy 95.844443 -51.356989)
			(xy 95.9354 -51.429525) (xy 96.021136 -51.508164) (xy 96.101243 -51.59253) (xy 96.175339 -51.682222)
			(xy 96.243069 -51.776812) (xy 96.304113 -51.87585) (xy 96.358178 -51.978863) (xy 96.405008 -52.08536)
			(xy 96.444379 -52.194835) (xy 96.476103 -52.306765) (xy 96.500029 -52.420617) (xy 96.516043 -52.535849)
			(xy 96.52407 -52.651911) (xy 96.524572 -52.71008) (xy 96.52407 -52.768249) (xy 96.516043 -52.884311)
			(xy 96.500029 -52.999543) (xy 96.476103 -53.113395) (xy 96.444379 -53.225325) (xy 96.405008 -53.3348)
			(xy 96.358178 -53.441297) (xy 96.304113 -53.54431) (xy 96.243069 -53.643348) (xy 96.175339 -53.737938)
			(xy 96.101243 -53.82763) (xy 96.021136 -53.911996) (xy 95.9354 -53.990635) (xy 95.844443 -54.063171)
			(xy 95.748697 -54.129259) (xy 95.648621 -54.188584) (xy 95.54469 -54.240863) (xy 95.4374 -54.285848)
			(xy 95.327262 -54.323323) (xy 95.214801 -54.35311) (xy 95.100553 -54.375068) (xy 94.985062 -54.389091)
			(xy 94.868879 -54.395113) (xy 94.752557 -54.393105) (xy 94.636651 -54.383076) (xy 94.521714 -54.365075)
			(xy 94.408291 -54.339187) (xy 94.296926 -54.305536) (xy 94.188147 -54.264282) (xy 94.082473 -54.215621)
			(xy 93.980409 -54.159785) (xy 93.88244 -54.097042) (xy 93.789033 -54.027688) (xy 93.700633 -53.952056)
			(xy 93.617662 -53.870505) (xy 93.540515 -53.783424) (xy 93.46956 -53.691228) (xy 93.405134 -53.594356)
			(xy 93.347545 -53.493271) (xy 93.297068 -53.388453) (xy 93.253942 -53.280402) (xy 93.218373 -53.169634)
			(xy 93.190531 -53.056675) (xy 93.170549 -52.942065) (xy 93.158522 -52.82635) (xy 93.154506 -52.71008)
			(xy 91.165664 -52.71008) (xy 91.216772 -52.7548) (xy 91.268196 -52.810504) (xy 91.313407 -52.871359)
			(xy 91.351894 -52.936674) (xy 91.38322 -53.00571) (xy 91.40703 -53.077685) (xy 91.423055 -53.151783)
			(xy 91.431114 -53.227164) (xy 91.431618 -53.26507) (xy 91.431114 -53.302976) (xy 91.423055 -53.378357)
			(xy 91.40703 -53.452455) (xy 91.38322 -53.52443) (xy 91.351894 -53.593466) (xy 91.313407 -53.658781)
			(xy 91.268196 -53.719636) (xy 91.216772 -53.77534) (xy 91.159719 -53.825262) (xy 91.097683 -53.868837)
			(xy 91.031366 -53.905572) (xy 90.96152 -53.935049) (xy 90.888937 -53.956935) (xy 90.814439 -53.970982)
			(xy 90.738869 -53.977031) (xy 90.663085 -53.975012) (xy 90.587945 -53.96495) (xy 90.5143 -53.946958)
			(xy 90.442984 -53.92124) (xy 90.374807 -53.888088) (xy 90.310539 -53.847876) (xy 90.25091 -53.801061)
			(xy 90.196594 -53.748173) (xy 90.148208 -53.689811) (xy 90.1063 -53.626636) (xy 90.071344 -53.559365)
			(xy 90.043737 -53.48876) (xy 90.023791 -53.415619) (xy 90.011732 -53.340774) (xy 90.007697 -53.26507)
			(xy 88.891618 -53.26507) (xy 88.891114 -53.302976) (xy 88.883055 -53.378357) (xy 88.86703 -53.452455)
			(xy 88.84322 -53.52443) (xy 88.811894 -53.593466) (xy 88.773407 -53.658781) (xy 88.728196 -53.719636)
			(xy 88.676772 -53.77534) (xy 88.619719 -53.825262) (xy 88.557683 -53.868837) (xy 88.491366 -53.905572)
			(xy 88.42152 -53.935049) (xy 88.348937 -53.956935) (xy 88.274439 -53.970982) (xy 88.198869 -53.977031)
			(xy 88.123085 -53.975012) (xy 88.047945 -53.96495) (xy 87.9743 -53.946958) (xy 87.902984 -53.92124)
			(xy 87.834807 -53.888088) (xy 87.770539 -53.847876) (xy 87.71091 -53.801061) (xy 87.656594 -53.748173)
			(xy 87.608208 -53.689811) (xy 87.5663 -53.626636) (xy 87.531344 -53.559365) (xy 87.503737 -53.48876)
			(xy 87.483791 -53.415619) (xy 87.471732 -53.340774) (xy 87.467697 -53.26507) (xy 86.351618 -53.26507)
			(xy 86.351114 -53.302976) (xy 86.343055 -53.378357) (xy 86.32703 -53.452455) (xy 86.30322 -53.52443)
			(xy 86.271894 -53.593466) (xy 86.233407 -53.658781) (xy 86.188196 -53.719636) (xy 86.136772 -53.77534)
			(xy 86.079719 -53.825262) (xy 86.017683 -53.868837) (xy 85.951366 -53.905572) (xy 85.88152 -53.935049)
			(xy 85.808937 -53.956935) (xy 85.734439 -53.970982) (xy 85.658869 -53.977031) (xy 85.583085 -53.975012)
			(xy 85.507945 -53.96495) (xy 85.4343 -53.946958) (xy 85.362984 -53.92124) (xy 85.294807 -53.888088)
			(xy 85.230539 -53.847876) (xy 85.17091 -53.801061) (xy 85.116594 -53.748173) (xy 85.068208 -53.689811)
			(xy 85.0263 -53.626636) (xy 84.991344 -53.559365) (xy 84.963737 -53.48876) (xy 84.943791 -53.415619)
			(xy 84.931732 -53.340774) (xy 84.927697 -53.26507) (xy 62.265544 -53.26507) (xy 62.259599 -53.270272)
			(xy 62.197563 -53.313847) (xy 62.131246 -53.350582) (xy 62.0614 -53.380059) (xy 61.988817 -53.401945)
			(xy 61.914319 -53.415992) (xy 61.838749 -53.422041) (xy 61.762965 -53.420022) (xy 61.687825 -53.40996)
			(xy 61.61418 -53.391968) (xy 61.542864 -53.36625) (xy 61.474687 -53.333098) (xy 61.410419 -53.292886)
			(xy 61.35079 -53.246071) (xy 61.296474 -53.193183) (xy 61.248088 -53.134821) (xy 61.20618 -53.071646)
			(xy 61.171224 -53.004375) (xy 61.143617 -52.93377) (xy 61.123671 -52.860629) (xy 61.111612 -52.785784)
			(xy 61.107577 -52.71008) (xy 59.991498 -52.71008) (xy 59.990994 -52.747986) (xy 59.982935 -52.823367)
			(xy 59.96691 -52.897465) (xy 59.9431 -52.96944) (xy 59.911774 -53.038476) (xy 59.873287 -53.103791)
			(xy 59.828076 -53.164646) (xy 59.776652 -53.22035) (xy 59.719599 -53.270272) (xy 59.657563 -53.313847)
			(xy 59.591246 -53.350582) (xy 59.5214 -53.380059) (xy 59.448817 -53.401945) (xy 59.374319 -53.415992)
			(xy 59.298749 -53.422041) (xy 59.222965 -53.420022) (xy 59.147825 -53.40996) (xy 59.07418 -53.391968)
			(xy 59.002864 -53.36625) (xy 58.934687 -53.333098) (xy 58.870419 -53.292886) (xy 58.81079 -53.246071)
			(xy 58.756474 -53.193183) (xy 58.708088 -53.134821) (xy 58.66618 -53.071646) (xy 58.631224 -53.004375)
			(xy 58.603617 -52.93377) (xy 58.583671 -52.860629) (xy 58.571612 -52.785784) (xy 58.567577 -52.71008)
			(xy 57.451498 -52.71008) (xy 57.450994 -52.747986) (xy 57.442935 -52.823367) (xy 57.42691 -52.897465)
			(xy 57.4031 -52.96944) (xy 57.371774 -53.038476) (xy 57.333287 -53.103791) (xy 57.288076 -53.164646)
			(xy 57.236652 -53.22035) (xy 57.179599 -53.270272) (xy 57.117563 -53.313847) (xy 57.051246 -53.350582)
			(xy 56.9814 -53.380059) (xy 56.908817 -53.401945) (xy 56.834319 -53.415992) (xy 56.758749 -53.422041)
			(xy 56.682965 -53.420022) (xy 56.607825 -53.40996) (xy 56.53418 -53.391968) (xy 56.462864 -53.36625)
			(xy 56.394687 -53.333098) (xy 56.330419 -53.292886) (xy 56.27079 -53.246071) (xy 56.216474 -53.193183)
			(xy 56.168088 -53.134821) (xy 56.12618 -53.071646) (xy 56.091224 -53.004375) (xy 56.063617 -52.93377)
			(xy 56.043671 -52.860629) (xy 56.031612 -52.785784) (xy 56.027577 -52.71008) (xy 54.911498 -52.71008)
			(xy 54.910994 -52.747986) (xy 54.902935 -52.823367) (xy 54.88691 -52.897465) (xy 54.8631 -52.96944)
			(xy 54.831774 -53.038476) (xy 54.793287 -53.103791) (xy 54.748076 -53.164646) (xy 54.696652 -53.22035)
			(xy 54.639599 -53.270272) (xy 54.577563 -53.313847) (xy 54.511246 -53.350582) (xy 54.4414 -53.380059)
			(xy 54.368817 -53.401945) (xy 54.294319 -53.415992) (xy 54.218749 -53.422041) (xy 54.142965 -53.420022)
			(xy 54.067825 -53.40996) (xy 53.99418 -53.391968) (xy 53.922864 -53.36625) (xy 53.854687 -53.333098)
			(xy 53.790419 -53.292886) (xy 53.73079 -53.246071) (xy 53.676474 -53.193183) (xy 53.628088 -53.134821)
			(xy 53.58618 -53.071646) (xy 53.551224 -53.004375) (xy 53.523617 -52.93377) (xy 53.503671 -52.860629)
			(xy 53.491612 -52.785784) (xy 53.487577 -52.71008) (xy 52.371498 -52.71008) (xy 52.370994 -52.747986)
			(xy 52.362935 -52.823367) (xy 52.34691 -52.897465) (xy 52.3231 -52.96944) (xy 52.291774 -53.038476)
			(xy 52.253287 -53.103791) (xy 52.208076 -53.164646) (xy 52.156652 -53.22035) (xy 52.099599 -53.270272)
			(xy 52.037563 -53.313847) (xy 51.971246 -53.350582) (xy 51.9014 -53.380059) (xy 51.828817 -53.401945)
			(xy 51.754319 -53.415992) (xy 51.678749 -53.422041) (xy 51.602965 -53.420022) (xy 51.527825 -53.40996)
			(xy 51.45418 -53.391968) (xy 51.382864 -53.36625) (xy 51.314687 -53.333098) (xy 51.250419 -53.292886)
			(xy 51.19079 -53.246071) (xy 51.136474 -53.193183) (xy 51.088088 -53.134821) (xy 51.04618 -53.071646)
			(xy 51.011224 -53.004375) (xy 50.983617 -52.93377) (xy 50.963671 -52.860629) (xy 50.951612 -52.785784)
			(xy 50.947577 -52.71008) (xy 49.831498 -52.71008) (xy 49.830994 -52.747986) (xy 49.822935 -52.823367)
			(xy 49.80691 -52.897465) (xy 49.7831 -52.96944) (xy 49.751774 -53.038476) (xy 49.713287 -53.103791)
			(xy 49.668076 -53.164646) (xy 49.616652 -53.22035) (xy 49.559599 -53.270272) (xy 49.497563 -53.313847)
			(xy 49.431246 -53.350582) (xy 49.3614 -53.380059) (xy 49.288817 -53.401945) (xy 49.214319 -53.415992)
			(xy 49.138749 -53.422041) (xy 49.062965 -53.420022) (xy 48.987825 -53.40996) (xy 48.91418 -53.391968)
			(xy 48.842864 -53.36625) (xy 48.774687 -53.333098) (xy 48.710419 -53.292886) (xy 48.65079 -53.246071)
			(xy 48.596474 -53.193183) (xy 48.548088 -53.134821) (xy 48.50618 -53.071646) (xy 48.471224 -53.004375)
			(xy 48.443617 -52.93377) (xy 48.423671 -52.860629) (xy 48.411612 -52.785784) (xy 48.407577 -52.71008)
			(xy 47.291498 -52.71008) (xy 47.290994 -52.747986) (xy 47.282935 -52.823367) (xy 47.26691 -52.897465)
			(xy 47.2431 -52.96944) (xy 47.211774 -53.038476) (xy 47.173287 -53.103791) (xy 47.128076 -53.164646)
			(xy 47.076652 -53.22035) (xy 47.019599 -53.270272) (xy 46.957563 -53.313847) (xy 46.891246 -53.350582)
			(xy 46.8214 -53.380059) (xy 46.748817 -53.401945) (xy 46.674319 -53.415992) (xy 46.598749 -53.422041)
			(xy 46.522965 -53.420022) (xy 46.447825 -53.40996) (xy 46.37418 -53.391968) (xy 46.302864 -53.36625)
			(xy 46.234687 -53.333098) (xy 46.170419 -53.292886) (xy 46.11079 -53.246071) (xy 46.056474 -53.193183)
			(xy 46.008088 -53.134821) (xy 45.96618 -53.071646) (xy 45.931224 -53.004375) (xy 45.903617 -52.93377)
			(xy 45.883671 -52.860629) (xy 45.871612 -52.785784) (xy 45.867577 -52.71008) (xy 44.751244 -52.71008)
			(xy 44.751244 -53.421788) (xy 43.328336 -53.421788) (xy 43.328336 -51.998372) (xy 43.055152 -51.998372)
			(xy 43.014974 -52.089744) (xy 42.961022 -52.19254) (xy 42.900108 -52.291368) (xy 42.83252 -52.385759)
			(xy 42.758581 -52.475261) (xy 42.678643 -52.559449) (xy 42.593088 -52.637922) (xy 42.502322 -52.710305)
			(xy 42.406779 -52.776254) (xy 42.306914 -52.835454) (xy 42.203202 -52.887623) (xy 42.096139 -52.932512)
			(xy 41.986233 -52.969908) (xy 41.874009 -52.999633) (xy 41.760003 -53.021544) (xy 41.644756 -53.035537)
			(xy 41.528818 -53.041546) (xy 41.412742 -53.039543) (xy 41.29708 -53.029535) (xy 41.182385 -53.011572)
			(xy 41.069202 -52.985739) (xy 40.958071 -52.952159) (xy 40.849522 -52.910991) (xy 40.744072 -52.862433)
			(xy 40.642223 -52.806716) (xy 40.54446 -52.744104) (xy 40.45125 -52.674897) (xy 40.363037 -52.599424)
			(xy 40.280241 -52.518045) (xy 40.203257 -52.431148) (xy 40.132452 -52.339147) (xy 40.068162 -52.24248)
			(xy 40.010695 -52.141608) (xy 39.960324 -52.037011) (xy 39.917289 -51.929188) (xy 39.881795 -51.818654)
			(xy 39.854012 -51.705934) (xy 39.834072 -51.591566) (xy 39.82207 -51.476094) (xy 39.818063 -51.36007)
			(xy 29.24048 -51.36007) (xy 29.24048 -52.893484) (xy 29.519874 -52.893484) (xy 29.519874 -52.806584)
			(xy 29.527892 -52.720055) (xy 29.54386 -52.634635) (xy 29.567641 -52.551053) (xy 29.599033 -52.470021)
			(xy 29.637767 -52.392232) (xy 29.683514 -52.318348) (xy 29.735883 -52.249001) (xy 29.794427 -52.184781)
			(xy 29.858647 -52.126237) (xy 29.927994 -52.073868) (xy 30.001878 -52.028121) (xy 30.079667 -51.989387)
			(xy 30.160699 -51.957995) (xy 30.244281 -51.934214) (xy 30.329701 -51.918246) (xy 30.41623 -51.910228)
			(xy 30.50313 -51.910228) (xy 30.589659 -51.918246) (xy 30.675079 -51.934214) (xy 30.758661 -51.957995)
			(xy 30.839693 -51.989387) (xy 30.917482 -52.028121) (xy 30.991366 -52.073868) (xy 31.060713 -52.126237)
			(xy 31.124933 -52.184781) (xy 31.183477 -52.249001) (xy 31.235846 -52.318348) (xy 31.281593 -52.392232)
			(xy 31.320327 -52.470021) (xy 31.351719 -52.551053) (xy 31.3755 -52.634635) (xy 31.391468 -52.720055)
			(xy 31.399486 -52.806584) (xy 31.399988 -52.850034) (xy 31.399486 -52.893484) (xy 34.599874 -52.893484)
			(xy 34.599874 -52.806584) (xy 34.607892 -52.720055) (xy 34.62386 -52.634635) (xy 34.647641 -52.551053)
			(xy 34.679033 -52.470021) (xy 34.717767 -52.392232) (xy 34.763514 -52.318348) (xy 34.815883 -52.249001)
			(xy 34.874427 -52.184781) (xy 34.938647 -52.126237) (xy 35.007994 -52.073868) (xy 35.081878 -52.028121)
			(xy 35.159667 -51.989387) (xy 35.240699 -51.957995) (xy 35.324281 -51.934214) (xy 35.409701 -51.918246)
			(xy 35.49623 -51.910228) (xy 35.58313 -51.910228) (xy 35.669659 -51.918246) (xy 35.755079 -51.934214)
			(xy 35.838661 -51.957995) (xy 35.919693 -51.989387) (xy 35.997482 -52.028121) (xy 36.071366 -52.073868)
			(xy 36.140713 -52.126237) (xy 36.204933 -52.184781) (xy 36.263477 -52.249001) (xy 36.315846 -52.318348)
			(xy 36.361593 -52.392232) (xy 36.400327 -52.470021) (xy 36.431719 -52.551053) (xy 36.4555 -52.634635)
			(xy 36.471468 -52.720055) (xy 36.479486 -52.806584) (xy 36.479988 -52.850034) (xy 36.479486 -52.893484)
			(xy 36.471468 -52.980013) (xy 36.4555 -53.065433) (xy 36.431719 -53.149015) (xy 36.400327 -53.230047)
			(xy 36.361593 -53.307836) (xy 36.315846 -53.38172) (xy 36.263477 -53.451067) (xy 36.204933 -53.515287)
			(xy 36.140713 -53.573831) (xy 36.071366 -53.6262) (xy 35.997482 -53.671947) (xy 35.919693 -53.710681)
			(xy 35.838661 -53.742073) (xy 35.755079 -53.765854) (xy 35.669659 -53.781822) (xy 35.58313 -53.78984)
			(xy 35.49623 -53.78984) (xy 35.409701 -53.781822) (xy 35.324281 -53.765854) (xy 35.240699 -53.742073)
			(xy 35.159667 -53.710681) (xy 35.081878 -53.671947) (xy 35.007994 -53.6262) (xy 34.938647 -53.573831)
			(xy 34.874427 -53.515287) (xy 34.815883 -53.451067) (xy 34.763514 -53.38172) (xy 34.717767 -53.307836)
			(xy 34.679033 -53.230047) (xy 34.647641 -53.149015) (xy 34.62386 -53.065433) (xy 34.607892 -52.980013)
			(xy 34.599874 -52.893484) (xy 31.399486 -52.893484) (xy 31.391468 -52.980013) (xy 31.3755 -53.065433)
			(xy 31.351719 -53.149015) (xy 31.320327 -53.230047) (xy 31.281593 -53.307836) (xy 31.235846 -53.38172)
			(xy 31.183477 -53.451067) (xy 31.124933 -53.515287) (xy 31.060713 -53.573831) (xy 30.991366 -53.6262)
			(xy 30.917482 -53.671947) (xy 30.839693 -53.710681) (xy 30.758661 -53.742073) (xy 30.675079 -53.765854)
			(xy 30.589659 -53.781822) (xy 30.50313 -53.78984) (xy 30.41623 -53.78984) (xy 30.329701 -53.781822)
			(xy 30.244281 -53.765854) (xy 30.160699 -53.742073) (xy 30.079667 -53.710681) (xy 30.001878 -53.671947)
			(xy 29.927994 -53.6262) (xy 29.858647 -53.573831) (xy 29.794427 -53.515287) (xy 29.735883 -53.451067)
			(xy 29.683514 -53.38172) (xy 29.637767 -53.307836) (xy 29.599033 -53.230047) (xy 29.567641 -53.149015)
			(xy 29.54386 -53.065433) (xy 29.527892 -52.980013) (xy 29.519874 -52.893484) (xy 29.24048 -52.893484)
			(xy 29.24048 -57.398666) (xy 80.99247 -57.398666) (xy 80.996541 -57.343044) (xy 81.008667 -57.288607)
			(xy 81.02859 -57.236516) (xy 81.055886 -57.187881) (xy 81.089972 -57.143738) (xy 81.130121 -57.105029)
			(xy 81.175479 -57.072578) (xy 81.225079 -57.047077) (xy 81.277863 -57.02907) (xy 81.332706 -57.01894)
			(xy 81.38844 -57.016903) (xy 81.443877 -57.023003) (xy 81.497834 -57.037109) (xy 81.549163 -57.058921)
			(xy 81.596769 -57.087975) (xy 81.639637 -57.12365) (xy 81.676854 -57.165187) (xy 81.707627 -57.2117)
			(xy 81.731299 -57.262197) (xy 81.747367 -57.315604) (xy 81.755487 -57.37078) (xy 81.755996 -57.398666)
			(xy 81.755487 -57.426552) (xy 81.747367 -57.481728) (xy 81.731299 -57.535135) (xy 81.707627 -57.585632)
			(xy 81.676854 -57.632145) (xy 81.639637 -57.673682) (xy 81.596769 -57.709357) (xy 81.549163 -57.738411)
			(xy 81.497834 -57.760223) (xy 81.443877 -57.774329) (xy 81.38844 -57.780429) (xy 81.332706 -57.778392)
			(xy 81.277863 -57.768262) (xy 81.225079 -57.750255) (xy 81.175479 -57.724754) (xy 81.130121 -57.692303)
			(xy 81.089972 -57.653594) (xy 81.055886 -57.609451) (xy 81.02859 -57.560816) (xy 81.008667 -57.508725)
			(xy 80.996541 -57.454288) (xy 80.99247 -57.398666) (xy 29.24048 -57.398666) (xy 29.24048 -58.88228)
			(xy 80.412334 -58.88228) (xy 80.416405 -58.826658) (xy 80.428531 -58.772221) (xy 80.448454 -58.72013)
			(xy 80.47575 -58.671495) (xy 80.509836 -58.627352) (xy 80.549985 -58.588643) (xy 80.595343 -58.556192)
			(xy 80.644943 -58.530691) (xy 80.697727 -58.512684) (xy 80.75257 -58.502554) (xy 80.808304 -58.500517)
			(xy 80.863741 -58.506617) (xy 80.917698 -58.520723) (xy 80.969027 -58.542535) (xy 81.016633 -58.571589)
			(xy 81.059501 -58.607264) (xy 81.096718 -58.648801) (xy 81.127491 -58.695314) (xy 81.151163 -58.745811)
			(xy 81.167231 -58.799218) (xy 81.170484 -58.82132) (xy 82.094068 -58.82132) (xy 82.098139 -58.765698)
			(xy 82.110265 -58.711261) (xy 82.130188 -58.65917) (xy 82.157484 -58.610535) (xy 82.19157 -58.566392)
			(xy 82.231719 -58.527683) (xy 82.277077 -58.495232) (xy 82.326677 -58.469731) (xy 82.379461 -58.451724)
			(xy 82.434304 -58.441594) (xy 82.490038 -58.439557) (xy 82.545475 -58.445657) (xy 82.599432 -58.459763)
			(xy 82.650761 -58.481575) (xy 82.698367 -58.510629) (xy 82.741235 -58.546304) (xy 82.778452 -58.587841)
			(xy 82.809225 -58.634354) (xy 82.832897 -58.684851) (xy 82.848965 -58.738258) (xy 82.857085 -58.793434)
			(xy 82.857594 -58.82132) (xy 82.857085 -58.849206) (xy 82.848965 -58.904382) (xy 82.840255 -58.933334)
			(xy 83.703666 -58.933334) (xy 83.707737 -58.877712) (xy 83.719863 -58.823275) (xy 83.739786 -58.771184)
			(xy 83.767082 -58.722549) (xy 83.801168 -58.678406) (xy 83.841317 -58.639697) (xy 83.886675 -58.607246)
			(xy 83.936275 -58.581745) (xy 83.989059 -58.563738) (xy 84.043902 -58.553608) (xy 84.099636 -58.551571)
			(xy 84.155073 -58.557671) (xy 84.20903 -58.571777) (xy 84.260359 -58.593589) (xy 84.307965 -58.622643)
			(xy 84.350833 -58.658318) (xy 84.38805 -58.699855) (xy 84.418823 -58.746368) (xy 84.442495 -58.796865)
			(xy 84.458563 -58.850272) (xy 84.466683 -58.905448) (xy 84.467192 -58.933334) (xy 84.466683 -58.96122)
			(xy 84.458563 -59.016396) (xy 84.442495 -59.069803) (xy 84.418823 -59.1203) (xy 84.38805 -59.166813)
			(xy 84.350833 -59.20835) (xy 84.307965 -59.244025) (xy 84.260359 -59.273079) (xy 84.20903 -59.294891)
			(xy 84.155073 -59.308997) (xy 84.099636 -59.315097) (xy 84.043902 -59.31306) (xy 83.989059 -59.30293)
			(xy 83.936275 -59.284923) (xy 83.886675 -59.259422) (xy 83.841317 -59.226971) (xy 83.801168 -59.188262)
			(xy 83.767082 -59.144119) (xy 83.739786 -59.095484) (xy 83.719863 -59.043393) (xy 83.707737 -58.988956)
			(xy 83.703666 -58.933334) (xy 82.840255 -58.933334) (xy 82.832897 -58.957789) (xy 82.809225 -59.008286)
			(xy 82.778452 -59.054799) (xy 82.741235 -59.096336) (xy 82.698367 -59.132011) (xy 82.650761 -59.161065)
			(xy 82.599432 -59.182877) (xy 82.545475 -59.196983) (xy 82.490038 -59.203083) (xy 82.434304 -59.201046)
			(xy 82.379461 -59.190916) (xy 82.326677 -59.172909) (xy 82.277077 -59.147408) (xy 82.231719 -59.114957)
			(xy 82.19157 -59.076248) (xy 82.157484 -59.032105) (xy 82.130188 -58.98347) (xy 82.110265 -58.931379)
			(xy 82.098139 -58.876942) (xy 82.094068 -58.82132) (xy 81.170484 -58.82132) (xy 81.175351 -58.854394)
			(xy 81.17586 -58.88228) (xy 81.175351 -58.910166) (xy 81.167231 -58.965342) (xy 81.151163 -59.018749)
			(xy 81.127491 -59.069246) (xy 81.096718 -59.115759) (xy 81.059501 -59.157296) (xy 81.016633 -59.192971)
			(xy 80.969027 -59.222025) (xy 80.917698 -59.243837) (xy 80.863741 -59.257943) (xy 80.808304 -59.264043)
			(xy 80.75257 -59.262006) (xy 80.697727 -59.251876) (xy 80.644943 -59.233869) (xy 80.595343 -59.208368)
			(xy 80.549985 -59.175917) (xy 80.509836 -59.137208) (xy 80.47575 -59.093065) (xy 80.448454 -59.04443)
			(xy 80.428531 -58.992339) (xy 80.416405 -58.937902) (xy 80.412334 -58.88228) (xy 29.24048 -58.88228)
			(xy 29.24048 -60.430765) (xy 57.204348 -60.430765) (xy 57.204348 -60.359443) (xy 57.212334 -60.288569)
			(xy 57.228204 -60.219034) (xy 57.251761 -60.151714) (xy 57.282706 -60.087455) (xy 57.320652 -60.027064)
			(xy 57.365121 -59.971302) (xy 57.415554 -59.920869) (xy 57.471316 -59.8764) (xy 57.531707 -59.838454)
			(xy 57.595966 -59.807509) (xy 57.663286 -59.783952) (xy 57.732821 -59.768082) (xy 57.803695 -59.760096)
			(xy 57.875017 -59.760096) (xy 57.945891 -59.768082) (xy 58.015426 -59.783952) (xy 58.082746 -59.807509)
			(xy 58.147005 -59.838454) (xy 58.207396 -59.8764) (xy 58.263158 -59.920869) (xy 58.313591 -59.971302)
			(xy 58.35806 -60.027064) (xy 58.396006 -60.087455) (xy 58.426951 -60.151714) (xy 58.450508 -60.219034)
			(xy 58.466378 -60.288569) (xy 58.474364 -60.359443) (xy 58.474864 -60.395104) (xy 58.474364 -60.430765)
			(xy 58.466378 -60.501639) (xy 58.450508 -60.571174) (xy 58.426951 -60.638494) (xy 58.396006 -60.702753)
			(xy 58.35806 -60.763144) (xy 58.313591 -60.818906) (xy 58.263158 -60.869339) (xy 58.207396 -60.913808)
			(xy 58.147005 -60.951754) (xy 58.082746 -60.982699) (xy 58.015426 -61.006256) (xy 57.945891 -61.022126)
			(xy 57.875017 -61.030112) (xy 57.803695 -61.030112) (xy 57.732821 -61.022126) (xy 57.663286 -61.006256)
			(xy 57.595966 -60.982699) (xy 57.531707 -60.951754) (xy 57.471316 -60.913808) (xy 57.415554 -60.869339)
			(xy 57.365121 -60.818906) (xy 57.320652 -60.763144) (xy 57.282706 -60.702753) (xy 57.251761 -60.638494)
			(xy 57.228204 -60.571174) (xy 57.212334 -60.501639) (xy 57.204348 -60.430765) (xy 29.24048 -60.430765)
			(xy 29.24048 -62.922827) (xy 47.525168 -62.922827) (xy 47.525168 -62.841717) (xy 47.533118 -62.760998)
			(xy 47.548941 -62.681447) (xy 47.572486 -62.603831) (xy 47.603525 -62.528895) (xy 47.64176 -62.457363)
			(xy 47.686822 -62.389923) (xy 47.738277 -62.327224) (xy 47.79563 -62.269871) (xy 47.858329 -62.218416)
			(xy 47.925769 -62.173354) (xy 47.997301 -62.135119) (xy 48.072237 -62.10408) (xy 48.149853 -62.080535)
			(xy 48.229404 -62.064712) (xy 48.310123 -62.056762) (xy 48.391233 -62.056762) (xy 48.471952 -62.064712)
			(xy 48.551503 -62.080535) (xy 48.629119 -62.10408) (xy 48.704055 -62.135119) (xy 48.775587 -62.173354)
			(xy 48.843027 -62.218416) (xy 48.899049 -62.264391) (xy 57.204348 -62.264391) (xy 57.204348 -62.193069)
			(xy 57.212334 -62.122195) (xy 57.228204 -62.05266) (xy 57.251761 -61.98534) (xy 57.282706 -61.921081)
			(xy 57.320652 -61.86069) (xy 57.365121 -61.804928) (xy 57.415554 -61.754495) (xy 57.471316 -61.710026)
			(xy 57.531707 -61.67208) (xy 57.595966 -61.641135) (xy 57.663286 -61.617578) (xy 57.732821 -61.601708)
			(xy 57.803695 -61.593722) (xy 57.875017 -61.593722) (xy 57.945891 -61.601708) (xy 58.015426 -61.617578)
			(xy 58.082746 -61.641135) (xy 58.147005 -61.67208) (xy 58.207396 -61.710026) (xy 58.263158 -61.754495)
			(xy 58.313591 -61.804928) (xy 58.35806 -61.86069) (xy 58.396006 -61.921081) (xy 58.426951 -61.98534)
			(xy 58.450508 -62.05266) (xy 58.466378 -62.122195) (xy 58.474364 -62.193069) (xy 58.474864 -62.22873)
			(xy 58.474364 -62.264391) (xy 59.44539 -62.264391) (xy 59.44539 -62.193069) (xy 59.453376 -62.122195)
			(xy 59.469246 -62.05266) (xy 59.492803 -61.98534) (xy 59.523748 -61.921081) (xy 59.561694 -61.86069)
			(xy 59.606163 -61.804928) (xy 59.656596 -61.754495) (xy 59.712358 -61.710026) (xy 59.772749 -61.67208)
			(xy 59.837008 -61.641135) (xy 59.904328 -61.617578) (xy 59.973863 -61.601708) (xy 60.044737 -61.593722)
			(xy 60.116059 -61.593722) (xy 60.186933 -61.601708) (xy 60.256468 -61.617578) (xy 60.323788 -61.641135)
			(xy 60.388047 -61.67208) (xy 60.448438 -61.710026) (xy 60.5042 -61.754495) (xy 60.554633 -61.804928)
			(xy 60.599102 -61.86069) (xy 60.637048 -61.921081) (xy 60.667993 -61.98534) (xy 60.69155 -62.05266)
			(xy 60.70742 -62.122195) (xy 60.715406 -62.193069) (xy 60.715906 -62.22873) (xy 60.715406 -62.264391)
			(xy 61.349374 -62.264391) (xy 61.349374 -62.193069) (xy 61.35736 -62.122195) (xy 61.37323 -62.05266)
			(xy 61.396787 -61.98534) (xy 61.427732 -61.921081) (xy 61.465678 -61.86069) (xy 61.510147 -61.804928)
			(xy 61.56058 -61.754495) (xy 61.616342 -61.710026) (xy 61.676733 -61.67208) (xy 61.740992 -61.641135)
			(xy 61.808312 -61.617578) (xy 61.877847 -61.601708) (xy 61.948721 -61.593722) (xy 62.020043 -61.593722)
			(xy 62.090917 -61.601708) (xy 62.160452 -61.617578) (xy 62.227772 -61.641135) (xy 62.292031 -61.67208)
			(xy 62.352422 -61.710026) (xy 62.408184 -61.754495) (xy 62.458617 -61.804928) (xy 62.503086 -61.86069)
			(xy 62.541032 -61.921081) (xy 62.571977 -61.98534) (xy 62.595534 -62.05266) (xy 62.611404 -62.122195)
			(xy 62.61939 -62.193069) (xy 62.61989 -62.22873) (xy 62.61939 -62.264391) (xy 62.613162 -62.319662)
			(xy 68.464684 -62.319662) (xy 68.464684 -61.408056) (xy 68.465306 -61.371998) (xy 68.475511 -61.300608)
			(xy 68.485004 -61.265816) (xy 68.490084 -61.24829) (xy 68.490084 -60.874148) (xy 69.455792 -60.874148)
			(xy 69.455792 -61.24829) (xy 69.460872 -61.265816) (xy 69.470354 -61.30061) (xy 69.472497 -61.3156)
			(xy 69.752464 -61.3156) (xy 69.752464 -60.563506) (xy 69.752969 -60.53078) (xy 69.761362 -60.465868)
			(xy 69.778012 -60.402569) (xy 69.802642 -60.341928) (xy 69.834846 -60.284946) (xy 69.854064 -60.258452)
			(xy 69.879464 -60.22467) (xy 69.879464 -60.207652) (xy 69.894704 -60.207652) (xy 69.930518 -60.177172)
			(xy 69.955695 -60.156319) (xy 70.010427 -60.120568) (xy 70.069292 -60.092129) (xy 70.131317 -60.071474)
			(xy 70.195479 -60.058943) (xy 70.260718 -60.054743) (xy 70.325957 -60.058943) (xy 70.390119 -60.071474)
			(xy 70.452144 -60.092129) (xy 70.511009 -60.120568) (xy 70.565741 -60.156319) (xy 70.590918 -60.177172)
			(xy 70.626732 -60.207652) (xy 70.641972 -60.207652) (xy 70.641972 -60.22467) (xy 70.667372 -60.258452)
			(xy 70.684433 -60.281821) (xy 70.713711 -60.331729) (xy 70.725792 -60.35802) (xy 70.732842 -60.372733)
			(xy 70.753165 -60.39824) (xy 70.779296 -60.417754) (xy 70.809524 -60.429999) (xy 70.84187 -60.434171)
			(xy 70.874216 -60.429999) (xy 70.904444 -60.417754) (xy 70.930575 -60.39824) (xy 70.950898 -60.372733)
			(xy 70.957948 -60.35802) (xy 70.970039 -60.331734) (xy 70.999319 -60.281828) (xy 71.016368 -60.258452)
			(xy 71.041768 -60.22467) (xy 71.041768 -60.207652) (xy 71.057008 -60.207652) (xy 71.092822 -60.177172)
			(xy 71.117999 -60.156319) (xy 71.172731 -60.120568) (xy 71.231596 -60.092129) (xy 71.293621 -60.071474)
			(xy 71.357783 -60.058943) (xy 71.423022 -60.054743) (xy 71.488261 -60.058943) (xy 71.552423 -60.071474)
			(xy 71.614448 -60.092129) (xy 71.673313 -60.120568) (xy 71.728045 -60.156319) (xy 71.753222 -60.177172)
			(xy 71.789036 -60.207652) (xy 71.804276 -60.207652) (xy 71.804276 -60.22467) (xy 71.829676 -60.258452)
			(xy 71.848899 -60.284945) (xy 71.881128 -60.341916) (xy 71.905769 -60.402556) (xy 71.922414 -60.46586)
			(xy 71.925933 -60.493148) (xy 79.606138 -60.493148) (xy 79.610209 -60.437526) (xy 79.622335 -60.383089)
			(xy 79.642258 -60.330998) (xy 79.669554 -60.282363) (xy 79.70364 -60.23822) (xy 79.743789 -60.199511)
			(xy 79.789147 -60.16706) (xy 79.838747 -60.141559) (xy 79.891531 -60.123552) (xy 79.946374 -60.113422)
			(xy 80.002108 -60.111385) (xy 80.057545 -60.117485) (xy 80.111502 -60.131591) (xy 80.162831 -60.153403)
			(xy 80.210437 -60.182457) (xy 80.253305 -60.218132) (xy 80.290522 -60.259669) (xy 80.321295 -60.306182)
			(xy 80.344967 -60.356679) (xy 80.361035 -60.410086) (xy 80.369155 -60.465262) (xy 80.369548 -60.486798)
			(xy 81.380328 -60.486798) (xy 81.384399 -60.431176) (xy 81.396525 -60.376739) (xy 81.416448 -60.324648)
			(xy 81.443744 -60.276013) (xy 81.47783 -60.23187) (xy 81.517979 -60.193161) (xy 81.563337 -60.16071)
			(xy 81.612937 -60.135209) (xy 81.665721 -60.117202) (xy 81.720564 -60.107072) (xy 81.776298 -60.105035)
			(xy 81.831735 -60.111135) (xy 81.885692 -60.125241) (xy 81.937021 -60.147053) (xy 81.984627 -60.176107)
			(xy 82.027495 -60.211782) (xy 82.064712 -60.253319) (xy 82.095485 -60.299832) (xy 82.119157 -60.350329)
			(xy 82.135225 -60.403736) (xy 82.143345 -60.458912) (xy 82.143854 -60.486798) (xy 82.143345 -60.514684)
			(xy 82.135225 -60.56986) (xy 82.119157 -60.623267) (xy 82.095485 -60.673764) (xy 82.064712 -60.720277)
			(xy 82.027495 -60.761814) (xy 81.984627 -60.797489) (xy 81.937021 -60.826543) (xy 81.885692 -60.848355)
			(xy 81.831735 -60.862461) (xy 81.776298 -60.868561) (xy 81.720564 -60.866524) (xy 81.665721 -60.856394)
			(xy 81.612937 -60.838387) (xy 81.563337 -60.812886) (xy 81.517979 -60.780435) (xy 81.47783 -60.741726)
			(xy 81.443744 -60.697583) (xy 81.416448 -60.648948) (xy 81.396525 -60.596857) (xy 81.384399 -60.54242)
			(xy 81.380328 -60.486798) (xy 80.369548 -60.486798) (xy 80.369664 -60.493148) (xy 80.369155 -60.521034)
			(xy 80.361035 -60.57621) (xy 80.344967 -60.629617) (xy 80.321295 -60.680114) (xy 80.290522 -60.726627)
			(xy 80.253305 -60.768164) (xy 80.210437 -60.803839) (xy 80.162831 -60.832893) (xy 80.111502 -60.854705)
			(xy 80.057545 -60.868811) (xy 80.002108 -60.874911) (xy 79.946374 -60.872874) (xy 79.891531 -60.862744)
			(xy 79.838747 -60.844737) (xy 79.789147 -60.819236) (xy 79.743789 -60.786785) (xy 79.70364 -60.748076)
			(xy 79.669554 -60.703933) (xy 79.642258 -60.655298) (xy 79.622335 -60.603207) (xy 79.610209 -60.54877)
			(xy 79.606138 -60.493148) (xy 71.925933 -60.493148) (xy 71.930786 -60.530778) (xy 71.931276 -60.563506)
			(xy 71.931276 -61.21654) (xy 77.4098 -61.21654) (xy 77.413871 -61.160918) (xy 77.425997 -61.106481)
			(xy 77.44592 -61.05439) (xy 77.473216 -61.005755) (xy 77.507302 -60.961612) (xy 77.547451 -60.922903)
			(xy 77.592809 -60.890452) (xy 77.642409 -60.864951) (xy 77.695193 -60.846944) (xy 77.750036 -60.836814)
			(xy 77.80577 -60.834777) (xy 77.861207 -60.840877) (xy 77.915164 -60.854983) (xy 77.966493 -60.876795)
			(xy 78.014099 -60.905849) (xy 78.056967 -60.941524) (xy 78.094184 -60.983061) (xy 78.124957 -61.029574)
			(xy 78.148629 -61.080071) (xy 78.164697 -61.133478) (xy 78.172817 -61.188654) (xy 78.173326 -61.21654)
			(xy 78.172817 -61.244426) (xy 78.164697 -61.299602) (xy 78.148629 -61.353009) (xy 78.124957 -61.403506)
			(xy 78.094184 -61.450019) (xy 78.056967 -61.491556) (xy 78.014099 -61.527231) (xy 77.966493 -61.556285)
			(xy 77.915164 -61.578097) (xy 77.861207 -61.592203) (xy 77.80577 -61.598303) (xy 77.750036 -61.596266)
			(xy 77.695193 -61.586136) (xy 77.642409 -61.568129) (xy 77.592809 -61.542628) (xy 77.547451 -61.510177)
			(xy 77.507302 -61.471468) (xy 77.473216 -61.427325) (xy 77.44592 -61.37869) (xy 77.425997 -61.326599)
			(xy 77.413871 -61.272162) (xy 77.4098 -61.21654) (xy 71.931276 -61.21654) (xy 71.931276 -61.372496)
			(xy 71.930826 -61.404128) (xy 71.922988 -61.466903) (xy 71.90742 -61.528221) (xy 71.884364 -61.587133)
			(xy 71.854175 -61.642728) (xy 71.81732 -61.694147) (xy 71.774369 -61.740595) (xy 71.725987 -61.781354)
			(xy 71.67292 -61.815794) (xy 71.615989 -61.843382) (xy 71.556075 -61.863693) (xy 71.494104 -61.876411)
			(xy 71.431033 -61.88134) (xy 71.367838 -61.878404) (xy 71.305496 -61.867649) (xy 71.244971 -61.849241)
			(xy 71.187198 -61.823464) (xy 71.13307 -61.790716) (xy 71.083424 -61.751505) (xy 71.039028 -61.706436)
			(xy 71.019416 -61.681614) (xy 71.005644 -61.664351) (xy 70.973158 -61.634443) (xy 70.93599 -61.610601)
			(xy 70.89526 -61.593544) (xy 70.852195 -61.583785) (xy 70.808091 -61.581617) (xy 70.764276 -61.587107)
			(xy 70.72207 -61.600089) (xy 70.682744 -61.620172) (xy 70.647481 -61.646751) (xy 70.632066 -61.662564)
			(xy 70.609886 -61.685606) (xy 70.560704 -61.726494) (xy 70.50678 -61.760887) (xy 70.448967 -61.788243)
			(xy 70.388179 -61.808129) (xy 70.325376 -61.820231) (xy 70.261551 -61.824358) (xy 70.197712 -61.820445)
			(xy 70.134869 -61.808553) (xy 70.074015 -61.78887) (xy 70.016111 -61.761707) (xy 69.962072 -61.727494)
			(xy 69.912753 -61.686772) (xy 69.868933 -61.640183) (xy 69.831305 -61.588465) (xy 69.800463 -61.532435)
			(xy 69.776894 -61.472977) (xy 69.760972 -61.411032) (xy 69.752947 -61.347579) (xy 69.752464 -61.3156)
			(xy 69.472497 -61.3156) (xy 69.480558 -61.371999) (xy 69.481192 -61.408056) (xy 69.481192 -62.319662)
			(xy 69.480691 -62.351607) (xy 69.474105 -62.403736) (xy 83.420202 -62.403736) (xy 83.424273 -62.348114)
			(xy 83.436399 -62.293677) (xy 83.456322 -62.241586) (xy 83.483618 -62.192951) (xy 83.517704 -62.148808)
			(xy 83.557853 -62.110099) (xy 83.603211 -62.077648) (xy 83.652811 -62.052147) (xy 83.705595 -62.03414)
			(xy 83.760438 -62.02401) (xy 83.816172 -62.021973) (xy 83.871609 -62.028073) (xy 83.925566 -62.042179)
			(xy 83.976895 -62.063991) (xy 84.024501 -62.093045) (xy 84.067369 -62.12872) (xy 84.104586 -62.170257)
			(xy 84.135359 -62.21677) (xy 84.159031 -62.267267) (xy 84.175099 -62.320674) (xy 84.183219 -62.37585)
			(xy 84.183728 -62.403736) (xy 84.183219 -62.431622) (xy 84.175099 -62.486798) (xy 84.159031 -62.540205)
			(xy 84.135359 -62.590702) (xy 84.104586 -62.637215) (xy 84.067369 -62.678752) (xy 84.024501 -62.714427)
			(xy 83.976895 -62.743481) (xy 83.925566 -62.765293) (xy 83.871609 -62.779399) (xy 83.816172 -62.785499)
			(xy 83.760438 -62.783462) (xy 83.705595 -62.773332) (xy 83.652811 -62.755325) (xy 83.603211 -62.729824)
			(xy 83.557853 -62.697373) (xy 83.517704 -62.658664) (xy 83.483618 -62.614521) (xy 83.456322 -62.565886)
			(xy 83.436399 -62.513795) (xy 83.424273 -62.459358) (xy 83.420202 -62.403736) (xy 69.474105 -62.403736)
			(xy 69.472683 -62.414993) (xy 69.456794 -62.476876) (xy 69.433275 -62.53628) (xy 69.402495 -62.592267)
			(xy 69.364942 -62.643956) (xy 69.321206 -62.69053) (xy 69.271978 -62.731255) (xy 69.218033 -62.765489)
			(xy 69.160224 -62.792692) (xy 69.099461 -62.812435) (xy 69.036702 -62.824407) (xy 68.972938 -62.828419)
			(xy 68.909174 -62.824407) (xy 68.846415 -62.812435) (xy 68.785652 -62.792692) (xy 68.727843 -62.765489)
			(xy 68.673898 -62.731255) (xy 68.62467 -62.69053) (xy 68.580934 -62.643956) (xy 68.543381 -62.592267)
			(xy 68.512601 -62.53628) (xy 68.489082 -62.476876) (xy 68.473193 -62.414993) (xy 68.465185 -62.351607)
			(xy 68.464684 -62.319662) (xy 62.613162 -62.319662) (xy 62.611404 -62.335265) (xy 62.595534 -62.4048)
			(xy 62.571977 -62.47212) (xy 62.541032 -62.536379) (xy 62.503086 -62.59677) (xy 62.458617 -62.652532)
			(xy 62.408184 -62.702965) (xy 62.352422 -62.747434) (xy 62.292031 -62.78538) (xy 62.227772 -62.816325)
			(xy 62.160452 -62.839882) (xy 62.090917 -62.855752) (xy 62.020043 -62.863738) (xy 61.948721 -62.863738)
			(xy 61.877847 -62.855752) (xy 61.808312 -62.839882) (xy 61.740992 -62.816325) (xy 61.676733 -62.78538)
			(xy 61.616342 -62.747434) (xy 61.56058 -62.702965) (xy 61.510147 -62.652532) (xy 61.465678 -62.59677)
			(xy 61.427732 -62.536379) (xy 61.396787 -62.47212) (xy 61.37323 -62.4048) (xy 61.35736 -62.335265)
			(xy 61.349374 -62.264391) (xy 60.715406 -62.264391) (xy 60.70742 -62.335265) (xy 60.69155 -62.4048)
			(xy 60.667993 -62.47212) (xy 60.637048 -62.536379) (xy 60.599102 -62.59677) (xy 60.554633 -62.652532)
			(xy 60.5042 -62.702965) (xy 60.448438 -62.747434) (xy 60.388047 -62.78538) (xy 60.323788 -62.816325)
			(xy 60.256468 -62.839882) (xy 60.186933 -62.855752) (xy 60.116059 -62.863738) (xy 60.044737 -62.863738)
			(xy 59.973863 -62.855752) (xy 59.904328 -62.839882) (xy 59.837008 -62.816325) (xy 59.772749 -62.78538)
			(xy 59.712358 -62.747434) (xy 59.656596 -62.702965) (xy 59.606163 -62.652532) (xy 59.561694 -62.59677)
			(xy 59.523748 -62.536379) (xy 59.492803 -62.47212) (xy 59.469246 -62.4048) (xy 59.453376 -62.335265)
			(xy 59.44539 -62.264391) (xy 58.474364 -62.264391) (xy 58.466378 -62.335265) (xy 58.450508 -62.4048)
			(xy 58.426951 -62.47212) (xy 58.396006 -62.536379) (xy 58.35806 -62.59677) (xy 58.313591 -62.652532)
			(xy 58.263158 -62.702965) (xy 58.207396 -62.747434) (xy 58.147005 -62.78538) (xy 58.082746 -62.816325)
			(xy 58.015426 -62.839882) (xy 57.945891 -62.855752) (xy 57.875017 -62.863738) (xy 57.803695 -62.863738)
			(xy 57.732821 -62.855752) (xy 57.663286 -62.839882) (xy 57.595966 -62.816325) (xy 57.531707 -62.78538)
			(xy 57.471316 -62.747434) (xy 57.415554 -62.702965) (xy 57.365121 -62.652532) (xy 57.320652 -62.59677)
			(xy 57.282706 -62.536379) (xy 57.251761 -62.47212) (xy 57.228204 -62.4048) (xy 57.212334 -62.335265)
			(xy 57.204348 -62.264391) (xy 48.899049 -62.264391) (xy 48.905726 -62.269871) (xy 48.963079 -62.327224)
			(xy 49.014534 -62.389923) (xy 49.059596 -62.457363) (xy 49.097831 -62.528895) (xy 49.12887 -62.603831)
			(xy 49.152415 -62.681447) (xy 49.168238 -62.760998) (xy 49.176188 -62.841717) (xy 49.176686 -62.882272)
			(xy 49.176188 -62.922827) (xy 49.168238 -63.003546) (xy 49.152415 -63.083097) (xy 49.12887 -63.160713)
			(xy 49.107957 -63.211202) (xy 77.86446 -63.211202) (xy 77.868531 -63.15558) (xy 77.880657 -63.101143)
			(xy 77.90058 -63.049052) (xy 77.927876 -63.000417) (xy 77.961962 -62.956274) (xy 78.002111 -62.917565)
			(xy 78.047469 -62.885114) (xy 78.097069 -62.859613) (xy 78.149853 -62.841606) (xy 78.204696 -62.831476)
			(xy 78.26043 -62.829439) (xy 78.315867 -62.835539) (xy 78.369824 -62.849645) (xy 78.421153 -62.871457)
			(xy 78.468759 -62.900511) (xy 78.511627 -62.936186) (xy 78.548844 -62.977723) (xy 78.579617 -63.024236)
			(xy 78.603289 -63.074733) (xy 78.619357 -63.12814) (xy 78.627477 -63.183316) (xy 78.627986 -63.211202)
			(xy 78.627477 -63.239088) (xy 78.619357 -63.294264) (xy 78.603289 -63.347671) (xy 78.579617 -63.398168)
			(xy 78.548844 -63.444681) (xy 78.511627 -63.486218) (xy 78.468759 -63.521893) (xy 78.460932 -63.52667)
			(xy 81.142076 -63.52667) (xy 81.146147 -63.471048) (xy 81.158273 -63.416611) (xy 81.178196 -63.36452)
			(xy 81.205492 -63.315885) (xy 81.239578 -63.271742) (xy 81.279727 -63.233033) (xy 81.325085 -63.200582)
			(xy 81.374685 -63.175081) (xy 81.427469 -63.157074) (xy 81.482312 -63.146944) (xy 81.538046 -63.144907)
			(xy 81.593483 -63.151007) (xy 81.64744 -63.165113) (xy 81.698769 -63.186925) (xy 81.746375 -63.215979)
			(xy 81.789243 -63.251654) (xy 81.82646 -63.293191) (xy 81.857233 -63.339704) (xy 81.880905 -63.390201)
			(xy 81.896973 -63.443608) (xy 81.905093 -63.498784) (xy 81.905602 -63.52667) (xy 81.905093 -63.554556)
			(xy 81.896973 -63.609732) (xy 81.880905 -63.663139) (xy 81.857233 -63.713636) (xy 81.82646 -63.760149)
			(xy 81.789243 -63.801686) (xy 81.746375 -63.837361) (xy 81.698769 -63.866415) (xy 81.64744 -63.888227)
			(xy 81.593483 -63.902333) (xy 81.538046 -63.908433) (xy 81.482312 -63.906396) (xy 81.427469 -63.896266)
			(xy 81.374685 -63.878259) (xy 81.325085 -63.852758) (xy 81.279727 -63.820307) (xy 81.239578 -63.781598)
			(xy 81.205492 -63.737455) (xy 81.178196 -63.68882) (xy 81.158273 -63.636729) (xy 81.146147 -63.582292)
			(xy 81.142076 -63.52667) (xy 78.460932 -63.52667) (xy 78.421153 -63.550947) (xy 78.369824 -63.572759)
			(xy 78.315867 -63.586865) (xy 78.26043 -63.592965) (xy 78.204696 -63.590928) (xy 78.149853 -63.580798)
			(xy 78.097069 -63.562791) (xy 78.047469 -63.53729) (xy 78.002111 -63.504839) (xy 77.961962 -63.46613)
			(xy 77.927876 -63.421987) (xy 77.90058 -63.373352) (xy 77.880657 -63.321261) (xy 77.868531 -63.266824)
			(xy 77.86446 -63.211202) (xy 49.107957 -63.211202) (xy 49.097831 -63.235649) (xy 49.059596 -63.307181)
			(xy 49.014534 -63.374621) (xy 48.963079 -63.43732) (xy 48.905726 -63.494673) (xy 48.843027 -63.546128)
			(xy 48.775587 -63.59119) (xy 48.704055 -63.629425) (xy 48.629119 -63.660464) (xy 48.551503 -63.684009)
			(xy 48.471952 -63.699832) (xy 48.391233 -63.707782) (xy 48.310123 -63.707782) (xy 48.229404 -63.699832)
			(xy 48.149853 -63.684009) (xy 48.072237 -63.660464) (xy 47.997301 -63.629425) (xy 47.925769 -63.59119)
			(xy 47.858329 -63.546128) (xy 47.79563 -63.494673) (xy 47.738277 -63.43732) (xy 47.686822 -63.374621)
			(xy 47.64176 -63.307181) (xy 47.603525 -63.235649) (xy 47.572486 -63.160713) (xy 47.548941 -63.083097)
			(xy 47.533118 -63.003546) (xy 47.525168 -62.922827) (xy 29.24048 -62.922827) (xy 29.24048 -64.165327)
			(xy 57.204348 -64.165327) (xy 57.204348 -64.094005) (xy 57.212334 -64.023131) (xy 57.228204 -63.953596)
			(xy 57.251761 -63.886276) (xy 57.282706 -63.822017) (xy 57.320652 -63.761626) (xy 57.365121 -63.705864)
			(xy 57.415554 -63.655431) (xy 57.471316 -63.610962) (xy 57.531707 -63.573016) (xy 57.595966 -63.542071)
			(xy 57.663286 -63.518514) (xy 57.732821 -63.502644) (xy 57.803695 -63.494658) (xy 57.875017 -63.494658)
			(xy 57.945891 -63.502644) (xy 58.015426 -63.518514) (xy 58.082746 -63.542071) (xy 58.147005 -63.573016)
			(xy 58.207396 -63.610962) (xy 58.263158 -63.655431) (xy 58.313591 -63.705864) (xy 58.35806 -63.761626)
			(xy 58.396006 -63.822017) (xy 58.426951 -63.886276) (xy 58.450508 -63.953596) (xy 58.466378 -64.023131)
			(xy 58.474364 -64.094005) (xy 58.474864 -64.129666) (xy 58.474364 -64.165327) (xy 59.44539 -64.165327)
			(xy 59.44539 -64.094005) (xy 59.453376 -64.023131) (xy 59.469246 -63.953596) (xy 59.492803 -63.886276)
			(xy 59.523748 -63.822017) (xy 59.561694 -63.761626) (xy 59.606163 -63.705864) (xy 59.656596 -63.655431)
			(xy 59.712358 -63.610962) (xy 59.772749 -63.573016) (xy 59.837008 -63.542071) (xy 59.904328 -63.518514)
			(xy 59.973863 -63.502644) (xy 60.044737 -63.494658) (xy 60.116059 -63.494658) (xy 60.186933 -63.502644)
			(xy 60.256468 -63.518514) (xy 60.323788 -63.542071) (xy 60.388047 -63.573016) (xy 60.448438 -63.610962)
			(xy 60.5042 -63.655431) (xy 60.554633 -63.705864) (xy 60.599102 -63.761626) (xy 60.637048 -63.822017)
			(xy 60.667993 -63.886276) (xy 60.69155 -63.953596) (xy 60.70742 -64.023131) (xy 60.715406 -64.094005)
			(xy 60.715906 -64.129666) (xy 60.715406 -64.165327) (xy 61.349374 -64.165327) (xy 61.349374 -64.094005)
			(xy 61.35736 -64.023131) (xy 61.37323 -63.953596) (xy 61.396787 -63.886276) (xy 61.427732 -63.822017)
			(xy 61.465678 -63.761626) (xy 61.510147 -63.705864) (xy 61.56058 -63.655431) (xy 61.616342 -63.610962)
			(xy 61.676733 -63.573016) (xy 61.740992 -63.542071) (xy 61.808312 -63.518514) (xy 61.877847 -63.502644)
			(xy 61.948721 -63.494658) (xy 62.020043 -63.494658) (xy 62.090917 -63.502644) (xy 62.160452 -63.518514)
			(xy 62.227772 -63.542071) (xy 62.292031 -63.573016) (xy 62.352422 -63.610962) (xy 62.408184 -63.655431)
			(xy 62.458617 -63.705864) (xy 62.503086 -63.761626) (xy 62.541032 -63.822017) (xy 62.571977 -63.886276)
			(xy 62.595534 -63.953596) (xy 62.611404 -64.023131) (xy 62.612075 -64.029082) (xy 79.612742 -64.029082)
			(xy 79.616813 -63.97346) (xy 79.628939 -63.919023) (xy 79.648862 -63.866932) (xy 79.676158 -63.818297)
			(xy 79.710244 -63.774154) (xy 79.750393 -63.735445) (xy 79.795751 -63.702994) (xy 79.845351 -63.677493)
			(xy 79.898135 -63.659486) (xy 79.952978 -63.649356) (xy 80.008712 -63.647319) (xy 80.064149 -63.653419)
			(xy 80.118106 -63.667525) (xy 80.169435 -63.689337) (xy 80.217041 -63.718391) (xy 80.259909 -63.754066)
			(xy 80.297126 -63.795603) (xy 80.327899 -63.842116) (xy 80.351571 -63.892613) (xy 80.367639 -63.94602)
			(xy 80.375759 -64.001196) (xy 80.376268 -64.029082) (xy 80.375759 -64.056968) (xy 80.367639 -64.112144)
			(xy 80.351571 -64.165551) (xy 80.327899 -64.216048) (xy 80.297126 -64.262561) (xy 80.259909 -64.304098)
			(xy 80.217041 -64.339773) (xy 80.169435 -64.368827) (xy 80.118106 -64.390639) (xy 80.064149 -64.404745)
			(xy 80.008712 -64.410845) (xy 79.952978 -64.408808) (xy 79.898135 -64.398678) (xy 79.845351 -64.380671)
			(xy 79.795751 -64.35517) (xy 79.750393 -64.322719) (xy 79.710244 -64.28401) (xy 79.676158 -64.239867)
			(xy 79.648862 -64.191232) (xy 79.628939 -64.139141) (xy 79.616813 -64.084704) (xy 79.612742 -64.029082)
			(xy 62.612075 -64.029082) (xy 62.61939 -64.094005) (xy 62.61989 -64.129666) (xy 62.61939 -64.165327)
			(xy 62.611404 -64.236201) (xy 62.595534 -64.305736) (xy 62.571977 -64.373056) (xy 62.541032 -64.437315)
			(xy 62.526703 -64.46012) (xy 86.39887 -64.46012) (xy 86.402874 -64.260022) (xy 86.414881 -64.060244)
			(xy 86.434872 -63.861107) (xy 86.462814 -63.662929) (xy 86.498662 -63.466027) (xy 86.54236 -63.270718)
			(xy 86.593837 -63.077313) (xy 86.653011 -62.886123) (xy 86.719787 -62.697453) (xy 86.794059 -62.511606)
			(xy 86.875706 -62.328879) (xy 86.964599 -62.149566) (xy 87.060595 -61.973952) (xy 87.16354 -61.80232)
			(xy 87.27327 -61.634944) (xy 87.389608 -61.472093) (xy 87.512369 -61.314026) (xy 87.641356 -61.160998)
			(xy 87.776363 -61.013253) (xy 87.917172 -60.871027) (xy 88.063559 -60.73455) (xy 88.215289 -60.604038)
			(xy 88.37212 -60.479702) (xy 88.533799 -60.36174) (xy 88.700069 -60.250341) (xy 88.870662 -60.145684)
			(xy 89.045306 -60.047936) (xy 89.223722 -59.957253) (xy 89.405622 -59.873782) (xy 89.590717 -59.797655)
			(xy 89.778709 -59.728995) (xy 89.969298 -59.667911) (xy 90.162178 -59.614501) (xy 90.35704 -59.568852)
			(xy 90.553573 -59.531035) (xy 90.751462 -59.501111) (xy 90.950389 -59.479129) (xy 91.150037 -59.465124)
			(xy 91.350085 -59.459118) (xy 91.550213 -59.46112) (xy 91.750101 -59.471128) (xy 91.949428 -59.489125)
			(xy 92.147876 -59.515083) (xy 92.345126 -59.54896) (xy 92.540863 -59.590702) (xy 92.734773 -59.640241)
			(xy 92.926546 -59.697499) (xy 93.115875 -59.762384) (xy 93.302455 -59.834792) (xy 93.48599 -59.914608)
			(xy 93.666184 -60.001702) (xy 93.842749 -60.095936) (xy 94.015402 -60.197159) (xy 94.183867 -60.305209)
			(xy 94.347875 -60.419912) (xy 94.507162 -60.541086) (xy 94.661473 -60.668535) (xy 94.810561 -60.802056)
			(xy 94.954188 -60.941436) (xy 95.092124 -61.08645) (xy 95.224147 -61.236867) (xy 95.350046 -61.392445)
			(xy 95.46962 -61.552937) (xy 95.582676 -61.718083) (xy 95.689035 -61.887621) (xy 95.788526 -62.061279)
			(xy 95.880989 -62.238778) (xy 95.966276 -62.419834) (xy 96.044251 -62.604158) (xy 96.114788 -62.791454)
			(xy 96.177776 -62.981422) (xy 96.233113 -63.173758) (xy 96.28071 -63.368154) (xy 96.320491 -63.564299)
			(xy 96.352393 -63.761878) (xy 96.376364 -63.960575) (xy 96.392366 -64.160073) (xy 96.400373 -64.360051)
			(xy 96.400874 -64.46012) (xy 96.400373 -64.560189) (xy 96.392366 -64.760167) (xy 96.376364 -64.959665)
			(xy 96.352393 -65.158362) (xy 96.320491 -65.355941) (xy 96.28071 -65.552086) (xy 96.233113 -65.746482)
			(xy 96.177776 -65.938818) (xy 96.114788 -66.128786) (xy 96.044251 -66.316082) (xy 95.966276 -66.500406)
			(xy 95.880989 -66.681462) (xy 95.788526 -66.858961) (xy 95.689035 -67.032619) (xy 95.582676 -67.202157)
			(xy 95.46962 -67.367303) (xy 95.350046 -67.527795) (xy 95.224147 -67.683373) (xy 95.092124 -67.83379)
			(xy 94.954188 -67.978804) (xy 94.810561 -68.118184) (xy 94.661473 -68.251705) (xy 94.507162 -68.379154)
			(xy 94.347875 -68.500328) (xy 94.183867 -68.615031) (xy 94.015402 -68.723081) (xy 93.842749 -68.824304)
			(xy 93.666184 -68.918538) (xy 93.48599 -69.005632) (xy 93.302455 -69.085448) (xy 93.115875 -69.157856)
			(xy 92.926546 -69.222741) (xy 92.734773 -69.279999) (xy 92.540863 -69.329538) (xy 92.345126 -69.37128)
			(xy 92.147876 -69.405157) (xy 91.949428 -69.431115) (xy 91.750101 -69.449112) (xy 91.550213 -69.45912)
			(xy 91.350085 -69.461122) (xy 91.150037 -69.455116) (xy 90.950389 -69.441111) (xy 90.751462 -69.419129)
			(xy 90.553573 -69.389205) (xy 90.35704 -69.351388) (xy 90.162178 -69.305739) (xy 89.969298 -69.252329)
			(xy 89.778709 -69.191245) (xy 89.590717 -69.122585) (xy 89.405622 -69.046458) (xy 89.223722 -68.962987)
			(xy 89.045306 -68.872304) (xy 88.870662 -68.774556) (xy 88.700069 -68.669899) (xy 88.533799 -68.5585)
			(xy 88.37212 -68.440538) (xy 88.215289 -68.316202) (xy 88.063559 -68.18569) (xy 87.917172 -68.049213)
			(xy 87.776363 -67.906987) (xy 87.641356 -67.759242) (xy 87.512369 -67.606214) (xy 87.389608 -67.448147)
			(xy 87.27327 -67.285296) (xy 87.16354 -67.11792) (xy 87.060595 -66.946288) (xy 86.964599 -66.770674)
			(xy 86.875706 -66.591361) (xy 86.794059 -66.408634) (xy 86.719787 -66.222787) (xy 86.653011 -66.034117)
			(xy 86.593837 -65.842927) (xy 86.54236 -65.649522) (xy 86.498662 -65.454213) (xy 86.462814 -65.257311)
			(xy 86.434872 -65.059133) (xy 86.414881 -64.859996) (xy 86.402874 -64.660218) (xy 86.39887 -64.46012)
			(xy 62.526703 -64.46012) (xy 62.503086 -64.497706) (xy 62.458617 -64.553468) (xy 62.408184 -64.603901)
			(xy 62.352422 -64.64837) (xy 62.292031 -64.686316) (xy 62.227772 -64.717261) (xy 62.160452 -64.740818)
			(xy 62.090917 -64.756688) (xy 62.020043 -64.764674) (xy 61.948721 -64.764674) (xy 61.877847 -64.756688)
			(xy 61.808312 -64.740818) (xy 61.740992 -64.717261) (xy 61.676733 -64.686316) (xy 61.616342 -64.64837)
			(xy 61.56058 -64.603901) (xy 61.510147 -64.553468) (xy 61.465678 -64.497706) (xy 61.427732 -64.437315)
			(xy 61.396787 -64.373056) (xy 61.37323 -64.305736) (xy 61.35736 -64.236201) (xy 61.349374 -64.165327)
			(xy 60.715406 -64.165327) (xy 60.70742 -64.236201) (xy 60.69155 -64.305736) (xy 60.667993 -64.373056)
			(xy 60.637048 -64.437315) (xy 60.599102 -64.497706) (xy 60.554633 -64.553468) (xy 60.5042 -64.603901)
			(xy 60.448438 -64.64837) (xy 60.388047 -64.686316) (xy 60.323788 -64.717261) (xy 60.256468 -64.740818)
			(xy 60.186933 -64.756688) (xy 60.116059 -64.764674) (xy 60.044737 -64.764674) (xy 59.973863 -64.756688)
			(xy 59.904328 -64.740818) (xy 59.837008 -64.717261) (xy 59.772749 -64.686316) (xy 59.712358 -64.64837)
			(xy 59.656596 -64.603901) (xy 59.606163 -64.553468) (xy 59.561694 -64.497706) (xy 59.523748 -64.437315)
			(xy 59.492803 -64.373056) (xy 59.469246 -64.305736) (xy 59.453376 -64.236201) (xy 59.44539 -64.165327)
			(xy 58.474364 -64.165327) (xy 58.466378 -64.236201) (xy 58.450508 -64.305736) (xy 58.426951 -64.373056)
			(xy 58.396006 -64.437315) (xy 58.35806 -64.497706) (xy 58.313591 -64.553468) (xy 58.263158 -64.603901)
			(xy 58.207396 -64.64837) (xy 58.147005 -64.686316) (xy 58.082746 -64.717261) (xy 58.015426 -64.740818)
			(xy 57.945891 -64.756688) (xy 57.875017 -64.764674) (xy 57.803695 -64.764674) (xy 57.732821 -64.756688)
			(xy 57.663286 -64.740818) (xy 57.595966 -64.717261) (xy 57.531707 -64.686316) (xy 57.471316 -64.64837)
			(xy 57.415554 -64.603901) (xy 57.365121 -64.553468) (xy 57.320652 -64.497706) (xy 57.282706 -64.437315)
			(xy 57.251761 -64.373056) (xy 57.228204 -64.305736) (xy 57.212334 -64.236201) (xy 57.204348 -64.165327)
			(xy 29.24048 -64.165327) (xy 29.24048 -66.480537) (xy 43.823374 -66.480537) (xy 43.823374 -66.409215)
			(xy 43.83136 -66.338341) (xy 43.84723 -66.268806) (xy 43.870787 -66.201486) (xy 43.901732 -66.137227)
			(xy 43.939678 -66.076836) (xy 43.984147 -66.021074) (xy 44.03458 -65.970641) (xy 44.090342 -65.926172)
			(xy 44.150733 -65.888226) (xy 44.214992 -65.857281) (xy 44.282312 -65.833724) (xy 44.351847 -65.817854)
			(xy 44.422721 -65.809868) (xy 44.494043 -65.809868) (xy 44.564917 -65.817854) (xy 44.634452 -65.833724)
			(xy 44.653693 -65.840457) (xy 57.204348 -65.840457) (xy 57.204348 -65.769135) (xy 57.212334 -65.698261)
			(xy 57.228204 -65.628726) (xy 57.251761 -65.561406) (xy 57.282706 -65.497147) (xy 57.320652 -65.436756)
			(xy 57.365121 -65.380994) (xy 57.415554 -65.330561) (xy 57.471316 -65.286092) (xy 57.531707 -65.248146)
			(xy 57.595966 -65.217201) (xy 57.663286 -65.193644) (xy 57.732821 -65.177774) (xy 57.803695 -65.169788)
			(xy 57.875017 -65.169788) (xy 57.945891 -65.177774) (xy 58.015426 -65.193644) (xy 58.082746 -65.217201)
			(xy 58.147005 -65.248146) (xy 58.207396 -65.286092) (xy 58.263158 -65.330561) (xy 58.313591 -65.380994)
			(xy 58.35806 -65.436756) (xy 58.396006 -65.497147) (xy 58.426951 -65.561406) (xy 58.450508 -65.628726)
			(xy 58.466378 -65.698261) (xy 58.474364 -65.769135) (xy 58.474864 -65.804796) (xy 58.474364 -65.840457)
			(xy 59.44539 -65.840457) (xy 59.44539 -65.769135) (xy 59.453376 -65.698261) (xy 59.469246 -65.628726)
			(xy 59.492803 -65.561406) (xy 59.523748 -65.497147) (xy 59.561694 -65.436756) (xy 59.606163 -65.380994)
			(xy 59.656596 -65.330561) (xy 59.712358 -65.286092) (xy 59.772749 -65.248146) (xy 59.837008 -65.217201)
			(xy 59.904328 -65.193644) (xy 59.973863 -65.177774) (xy 60.044737 -65.169788) (xy 60.116059 -65.169788)
			(xy 60.186933 -65.177774) (xy 60.256468 -65.193644) (xy 60.323788 -65.217201) (xy 60.388047 -65.248146)
			(xy 60.448438 -65.286092) (xy 60.5042 -65.330561) (xy 60.554633 -65.380994) (xy 60.599102 -65.436756)
			(xy 60.637048 -65.497147) (xy 60.667993 -65.561406) (xy 60.69155 -65.628726) (xy 60.70742 -65.698261)
			(xy 60.715406 -65.769135) (xy 60.715906 -65.804796) (xy 60.715406 -65.840457) (xy 61.349374 -65.840457)
			(xy 61.349374 -65.769135) (xy 61.35736 -65.698261) (xy 61.37323 -65.628726) (xy 61.396787 -65.561406)
			(xy 61.427732 -65.497147) (xy 61.465678 -65.436756) (xy 61.510147 -65.380994) (xy 61.56058 -65.330561)
			(xy 61.616342 -65.286092) (xy 61.676733 -65.248146) (xy 61.740992 -65.217201) (xy 61.808312 -65.193644)
			(xy 61.877847 -65.177774) (xy 61.948721 -65.169788) (xy 62.020043 -65.169788) (xy 62.090917 -65.177774)
			(xy 62.160452 -65.193644) (xy 62.227772 -65.217201) (xy 62.292031 -65.248146) (xy 62.352422 -65.286092)
			(xy 62.408184 -65.330561) (xy 62.458617 -65.380994) (xy 62.503086 -65.436756) (xy 62.541032 -65.497147)
			(xy 62.571977 -65.561406) (xy 62.595534 -65.628726) (xy 62.607603 -65.681606) (xy 77.3082 -65.681606)
			(xy 77.312271 -65.625984) (xy 77.324397 -65.571547) (xy 77.34432 -65.519456) (xy 77.371616 -65.470821)
			(xy 77.405702 -65.426678) (xy 77.445851 -65.387969) (xy 77.491209 -65.355518) (xy 77.540809 -65.330017)
			(xy 77.593593 -65.31201) (xy 77.648436 -65.30188) (xy 77.70417 -65.299843) (xy 77.759607 -65.305943)
			(xy 77.813564 -65.320049) (xy 77.864893 -65.341861) (xy 77.912499 -65.370915) (xy 77.955367 -65.40659)
			(xy 77.992584 -65.448127) (xy 78.023357 -65.49464) (xy 78.047029 -65.545137) (xy 78.063097 -65.598544)
			(xy 78.071217 -65.65372) (xy 78.071726 -65.681606) (xy 78.071217 -65.709492) (xy 78.063097 -65.764668)
			(xy 78.047029 -65.818075) (xy 78.023357 -65.868572) (xy 77.992584 -65.915085) (xy 77.955367 -65.956622)
			(xy 77.912499 -65.992297) (xy 77.864893 -66.021351) (xy 77.813564 -66.043163) (xy 77.759607 -66.057269)
			(xy 77.70417 -66.063369) (xy 77.648436 -66.061332) (xy 77.593593 -66.051202) (xy 77.540809 -66.033195)
			(xy 77.491209 -66.007694) (xy 77.445851 -65.975243) (xy 77.405702 -65.936534) (xy 77.371616 -65.892391)
			(xy 77.34432 -65.843756) (xy 77.324397 -65.791665) (xy 77.312271 -65.737228) (xy 77.3082 -65.681606)
			(xy 62.607603 -65.681606) (xy 62.611404 -65.698261) (xy 62.61939 -65.769135) (xy 62.61989 -65.804796)
			(xy 62.61939 -65.840457) (xy 62.611404 -65.911331) (xy 62.595534 -65.980866) (xy 62.571977 -66.048186)
			(xy 62.541032 -66.112445) (xy 62.503086 -66.172836) (xy 62.458617 -66.228598) (xy 62.408184 -66.279031)
			(xy 62.352422 -66.3235) (xy 62.292031 -66.361446) (xy 62.227772 -66.392391) (xy 62.160452 -66.415948)
			(xy 62.090917 -66.431818) (xy 62.020043 -66.439804) (xy 61.948721 -66.439804) (xy 61.877847 -66.431818)
			(xy 61.808312 -66.415948) (xy 61.740992 -66.392391) (xy 61.676733 -66.361446) (xy 61.616342 -66.3235)
			(xy 61.56058 -66.279031) (xy 61.510147 -66.228598) (xy 61.465678 -66.172836) (xy 61.427732 -66.112445)
			(xy 61.396787 -66.048186) (xy 61.37323 -65.980866) (xy 61.35736 -65.911331) (xy 61.349374 -65.840457)
			(xy 60.715406 -65.840457) (xy 60.70742 -65.911331) (xy 60.69155 -65.980866) (xy 60.667993 -66.048186)
			(xy 60.637048 -66.112445) (xy 60.599102 -66.172836) (xy 60.554633 -66.228598) (xy 60.5042 -66.279031)
			(xy 60.448438 -66.3235) (xy 60.388047 -66.361446) (xy 60.323788 -66.392391) (xy 60.256468 -66.415948)
			(xy 60.186933 -66.431818) (xy 60.116059 -66.439804) (xy 60.044737 -66.439804) (xy 59.973863 -66.431818)
			(xy 59.904328 -66.415948) (xy 59.837008 -66.392391) (xy 59.772749 -66.361446) (xy 59.712358 -66.3235)
			(xy 59.656596 -66.279031) (xy 59.606163 -66.228598) (xy 59.561694 -66.172836) (xy 59.523748 -66.112445)
			(xy 59.492803 -66.048186) (xy 59.469246 -65.980866) (xy 59.453376 -65.911331) (xy 59.44539 -65.840457)
			(xy 58.474364 -65.840457) (xy 58.466378 -65.911331) (xy 58.450508 -65.980866) (xy 58.426951 -66.048186)
			(xy 58.396006 -66.112445) (xy 58.35806 -66.172836) (xy 58.313591 -66.228598) (xy 58.263158 -66.279031)
			(xy 58.207396 -66.3235) (xy 58.147005 -66.361446) (xy 58.082746 -66.392391) (xy 58.015426 -66.415948)
			(xy 57.945891 -66.431818) (xy 57.875017 -66.439804) (xy 57.803695 -66.439804) (xy 57.732821 -66.431818)
			(xy 57.663286 -66.415948) (xy 57.595966 -66.392391) (xy 57.531707 -66.361446) (xy 57.471316 -66.3235)
			(xy 57.415554 -66.279031) (xy 57.365121 -66.228598) (xy 57.320652 -66.172836) (xy 57.282706 -66.112445)
			(xy 57.251761 -66.048186) (xy 57.228204 -65.980866) (xy 57.212334 -65.911331) (xy 57.204348 -65.840457)
			(xy 44.653693 -65.840457) (xy 44.701772 -65.857281) (xy 44.766031 -65.888226) (xy 44.826422 -65.926172)
			(xy 44.882184 -65.970641) (xy 44.932617 -66.021074) (xy 44.977086 -66.076836) (xy 45.015032 -66.137227)
			(xy 45.045977 -66.201486) (xy 45.069534 -66.268806) (xy 45.085404 -66.338341) (xy 45.09339 -66.409215)
			(xy 45.09389 -66.444876) (xy 45.09339 -66.480537) (xy 45.085404 -66.551411) (xy 45.069534 -66.620946)
			(xy 45.045977 -66.688266) (xy 45.015032 -66.752525) (xy 44.977086 -66.812916) (xy 44.932617 -66.868678)
			(xy 44.882184 -66.919111) (xy 44.826422 -66.96358) (xy 44.766031 -67.001526) (xy 44.701772 -67.032471)
			(xy 44.634452 -67.056028) (xy 44.564917 -67.071898) (xy 44.494043 -67.079884) (xy 44.422721 -67.079884)
			(xy 44.351847 -67.071898) (xy 44.282312 -67.056028) (xy 44.214992 -67.032471) (xy 44.150733 -67.001526)
			(xy 44.090342 -66.96358) (xy 44.03458 -66.919111) (xy 43.984147 -66.868678) (xy 43.939678 -66.812916)
			(xy 43.901732 -66.752525) (xy 43.870787 -66.688266) (xy 43.84723 -66.620946) (xy 43.83136 -66.551411)
			(xy 43.823374 -66.480537) (xy 29.24048 -66.480537) (xy 29.24048 -68.314163) (xy 43.823374 -68.314163)
			(xy 43.823374 -68.242841) (xy 43.83136 -68.171967) (xy 43.84723 -68.102432) (xy 43.870787 -68.035112)
			(xy 43.901732 -67.970853) (xy 43.939678 -67.910462) (xy 43.984147 -67.8547) (xy 44.03458 -67.804267)
			(xy 44.090342 -67.759798) (xy 44.150733 -67.721852) (xy 44.214992 -67.690907) (xy 44.282312 -67.66735)
			(xy 44.351847 -67.65148) (xy 44.422721 -67.643494) (xy 44.494043 -67.643494) (xy 44.564917 -67.65148)
			(xy 44.634452 -67.66735) (xy 44.701772 -67.690907) (xy 44.766031 -67.721852) (xy 44.826422 -67.759798)
			(xy 44.882184 -67.804267) (xy 44.929546 -67.851629) (xy 57.160914 -67.851629) (xy 57.160914 -67.780307)
			(xy 57.1689 -67.709433) (xy 57.18477 -67.639898) (xy 57.208327 -67.572578) (xy 57.239272 -67.508319)
			(xy 57.277218 -67.447928) (xy 57.321687 -67.392166) (xy 57.37212 -67.341733) (xy 57.427882 -67.297264)
			(xy 57.488273 -67.259318) (xy 57.552532 -67.228373) (xy 57.619852 -67.204816) (xy 57.689387 -67.188946)
			(xy 57.760261 -67.18096) (xy 57.831583 -67.18096) (xy 57.902457 -67.188946) (xy 57.971992 -67.204816)
			(xy 58.039312 -67.228373) (xy 58.103571 -67.259318) (xy 58.163962 -67.297264) (xy 58.219724 -67.341733)
			(xy 58.270157 -67.392166) (xy 58.314626 -67.447928) (xy 58.352572 -67.508319) (xy 58.383517 -67.572578)
			(xy 58.407074 -67.639898) (xy 58.422944 -67.709433) (xy 58.43093 -67.780307) (xy 58.43143 -67.815968)
			(xy 58.43093 -67.851629) (xy 59.401956 -67.851629) (xy 59.401956 -67.780307) (xy 59.409942 -67.709433)
			(xy 59.425812 -67.639898) (xy 59.449369 -67.572578) (xy 59.480314 -67.508319) (xy 59.51826 -67.447928)
			(xy 59.562729 -67.392166) (xy 59.613162 -67.341733) (xy 59.668924 -67.297264) (xy 59.729315 -67.259318)
			(xy 59.793574 -67.228373) (xy 59.860894 -67.204816) (xy 59.930429 -67.188946) (xy 60.001303 -67.18096)
			(xy 60.072625 -67.18096) (xy 60.143499 -67.188946) (xy 60.213034 -67.204816) (xy 60.280354 -67.228373)
			(xy 60.344613 -67.259318) (xy 60.405004 -67.297264) (xy 60.460766 -67.341733) (xy 60.511199 -67.392166)
			(xy 60.555668 -67.447928) (xy 60.593614 -67.508319) (xy 60.624559 -67.572578) (xy 60.648116 -67.639898)
			(xy 60.663986 -67.709433) (xy 60.671972 -67.780307) (xy 60.672472 -67.815968) (xy 60.671972 -67.851629)
			(xy 61.30594 -67.851629) (xy 61.30594 -67.780307) (xy 61.313926 -67.709433) (xy 61.329796 -67.639898)
			(xy 61.353353 -67.572578) (xy 61.384298 -67.508319) (xy 61.422244 -67.447928) (xy 61.466713 -67.392166)
			(xy 61.517146 -67.341733) (xy 61.572908 -67.297264) (xy 61.633299 -67.259318) (xy 61.697558 -67.228373)
			(xy 61.764878 -67.204816) (xy 61.834413 -67.188946) (xy 61.905287 -67.18096) (xy 61.976609 -67.18096)
			(xy 62.047483 -67.188946) (xy 62.117018 -67.204816) (xy 62.184338 -67.228373) (xy 62.248597 -67.259318)
			(xy 62.308988 -67.297264) (xy 62.36475 -67.341733) (xy 62.415183 -67.392166) (xy 62.459652 -67.447928)
			(xy 62.497598 -67.508319) (xy 62.528543 -67.572578) (xy 62.5521 -67.639898) (xy 62.56797 -67.709433)
			(xy 62.575956 -67.780307) (xy 62.576456 -67.815968) (xy 62.575956 -67.851629) (xy 62.56797 -67.922503)
			(xy 62.5521 -67.992038) (xy 62.528543 -68.059358) (xy 62.497598 -68.123617) (xy 62.459652 -68.184008)
			(xy 62.415183 -68.23977) (xy 62.36475 -68.290203) (xy 62.308988 -68.334672) (xy 62.248597 -68.372618)
			(xy 62.184338 -68.403563) (xy 62.117018 -68.42712) (xy 62.047483 -68.44299) (xy 61.976609 -68.450976)
			(xy 61.905287 -68.450976) (xy 61.834413 -68.44299) (xy 61.764878 -68.42712) (xy 61.697558 -68.403563)
			(xy 61.633299 -68.372618) (xy 61.572908 -68.334672) (xy 61.517146 -68.290203) (xy 61.466713 -68.23977)
			(xy 61.422244 -68.184008) (xy 61.384298 -68.123617) (xy 61.353353 -68.059358) (xy 61.329796 -67.992038)
			(xy 61.313926 -67.922503) (xy 61.30594 -67.851629) (xy 60.671972 -67.851629) (xy 60.663986 -67.922503)
			(xy 60.648116 -67.992038) (xy 60.624559 -68.059358) (xy 60.593614 -68.123617) (xy 60.555668 -68.184008)
			(xy 60.511199 -68.23977) (xy 60.460766 -68.290203) (xy 60.405004 -68.334672) (xy 60.344613 -68.372618)
			(xy 60.280354 -68.403563) (xy 60.213034 -68.42712) (xy 60.143499 -68.44299) (xy 60.072625 -68.450976)
			(xy 60.001303 -68.450976) (xy 59.930429 -68.44299) (xy 59.860894 -68.42712) (xy 59.793574 -68.403563)
			(xy 59.729315 -68.372618) (xy 59.668924 -68.334672) (xy 59.613162 -68.290203) (xy 59.562729 -68.23977)
			(xy 59.51826 -68.184008) (xy 59.480314 -68.123617) (xy 59.449369 -68.059358) (xy 59.425812 -67.992038)
			(xy 59.409942 -67.922503) (xy 59.401956 -67.851629) (xy 58.43093 -67.851629) (xy 58.422944 -67.922503)
			(xy 58.407074 -67.992038) (xy 58.383517 -68.059358) (xy 58.352572 -68.123617) (xy 58.314626 -68.184008)
			(xy 58.270157 -68.23977) (xy 58.219724 -68.290203) (xy 58.163962 -68.334672) (xy 58.103571 -68.372618)
			(xy 58.039312 -68.403563) (xy 57.971992 -68.42712) (xy 57.902457 -68.44299) (xy 57.831583 -68.450976)
			(xy 57.760261 -68.450976) (xy 57.689387 -68.44299) (xy 57.619852 -68.42712) (xy 57.552532 -68.403563)
			(xy 57.488273 -68.372618) (xy 57.427882 -68.334672) (xy 57.37212 -68.290203) (xy 57.321687 -68.23977)
			(xy 57.277218 -68.184008) (xy 57.239272 -68.123617) (xy 57.208327 -68.059358) (xy 57.18477 -67.992038)
			(xy 57.1689 -67.922503) (xy 57.160914 -67.851629) (xy 44.929546 -67.851629) (xy 44.932617 -67.8547)
			(xy 44.977086 -67.910462) (xy 45.015032 -67.970853) (xy 45.045977 -68.035112) (xy 45.069534 -68.102432)
			(xy 45.085404 -68.171967) (xy 45.09339 -68.242841) (xy 45.09389 -68.278502) (xy 45.09339 -68.314163)
			(xy 45.085404 -68.385037) (xy 45.069534 -68.454572) (xy 45.045977 -68.521892) (xy 45.015032 -68.586151)
			(xy 44.977086 -68.646542) (xy 44.932617 -68.702304) (xy 44.882184 -68.752737) (xy 44.826422 -68.797206)
			(xy 44.766031 -68.835152) (xy 44.701772 -68.866097) (xy 44.634452 -68.889654) (xy 44.564917 -68.905524)
			(xy 44.494043 -68.91351) (xy 44.422721 -68.91351) (xy 44.351847 -68.905524) (xy 44.282312 -68.889654)
			(xy 44.214992 -68.866097) (xy 44.150733 -68.835152) (xy 44.090342 -68.797206) (xy 44.03458 -68.752737)
			(xy 43.984147 -68.702304) (xy 43.939678 -68.646542) (xy 43.901732 -68.586151) (xy 43.870787 -68.521892)
			(xy 43.84723 -68.454572) (xy 43.83136 -68.385037) (xy 43.823374 -68.314163) (xy 29.24048 -68.314163)
			(xy 29.24048 -70.215099) (xy 43.823374 -70.215099) (xy 43.823374 -70.143777) (xy 43.83136 -70.072903)
			(xy 43.84723 -70.003368) (xy 43.870787 -69.936048) (xy 43.901732 -69.871789) (xy 43.939678 -69.811398)
			(xy 43.984147 -69.755636) (xy 44.03458 -69.705203) (xy 44.090342 -69.660734) (xy 44.150733 -69.622788)
			(xy 44.214992 -69.591843) (xy 44.282312 -69.568286) (xy 44.351847 -69.552416) (xy 44.422721 -69.54443)
			(xy 44.494043 -69.54443) (xy 44.564917 -69.552416) (xy 44.634452 -69.568286) (xy 44.701772 -69.591843)
			(xy 44.766031 -69.622788) (xy 44.826422 -69.660734) (xy 44.882184 -69.705203) (xy 44.919132 -69.742151)
			(xy 57.160914 -69.742151) (xy 57.160914 -69.670829) (xy 57.1689 -69.599955) (xy 57.18477 -69.53042)
			(xy 57.208327 -69.4631) (xy 57.239272 -69.398841) (xy 57.277218 -69.33845) (xy 57.321687 -69.282688)
			(xy 57.37212 -69.232255) (xy 57.427882 -69.187786) (xy 57.488273 -69.14984) (xy 57.552532 -69.118895)
			(xy 57.619852 -69.095338) (xy 57.689387 -69.079468) (xy 57.760261 -69.071482) (xy 57.831583 -69.071482)
			(xy 57.902457 -69.079468) (xy 57.971992 -69.095338) (xy 58.039312 -69.118895) (xy 58.103571 -69.14984)
			(xy 58.163962 -69.187786) (xy 58.219724 -69.232255) (xy 58.270157 -69.282688) (xy 58.314626 -69.33845)
			(xy 58.352572 -69.398841) (xy 58.383517 -69.4631) (xy 58.407074 -69.53042) (xy 58.422944 -69.599955)
			(xy 58.43093 -69.670829) (xy 58.43143 -69.70649) (xy 58.43093 -69.742151) (xy 59.401956 -69.742151)
			(xy 59.401956 -69.670829) (xy 59.409942 -69.599955) (xy 59.425812 -69.53042) (xy 59.449369 -69.4631)
			(xy 59.480314 -69.398841) (xy 59.51826 -69.33845) (xy 59.562729 -69.282688) (xy 59.613162 -69.232255)
			(xy 59.668924 -69.187786) (xy 59.729315 -69.14984) (xy 59.793574 -69.118895) (xy 59.860894 -69.095338)
			(xy 59.930429 -69.079468) (xy 60.001303 -69.071482) (xy 60.072625 -69.071482) (xy 60.143499 -69.079468)
			(xy 60.213034 -69.095338) (xy 60.280354 -69.118895) (xy 60.344613 -69.14984) (xy 60.405004 -69.187786)
			(xy 60.460766 -69.232255) (xy 60.511199 -69.282688) (xy 60.555668 -69.33845) (xy 60.593614 -69.398841)
			(xy 60.624559 -69.4631) (xy 60.648116 -69.53042) (xy 60.663986 -69.599955) (xy 60.671972 -69.670829)
			(xy 60.672472 -69.70649) (xy 60.671972 -69.742151) (xy 61.30594 -69.742151) (xy 61.30594 -69.670829)
			(xy 61.313926 -69.599955) (xy 61.329796 -69.53042) (xy 61.353353 -69.4631) (xy 61.384298 -69.398841)
			(xy 61.422244 -69.33845) (xy 61.466713 -69.282688) (xy 61.517146 -69.232255) (xy 61.572908 -69.187786)
			(xy 61.633299 -69.14984) (xy 61.697558 -69.118895) (xy 61.764878 -69.095338) (xy 61.834413 -69.079468)
			(xy 61.905287 -69.071482) (xy 61.976609 -69.071482) (xy 62.047483 -69.079468) (xy 62.117018 -69.095338)
			(xy 62.184338 -69.118895) (xy 62.248597 -69.14984) (xy 62.308988 -69.187786) (xy 62.36475 -69.232255)
			(xy 62.415183 -69.282688) (xy 62.459652 -69.33845) (xy 62.497598 -69.398841) (xy 62.528543 -69.4631)
			(xy 62.5521 -69.53042) (xy 62.56797 -69.599955) (xy 62.575956 -69.670829) (xy 62.576456 -69.70649)
			(xy 62.575956 -69.742151) (xy 62.56797 -69.813025) (xy 62.5521 -69.88256) (xy 62.528543 -69.94988)
			(xy 62.497598 -70.014139) (xy 62.459652 -70.07453) (xy 62.415183 -70.130292) (xy 62.36475 -70.180725)
			(xy 62.308988 -70.225194) (xy 62.248597 -70.26314) (xy 62.184338 -70.294085) (xy 62.117018 -70.317642)
			(xy 62.047483 -70.333512) (xy 61.976609 -70.341498) (xy 61.905287 -70.341498) (xy 61.834413 -70.333512)
			(xy 61.764878 -70.317642) (xy 61.697558 -70.294085) (xy 61.633299 -70.26314) (xy 61.572908 -70.225194)
			(xy 61.517146 -70.180725) (xy 61.466713 -70.130292) (xy 61.422244 -70.07453) (xy 61.384298 -70.014139)
			(xy 61.353353 -69.94988) (xy 61.329796 -69.88256) (xy 61.313926 -69.813025) (xy 61.30594 -69.742151)
			(xy 60.671972 -69.742151) (xy 60.663986 -69.813025) (xy 60.648116 -69.88256) (xy 60.624559 -69.94988)
			(xy 60.593614 -70.014139) (xy 60.555668 -70.07453) (xy 60.511199 -70.130292) (xy 60.460766 -70.180725)
			(xy 60.405004 -70.225194) (xy 60.344613 -70.26314) (xy 60.280354 -70.294085) (xy 60.213034 -70.317642)
			(xy 60.143499 -70.333512) (xy 60.072625 -70.341498) (xy 60.001303 -70.341498) (xy 59.930429 -70.333512)
			(xy 59.860894 -70.317642) (xy 59.793574 -70.294085) (xy 59.729315 -70.26314) (xy 59.668924 -70.225194)
			(xy 59.613162 -70.180725) (xy 59.562729 -70.130292) (xy 59.51826 -70.07453) (xy 59.480314 -70.014139)
			(xy 59.449369 -69.94988) (xy 59.425812 -69.88256) (xy 59.409942 -69.813025) (xy 59.401956 -69.742151)
			(xy 58.43093 -69.742151) (xy 58.422944 -69.813025) (xy 58.407074 -69.88256) (xy 58.383517 -69.94988)
			(xy 58.352572 -70.014139) (xy 58.314626 -70.07453) (xy 58.270157 -70.130292) (xy 58.219724 -70.180725)
			(xy 58.163962 -70.225194) (xy 58.103571 -70.26314) (xy 58.039312 -70.294085) (xy 57.971992 -70.317642)
			(xy 57.902457 -70.333512) (xy 57.831583 -70.341498) (xy 57.760261 -70.341498) (xy 57.689387 -70.333512)
			(xy 57.619852 -70.317642) (xy 57.552532 -70.294085) (xy 57.488273 -70.26314) (xy 57.427882 -70.225194)
			(xy 57.37212 -70.180725) (xy 57.321687 -70.130292) (xy 57.277218 -70.07453) (xy 57.239272 -70.014139)
			(xy 57.208327 -69.94988) (xy 57.18477 -69.88256) (xy 57.1689 -69.813025) (xy 57.160914 -69.742151)
			(xy 44.919132 -69.742151) (xy 44.932617 -69.755636) (xy 44.977086 -69.811398) (xy 45.015032 -69.871789)
			(xy 45.045977 -69.936048) (xy 45.069534 -70.003368) (xy 45.085404 -70.072903) (xy 45.09339 -70.143777)
			(xy 45.09389 -70.179438) (xy 45.09339 -70.215099) (xy 45.085404 -70.285973) (xy 45.069534 -70.355508)
			(xy 45.045977 -70.422828) (xy 45.015032 -70.487087) (xy 44.977086 -70.547478) (xy 44.932617 -70.60324)
			(xy 44.882184 -70.653673) (xy 44.826422 -70.698142) (xy 44.766031 -70.736088) (xy 44.701772 -70.767033)
			(xy 44.634452 -70.79059) (xy 44.564917 -70.80646) (xy 44.494043 -70.814446) (xy 44.422721 -70.814446)
			(xy 44.351847 -70.80646) (xy 44.282312 -70.79059) (xy 44.214992 -70.767033) (xy 44.150733 -70.736088)
			(xy 44.090342 -70.698142) (xy 44.03458 -70.653673) (xy 43.984147 -70.60324) (xy 43.939678 -70.547478)
			(xy 43.901732 -70.487087) (xy 43.870787 -70.422828) (xy 43.84723 -70.355508) (xy 43.83136 -70.285973)
			(xy 43.823374 -70.215099) (xy 29.24048 -70.215099) (xy 29.24048 -71.890229) (xy 43.823374 -71.890229)
			(xy 43.823374 -71.818907) (xy 43.83136 -71.748033) (xy 43.84723 -71.678498) (xy 43.870787 -71.611178)
			(xy 43.901732 -71.546919) (xy 43.939678 -71.486528) (xy 43.984147 -71.430766) (xy 44.03458 -71.380333)
			(xy 44.090342 -71.335864) (xy 44.150733 -71.297918) (xy 44.214992 -71.266973) (xy 44.282312 -71.243416)
			(xy 44.351847 -71.227546) (xy 44.422721 -71.21956) (xy 44.494043 -71.21956) (xy 44.564917 -71.227546)
			(xy 44.634452 -71.243416) (xy 44.701772 -71.266973) (xy 44.766031 -71.297918) (xy 44.826422 -71.335864)
			(xy 44.882184 -71.380333) (xy 44.932617 -71.430766) (xy 44.977086 -71.486528) (xy 45.015032 -71.546919)
			(xy 45.045977 -71.611178) (xy 45.069534 -71.678498) (xy 45.085404 -71.748033) (xy 45.089377 -71.783295)
			(xy 57.160914 -71.783295) (xy 57.160914 -71.711973) (xy 57.1689 -71.641099) (xy 57.18477 -71.571564)
			(xy 57.208327 -71.504244) (xy 57.239272 -71.439985) (xy 57.277218 -71.379594) (xy 57.321687 -71.323832)
			(xy 57.37212 -71.273399) (xy 57.427882 -71.22893) (xy 57.488273 -71.190984) (xy 57.552532 -71.160039)
			(xy 57.619852 -71.136482) (xy 57.689387 -71.120612) (xy 57.760261 -71.112626) (xy 57.831583 -71.112626)
			(xy 57.902457 -71.120612) (xy 57.971992 -71.136482) (xy 58.039312 -71.160039) (xy 58.103571 -71.190984)
			(xy 58.163962 -71.22893) (xy 58.219724 -71.273399) (xy 58.270157 -71.323832) (xy 58.314626 -71.379594)
			(xy 58.352572 -71.439985) (xy 58.383517 -71.504244) (xy 58.407074 -71.571564) (xy 58.422944 -71.641099)
			(xy 58.43093 -71.711973) (xy 58.43143 -71.747634) (xy 58.43093 -71.783295) (xy 59.401956 -71.783295)
			(xy 59.401956 -71.711973) (xy 59.409942 -71.641099) (xy 59.425812 -71.571564) (xy 59.449369 -71.504244)
			(xy 59.480314 -71.439985) (xy 59.51826 -71.379594) (xy 59.562729 -71.323832) (xy 59.613162 -71.273399)
			(xy 59.668924 -71.22893) (xy 59.729315 -71.190984) (xy 59.793574 -71.160039) (xy 59.860894 -71.136482)
			(xy 59.930429 -71.120612) (xy 60.001303 -71.112626) (xy 60.072625 -71.112626) (xy 60.143499 -71.120612)
			(xy 60.213034 -71.136482) (xy 60.280354 -71.160039) (xy 60.344613 -71.190984) (xy 60.405004 -71.22893)
			(xy 60.460766 -71.273399) (xy 60.511199 -71.323832) (xy 60.555668 -71.379594) (xy 60.593614 -71.439985)
			(xy 60.624559 -71.504244) (xy 60.648116 -71.571564) (xy 60.663986 -71.641099) (xy 60.671972 -71.711973)
			(xy 60.672472 -71.747634) (xy 60.671972 -71.783295) (xy 61.30594 -71.783295) (xy 61.30594 -71.711973)
			(xy 61.313926 -71.641099) (xy 61.329796 -71.571564) (xy 61.353353 -71.504244) (xy 61.384298 -71.439985)
			(xy 61.422244 -71.379594) (xy 61.466713 -71.323832) (xy 61.517146 -71.273399) (xy 61.572908 -71.22893)
			(xy 61.633299 -71.190984) (xy 61.697558 -71.160039) (xy 61.764878 -71.136482) (xy 61.834413 -71.120612)
			(xy 61.905287 -71.112626) (xy 61.976609 -71.112626) (xy 62.047483 -71.120612) (xy 62.117018 -71.136482)
			(xy 62.184338 -71.160039) (xy 62.248597 -71.190984) (xy 62.308988 -71.22893) (xy 62.36475 -71.273399)
			(xy 62.415183 -71.323832) (xy 62.459652 -71.379594) (xy 62.497598 -71.439985) (xy 62.528543 -71.504244)
			(xy 62.5521 -71.571564) (xy 62.56797 -71.641099) (xy 62.575956 -71.711973) (xy 62.576456 -71.747634)
			(xy 62.575956 -71.783295) (xy 62.56797 -71.854169) (xy 62.5521 -71.923704) (xy 62.528543 -71.991024)
			(xy 62.497598 -72.055283) (xy 62.459652 -72.115674) (xy 62.415183 -72.171436) (xy 62.36475 -72.221869)
			(xy 62.308988 -72.266338) (xy 62.248597 -72.304284) (xy 62.184338 -72.335229) (xy 62.117018 -72.358786)
			(xy 62.047483 -72.374656) (xy 61.976609 -72.382642) (xy 61.905287 -72.382642) (xy 61.834413 -72.374656)
			(xy 61.764878 -72.358786) (xy 61.697558 -72.335229) (xy 61.633299 -72.304284) (xy 61.572908 -72.266338)
			(xy 61.517146 -72.221869) (xy 61.466713 -72.171436) (xy 61.422244 -72.115674) (xy 61.384298 -72.055283)
			(xy 61.353353 -71.991024) (xy 61.329796 -71.923704) (xy 61.313926 -71.854169) (xy 61.30594 -71.783295)
			(xy 60.671972 -71.783295) (xy 60.663986 -71.854169) (xy 60.648116 -71.923704) (xy 60.624559 -71.991024)
			(xy 60.593614 -72.055283) (xy 60.555668 -72.115674) (xy 60.511199 -72.171436) (xy 60.460766 -72.221869)
			(xy 60.405004 -72.266338) (xy 60.344613 -72.304284) (xy 60.280354 -72.335229) (xy 60.213034 -72.358786)
			(xy 60.143499 -72.374656) (xy 60.072625 -72.382642) (xy 60.001303 -72.382642) (xy 59.930429 -72.374656)
			(xy 59.860894 -72.358786) (xy 59.793574 -72.335229) (xy 59.729315 -72.304284) (xy 59.668924 -72.266338)
			(xy 59.613162 -72.221869) (xy 59.562729 -72.171436) (xy 59.51826 -72.115674) (xy 59.480314 -72.055283)
			(xy 59.449369 -71.991024) (xy 59.425812 -71.923704) (xy 59.409942 -71.854169) (xy 59.401956 -71.783295)
			(xy 58.43093 -71.783295) (xy 58.422944 -71.854169) (xy 58.407074 -71.923704) (xy 58.383517 -71.991024)
			(xy 58.352572 -72.055283) (xy 58.314626 -72.115674) (xy 58.270157 -72.171436) (xy 58.219724 -72.221869)
			(xy 58.163962 -72.266338) (xy 58.103571 -72.304284) (xy 58.039312 -72.335229) (xy 57.971992 -72.358786)
			(xy 57.902457 -72.374656) (xy 57.831583 -72.382642) (xy 57.760261 -72.382642) (xy 57.689387 -72.374656)
			(xy 57.619852 -72.358786) (xy 57.552532 -72.335229) (xy 57.488273 -72.304284) (xy 57.427882 -72.266338)
			(xy 57.37212 -72.221869) (xy 57.321687 -72.171436) (xy 57.277218 -72.115674) (xy 57.239272 -72.055283)
			(xy 57.208327 -71.991024) (xy 57.18477 -71.923704) (xy 57.1689 -71.854169) (xy 57.160914 -71.783295)
			(xy 45.089377 -71.783295) (xy 45.09339 -71.818907) (xy 45.09389 -71.854568) (xy 45.09339 -71.890229)
			(xy 45.085404 -71.961103) (xy 45.069534 -72.030638) (xy 45.045977 -72.097958) (xy 45.015032 -72.162217)
			(xy 44.977086 -72.222608) (xy 44.932617 -72.27837) (xy 44.882184 -72.328803) (xy 44.826422 -72.373272)
			(xy 44.766031 -72.411218) (xy 44.701772 -72.442163) (xy 44.634452 -72.46572) (xy 44.564917 -72.48159)
			(xy 44.494043 -72.489576) (xy 44.422721 -72.489576) (xy 44.351847 -72.48159) (xy 44.282312 -72.46572)
			(xy 44.214992 -72.442163) (xy 44.150733 -72.411218) (xy 44.090342 -72.373272) (xy 44.03458 -72.328803)
			(xy 43.984147 -72.27837) (xy 43.939678 -72.222608) (xy 43.901732 -72.162217) (xy 43.870787 -72.097958)
			(xy 43.84723 -72.030638) (xy 43.83136 -71.961103) (xy 43.823374 -71.890229) (xy 29.24048 -71.890229)
			(xy 29.24048 -73.901401) (xy 43.77994 -73.901401) (xy 43.77994 -73.830079) (xy 43.787926 -73.759205)
			(xy 43.803796 -73.68967) (xy 43.827353 -73.62235) (xy 43.858298 -73.558091) (xy 43.896244 -73.4977)
			(xy 43.940713 -73.441938) (xy 43.991146 -73.391505) (xy 44.046908 -73.347036) (xy 44.107299 -73.30909)
			(xy 44.171558 -73.278145) (xy 44.238878 -73.254588) (xy 44.308413 -73.238718) (xy 44.379287 -73.230732)
			(xy 44.450609 -73.230732) (xy 44.521483 -73.238718) (xy 44.591018 -73.254588) (xy 44.658338 -73.278145)
			(xy 44.722597 -73.30909) (xy 44.782988 -73.347036) (xy 44.83875 -73.391505) (xy 44.889183 -73.441938)
			(xy 44.933652 -73.4977) (xy 44.971598 -73.558091) (xy 45.002543 -73.62235) (xy 45.0261 -73.68967)
			(xy 45.026888 -73.693121) (xy 57.160914 -73.693121) (xy 57.160914 -73.621799) (xy 57.1689 -73.550925)
			(xy 57.18477 -73.48139) (xy 57.208327 -73.41407) (xy 57.239272 -73.349811) (xy 57.277218 -73.28942)
			(xy 57.321687 -73.233658) (xy 57.37212 -73.183225) (xy 57.427882 -73.138756) (xy 57.488273 -73.10081)
			(xy 57.552532 -73.069865) (xy 57.619852 -73.046308) (xy 57.689387 -73.030438) (xy 57.760261 -73.022452)
			(xy 57.831583 -73.022452) (xy 57.902457 -73.030438) (xy 57.971992 -73.046308) (xy 58.039312 -73.069865)
			(xy 58.103571 -73.10081) (xy 58.163962 -73.138756) (xy 58.219724 -73.183225) (xy 58.270157 -73.233658)
			(xy 58.314626 -73.28942) (xy 58.352572 -73.349811) (xy 58.383517 -73.41407) (xy 58.407074 -73.48139)
			(xy 58.422944 -73.550925) (xy 58.43093 -73.621799) (xy 58.43143 -73.65746) (xy 58.43093 -73.693121)
			(xy 59.401956 -73.693121) (xy 59.401956 -73.621799) (xy 59.409942 -73.550925) (xy 59.425812 -73.48139)
			(xy 59.449369 -73.41407) (xy 59.480314 -73.349811) (xy 59.51826 -73.28942) (xy 59.562729 -73.233658)
			(xy 59.613162 -73.183225) (xy 59.668924 -73.138756) (xy 59.729315 -73.10081) (xy 59.793574 -73.069865)
			(xy 59.860894 -73.046308) (xy 59.930429 -73.030438) (xy 60.001303 -73.022452) (xy 60.072625 -73.022452)
			(xy 60.143499 -73.030438) (xy 60.213034 -73.046308) (xy 60.280354 -73.069865) (xy 60.344613 -73.10081)
			(xy 60.405004 -73.138756) (xy 60.460766 -73.183225) (xy 60.511199 -73.233658) (xy 60.555668 -73.28942)
			(xy 60.593614 -73.349811) (xy 60.624559 -73.41407) (xy 60.648116 -73.48139) (xy 60.663986 -73.550925)
			(xy 60.671972 -73.621799) (xy 60.672472 -73.65746) (xy 60.671972 -73.693121) (xy 61.30594 -73.693121)
			(xy 61.30594 -73.621799) (xy 61.313926 -73.550925) (xy 61.329796 -73.48139) (xy 61.353353 -73.41407)
			(xy 61.384298 -73.349811) (xy 61.422244 -73.28942) (xy 61.466713 -73.233658) (xy 61.517146 -73.183225)
			(xy 61.572908 -73.138756) (xy 61.633299 -73.10081) (xy 61.697558 -73.069865) (xy 61.764878 -73.046308)
			(xy 61.834413 -73.030438) (xy 61.905287 -73.022452) (xy 61.976609 -73.022452) (xy 62.047483 -73.030438)
			(xy 62.117018 -73.046308) (xy 62.184338 -73.069865) (xy 62.248597 -73.10081) (xy 62.308988 -73.138756)
			(xy 62.36475 -73.183225) (xy 62.415183 -73.233658) (xy 62.459652 -73.28942) (xy 62.497598 -73.349811)
			(xy 62.528543 -73.41407) (xy 62.5521 -73.48139) (xy 62.56797 -73.550925) (xy 62.575956 -73.621799)
			(xy 62.576456 -73.65746) (xy 62.575956 -73.693121) (xy 62.56797 -73.763995) (xy 62.5521 -73.83353)
			(xy 62.528543 -73.90085) (xy 62.497598 -73.965109) (xy 62.459652 -74.0255) (xy 62.415183 -74.081262)
			(xy 62.36475 -74.131695) (xy 62.308988 -74.176164) (xy 62.248597 -74.21411) (xy 62.184338 -74.245055)
			(xy 62.117018 -74.268612) (xy 62.047483 -74.284482) (xy 61.976609 -74.292468) (xy 61.905287 -74.292468)
			(xy 61.834413 -74.284482) (xy 61.764878 -74.268612) (xy 61.697558 -74.245055) (xy 61.633299 -74.21411)
			(xy 61.572908 -74.176164) (xy 61.517146 -74.131695) (xy 61.466713 -74.081262) (xy 61.422244 -74.0255)
			(xy 61.384298 -73.965109) (xy 61.353353 -73.90085) (xy 61.329796 -73.83353) (xy 61.313926 -73.763995)
			(xy 61.30594 -73.693121) (xy 60.671972 -73.693121) (xy 60.663986 -73.763995) (xy 60.648116 -73.83353)
			(xy 60.624559 -73.90085) (xy 60.593614 -73.965109) (xy 60.555668 -74.0255) (xy 60.511199 -74.081262)
			(xy 60.460766 -74.131695) (xy 60.405004 -74.176164) (xy 60.344613 -74.21411) (xy 60.280354 -74.245055)
			(xy 60.213034 -74.268612) (xy 60.143499 -74.284482) (xy 60.072625 -74.292468) (xy 60.001303 -74.292468)
			(xy 59.930429 -74.284482) (xy 59.860894 -74.268612) (xy 59.793574 -74.245055) (xy 59.729315 -74.21411)
			(xy 59.668924 -74.176164) (xy 59.613162 -74.131695) (xy 59.562729 -74.081262) (xy 59.51826 -74.0255)
			(xy 59.480314 -73.965109) (xy 59.449369 -73.90085) (xy 59.425812 -73.83353) (xy 59.409942 -73.763995)
			(xy 59.401956 -73.693121) (xy 58.43093 -73.693121) (xy 58.422944 -73.763995) (xy 58.407074 -73.83353)
			(xy 58.383517 -73.90085) (xy 58.352572 -73.965109) (xy 58.314626 -74.0255) (xy 58.270157 -74.081262)
			(xy 58.219724 -74.131695) (xy 58.163962 -74.176164) (xy 58.103571 -74.21411) (xy 58.039312 -74.245055)
			(xy 57.971992 -74.268612) (xy 57.902457 -74.284482) (xy 57.831583 -74.292468) (xy 57.760261 -74.292468)
			(xy 57.689387 -74.284482) (xy 57.619852 -74.268612) (xy 57.552532 -74.245055) (xy 57.488273 -74.21411)
			(xy 57.427882 -74.176164) (xy 57.37212 -74.131695) (xy 57.321687 -74.081262) (xy 57.277218 -74.0255)
			(xy 57.239272 -73.965109) (xy 57.208327 -73.90085) (xy 57.18477 -73.83353) (xy 57.1689 -73.763995)
			(xy 57.160914 -73.693121) (xy 45.026888 -73.693121) (xy 45.04197 -73.759205) (xy 45.049956 -73.830079)
			(xy 45.050456 -73.86574) (xy 45.049956 -73.901401) (xy 45.04197 -73.972275) (xy 45.0261 -74.04181)
			(xy 45.002543 -74.10913) (xy 44.971598 -74.173389) (xy 44.933652 -74.23378) (xy 44.889183 -74.289542)
			(xy 44.83875 -74.339975) (xy 44.782988 -74.384444) (xy 44.722597 -74.42239) (xy 44.658338 -74.453335)
			(xy 44.591018 -74.476892) (xy 44.521483 -74.492762) (xy 44.450609 -74.500748) (xy 44.379287 -74.500748)
			(xy 44.308413 -74.492762) (xy 44.238878 -74.476892) (xy 44.171558 -74.453335) (xy 44.107299 -74.42239)
			(xy 44.046908 -74.384444) (xy 43.991146 -74.339975) (xy 43.940713 -74.289542) (xy 43.896244 -74.23378)
			(xy 43.858298 -74.173389) (xy 43.827353 -74.10913) (xy 43.803796 -74.04181) (xy 43.787926 -73.972275)
			(xy 43.77994 -73.901401) (xy 29.24048 -73.901401) (xy 29.24048 -75.791923) (xy 43.77994 -75.791923)
			(xy 43.77994 -75.720601) (xy 43.787926 -75.649727) (xy 43.803796 -75.580192) (xy 43.827353 -75.512872)
			(xy 43.858298 -75.448613) (xy 43.896244 -75.388222) (xy 43.940713 -75.33246) (xy 43.991146 -75.282027)
			(xy 44.046908 -75.237558) (xy 44.107299 -75.199612) (xy 44.171558 -75.168667) (xy 44.238878 -75.14511)
			(xy 44.308413 -75.12924) (xy 44.379287 -75.121254) (xy 44.450609 -75.121254) (xy 44.521483 -75.12924)
			(xy 44.591018 -75.14511) (xy 44.658338 -75.168667) (xy 44.722597 -75.199612) (xy 44.782988 -75.237558)
			(xy 44.83875 -75.282027) (xy 44.889183 -75.33246) (xy 44.933652 -75.388222) (xy 44.971598 -75.448613)
			(xy 45.002543 -75.512872) (xy 45.0261 -75.580192) (xy 45.04197 -75.649727) (xy 45.049956 -75.720601)
			(xy 45.050456 -75.756262) (xy 45.049956 -75.791923) (xy 45.04197 -75.862797) (xy 45.0261 -75.932332)
			(xy 45.002543 -75.999652) (xy 44.971598 -76.063911) (xy 44.933652 -76.124302) (xy 44.889183 -76.180064)
			(xy 44.83875 -76.230497) (xy 44.782988 -76.274966) (xy 44.722597 -76.312912) (xy 44.658338 -76.343857)
			(xy 44.591018 -76.367414) (xy 44.521483 -76.383284) (xy 44.450609 -76.39127) (xy 44.379287 -76.39127)
			(xy 44.308413 -76.383284) (xy 44.238878 -76.367414) (xy 44.171558 -76.343857) (xy 44.107299 -76.312912)
			(xy 44.046908 -76.274966) (xy 43.991146 -76.230497) (xy 43.940713 -76.180064) (xy 43.896244 -76.124302)
			(xy 43.858298 -76.063911) (xy 43.827353 -75.999652) (xy 43.803796 -75.932332) (xy 43.787926 -75.862797)
			(xy 43.77994 -75.791923) (xy 29.24048 -75.791923) (xy 29.24048 -77.833067) (xy 43.77994 -77.833067)
			(xy 43.77994 -77.761745) (xy 43.787926 -77.690871) (xy 43.803796 -77.621336) (xy 43.827353 -77.554016)
			(xy 43.858298 -77.489757) (xy 43.896244 -77.429366) (xy 43.940713 -77.373604) (xy 43.991146 -77.323171)
			(xy 44.046908 -77.278702) (xy 44.107299 -77.240756) (xy 44.171558 -77.209811) (xy 44.238878 -77.186254)
			(xy 44.308413 -77.170384) (xy 44.379287 -77.162398) (xy 44.450609 -77.162398) (xy 44.521483 -77.170384)
			(xy 44.591018 -77.186254) (xy 44.658338 -77.209811) (xy 44.722597 -77.240756) (xy 44.782988 -77.278702)
			(xy 44.83875 -77.323171) (xy 44.889183 -77.373604) (xy 44.933652 -77.429366) (xy 44.971598 -77.489757)
			(xy 45.002543 -77.554016) (xy 45.0261 -77.621336) (xy 45.04197 -77.690871) (xy 45.049956 -77.761745)
			(xy 45.050456 -77.797406) (xy 45.049956 -77.833067) (xy 45.04197 -77.903941) (xy 45.0261 -77.973476)
			(xy 45.002543 -78.040796) (xy 44.971598 -78.105055) (xy 44.933652 -78.165446) (xy 44.889183 -78.221208)
			(xy 44.83875 -78.271641) (xy 44.803099 -78.300072) (xy 74.398892 -78.300072) (xy 74.402909 -78.130007)
			(xy 74.414954 -77.960322) (xy 74.434998 -77.791394) (xy 74.462998 -77.623602) (xy 74.49889 -77.457319)
			(xy 74.542595 -77.292917) (xy 74.594015 -77.130762) (xy 74.653035 -76.971216) (xy 74.719524 -76.814636)
			(xy 74.793333 -76.66137) (xy 74.874297 -76.511761) (xy 74.962237 -76.366142) (xy 75.056955 -76.224838)
			(xy 75.15824 -76.088165) (xy 75.265867 -75.956428) (xy 75.379595 -75.82992) (xy 75.49917 -75.708924)
			(xy 75.624325 -75.59371) (xy 75.754782 -75.484535) (xy 75.89025 -75.381643) (xy 76.030425 -75.285263)
			(xy 76.174995 -75.19561) (xy 76.323638 -75.112884) (xy 76.476021 -75.03727) (xy 76.631806 -74.968936)
			(xy 76.790643 -74.908036) (xy 76.952179 -74.854705) (xy 77.116054 -74.809061) (xy 77.281901 -74.771208)
			(xy 77.449351 -74.741229) (xy 77.61803 -74.719191) (xy 77.787561 -74.705143) (xy 77.957567 -74.699117)
			(xy 78.127667 -74.701126) (xy 78.297483 -74.711165) (xy 78.466636 -74.729213) (xy 78.634747 -74.755229)
			(xy 78.801442 -74.789155) (xy 78.966349 -74.830915) (xy 79.1291 -74.880417) (xy 79.289331 -74.937548)
			(xy 79.446686 -75.002183) (xy 79.600813 -75.074177) (xy 79.751368 -75.153369) (xy 79.898016 -75.239582)
			(xy 80.040428 -75.332625) (xy 80.178288 -75.432289) (xy 80.311287 -75.538352) (xy 80.439129 -75.650578)
			(xy 80.561528 -75.768716) (xy 80.678212 -75.892502) (xy 80.788921 -76.021661) (xy 80.893406 -76.155904)
			(xy 80.991435 -76.294931) (xy 81.082789 -76.438432) (xy 81.167265 -76.586087) (xy 81.244673 -76.737567)
			(xy 81.314841 -76.892534) (xy 81.377613 -77.050641) (xy 81.432849 -77.211536) (xy 81.480424 -77.37486)
			(xy 81.520234 -77.540249) (xy 81.552189 -77.707333) (xy 81.576217 -77.87574) (xy 81.592266 -78.045093)
			(xy 81.6003 -78.215016) (xy 81.600802 -78.300072) (xy 81.6003 -78.385128) (xy 81.592266 -78.555051)
			(xy 81.576217 -78.724404) (xy 81.552189 -78.892811) (xy 81.520234 -79.059895) (xy 81.480424 -79.225284)
			(xy 81.432849 -79.388608) (xy 81.377613 -79.549503) (xy 81.314841 -79.70761) (xy 81.244673 -79.862577)
			(xy 81.167265 -80.014057) (xy 81.082789 -80.161712) (xy 80.991435 -80.305213) (xy 80.893406 -80.44424)
			(xy 80.788921 -80.578483) (xy 80.678212 -80.707642) (xy 80.561528 -80.831428) (xy 80.439129 -80.949566)
			(xy 80.311287 -81.061792) (xy 80.178288 -81.167855) (xy 80.040428 -81.267519) (xy 79.898016 -81.360562)
			(xy 79.751368 -81.446775) (xy 79.600813 -81.525967) (xy 79.446686 -81.597961) (xy 79.289331 -81.662596)
			(xy 79.1291 -81.719727) (xy 78.966349 -81.769229) (xy 78.801442 -81.810989) (xy 78.634747 -81.844915)
			(xy 78.466636 -81.870931) (xy 78.297483 -81.888979) (xy 78.127667 -81.899018) (xy 77.957567 -81.901027)
			(xy 77.787561 -81.895001) (xy 77.61803 -81.880953) (xy 77.449351 -81.858915) (xy 77.281901 -81.828936)
			(xy 77.116054 -81.791083) (xy 76.952179 -81.745439) (xy 76.790643 -81.692108) (xy 76.631806 -81.631208)
			(xy 76.476021 -81.562874) (xy 76.323638 -81.48726) (xy 76.174995 -81.404534) (xy 76.030425 -81.314881)
			(xy 75.89025 -81.218501) (xy 75.754782 -81.115609) (xy 75.624325 -81.006434) (xy 75.49917 -80.89122)
			(xy 75.379595 -80.770224) (xy 75.265867 -80.643716) (xy 75.15824 -80.511979) (xy 75.056955 -80.375306)
			(xy 74.962237 -80.234002) (xy 74.874297 -80.088383) (xy 74.793333 -79.938774) (xy 74.719524 -79.785508)
			(xy 74.653035 -79.628928) (xy 74.594015 -79.469382) (xy 74.542595 -79.307227) (xy 74.49889 -79.142825)
			(xy 74.462998 -78.976542) (xy 74.434998 -78.80875) (xy 74.414954 -78.639822) (xy 74.402909 -78.470137)
			(xy 74.398892 -78.300072) (xy 44.803099 -78.300072) (xy 44.782988 -78.31611) (xy 44.722597 -78.354056)
			(xy 44.658338 -78.385001) (xy 44.591018 -78.408558) (xy 44.521483 -78.424428) (xy 44.450609 -78.432414)
			(xy 44.379287 -78.432414) (xy 44.308413 -78.424428) (xy 44.238878 -78.408558) (xy 44.171558 -78.385001)
			(xy 44.107299 -78.354056) (xy 44.046908 -78.31611) (xy 43.991146 -78.271641) (xy 43.940713 -78.221208)
			(xy 43.896244 -78.165446) (xy 43.858298 -78.105055) (xy 43.827353 -78.040796) (xy 43.803796 -77.973476)
			(xy 43.787926 -77.903941) (xy 43.77994 -77.833067) (xy 29.24048 -77.833067) (xy 29.24048 -79.742893)
			(xy 43.77994 -79.742893) (xy 43.77994 -79.671571) (xy 43.787926 -79.600697) (xy 43.803796 -79.531162)
			(xy 43.827353 -79.463842) (xy 43.858298 -79.399583) (xy 43.896244 -79.339192) (xy 43.940713 -79.28343)
			(xy 43.991146 -79.232997) (xy 44.046908 -79.188528) (xy 44.107299 -79.150582) (xy 44.171558 -79.119637)
			(xy 44.238878 -79.09608) (xy 44.308413 -79.08021) (xy 44.379287 -79.072224) (xy 44.450609 -79.072224)
			(xy 44.521483 -79.08021) (xy 44.591018 -79.09608) (xy 44.658338 -79.119637) (xy 44.722597 -79.150582)
			(xy 44.782988 -79.188528) (xy 44.83875 -79.232997) (xy 44.889183 -79.28343) (xy 44.933652 -79.339192)
			(xy 44.971598 -79.399583) (xy 45.002543 -79.463842) (xy 45.0261 -79.531162) (xy 45.04197 -79.600697)
			(xy 45.049956 -79.671571) (xy 45.050456 -79.707232) (xy 45.049956 -79.742893) (xy 45.04197 -79.813767)
			(xy 45.0261 -79.883302) (xy 45.002543 -79.950622) (xy 44.971598 -80.014881) (xy 44.933652 -80.075272)
			(xy 44.889183 -80.131034) (xy 44.83875 -80.181467) (xy 44.782988 -80.225936) (xy 44.722597 -80.263882)
			(xy 44.658338 -80.294827) (xy 44.591018 -80.318384) (xy 44.521483 -80.334254) (xy 44.450609 -80.34224)
			(xy 44.379287 -80.34224) (xy 44.308413 -80.334254) (xy 44.238878 -80.318384) (xy 44.171558 -80.294827)
			(xy 44.107299 -80.263882) (xy 44.046908 -80.225936) (xy 43.991146 -80.181467) (xy 43.940713 -80.131034)
			(xy 43.896244 -80.075272) (xy 43.858298 -80.014881) (xy 43.827353 -79.950622) (xy 43.803796 -79.883302)
			(xy 43.787926 -79.813767) (xy 43.77994 -79.742893) (xy 29.24048 -79.742893) (xy 29.24048 -84.314199)
			(xy 47.642008 -84.314199) (xy 47.642008 -84.233089) (xy 47.649958 -84.15237) (xy 47.665781 -84.072819)
			(xy 47.689326 -83.995203) (xy 47.720365 -83.920267) (xy 47.7586 -83.848735) (xy 47.803662 -83.781295)
			(xy 47.855117 -83.718596) (xy 47.91247 -83.661243) (xy 47.975169 -83.609788) (xy 48.042609 -83.564726)
			(xy 48.114141 -83.526491) (xy 48.189077 -83.495452) (xy 48.266693 -83.471907) (xy 48.346244 -83.456084)
			(xy 48.426963 -83.448134) (xy 48.508073 -83.448134) (xy 48.588792 -83.456084) (xy 48.668343 -83.471907)
			(xy 48.745959 -83.495452) (xy 48.820895 -83.526491) (xy 48.892427 -83.564726) (xy 48.959867 -83.609788)
			(xy 49.022566 -83.661243) (xy 49.079919 -83.718596) (xy 49.131374 -83.781295) (xy 49.176436 -83.848735)
			(xy 49.214671 -83.920267) (xy 49.24571 -83.995203) (xy 49.269255 -84.072819) (xy 49.285078 -84.15237)
			(xy 49.293028 -84.233089) (xy 49.293526 -84.273644) (xy 49.293028 -84.314199) (xy 49.285078 -84.394918)
			(xy 49.269255 -84.474469) (xy 49.24571 -84.552085) (xy 49.214671 -84.627021) (xy 49.176436 -84.698553)
			(xy 49.131374 -84.765993) (xy 49.079919 -84.828692) (xy 49.022566 -84.886045) (xy 48.959867 -84.9375)
			(xy 48.892427 -84.982562) (xy 48.820895 -85.020797) (xy 48.745959 -85.051836) (xy 48.668343 -85.075381)
			(xy 48.588792 -85.091204) (xy 48.508073 -85.099154) (xy 48.426963 -85.099154) (xy 48.346244 -85.091204)
			(xy 48.266693 -85.075381) (xy 48.189077 -85.051836) (xy 48.114141 -85.020797) (xy 48.042609 -84.982562)
			(xy 47.975169 -84.9375) (xy 47.91247 -84.886045) (xy 47.855117 -84.828692) (xy 47.803662 -84.765993)
			(xy 47.7586 -84.698553) (xy 47.720365 -84.627021) (xy 47.689326 -84.552085) (xy 47.665781 -84.474469)
			(xy 47.649958 -84.394918) (xy 47.642008 -84.314199) (xy 29.24048 -84.314199) (xy 29.24048 -86.745318)
			(xy 70.884288 -86.745318) (xy 70.884288 -85.772752) (xy 70.884901 -85.740595) (xy 70.893031 -85.676796)
			(xy 70.909142 -85.614532) (xy 70.932978 -85.554798) (xy 70.964157 -85.498546) (xy 71.002181 -85.446676)
			(xy 71.046444 -85.400016) (xy 71.096238 -85.35931) (xy 71.150769 -85.32521) (xy 71.209164 -85.29826)
			(xy 71.270493 -85.27889) (xy 71.333774 -85.267409) (xy 71.397998 -85.264001) (xy 71.46214 -85.26872)
			(xy 71.525174 -85.281491) (xy 71.586093 -85.30211) (xy 71.643926 -85.330248) (xy 71.697749 -85.365455)
			(xy 71.746701 -85.407169) (xy 71.768716 -85.430614) (xy 71.784958 -85.447603) (xy 71.822476 -85.475901)
			(xy 71.864552 -85.496831) (xy 71.909755 -85.509681) (xy 71.956549 -85.514013) (xy 72.003343 -85.509681)
			(xy 72.048546 -85.496831) (xy 72.090622 -85.475901) (xy 72.12814 -85.447603) (xy 72.144382 -85.430614)
			(xy 72.16653 -85.407118) (xy 72.215675 -85.365238) (xy 72.269729 -85.329921) (xy 72.327821 -85.301734)
			(xy 72.389015 -85.281134) (xy 72.452326 -85.26845) (xy 72.516734 -85.263888) (xy 72.5812 -85.267521)
			(xy 72.644687 -85.279291) (xy 72.706172 -85.299008) (xy 72.764664 -85.326353) (xy 72.819222 -85.360888)
			(xy 72.868965 -85.402055) (xy 72.891396 -85.42528) (xy 72.907559 -85.441812) (xy 72.94473 -85.469298)
			(xy 72.986259 -85.489606) (xy 73.030778 -85.502065) (xy 73.076816 -85.506264) (xy 73.122854 -85.502065)
			(xy 73.167373 -85.489606) (xy 73.208902 -85.469298) (xy 73.246073 -85.441812) (xy 73.262236 -85.42528)
			(xy 73.283564 -85.403104) (xy 73.330738 -85.363598) (xy 73.382334 -85.330074) (xy 73.437599 -85.303022)
			(xy 73.495725 -85.282837) (xy 73.555862 -85.269815) (xy 73.617131 -85.264146) (xy 73.678636 -85.265913)
			(xy 73.739479 -85.275089) (xy 73.798769 -85.291541) (xy 73.855641 -85.315028) (xy 73.909262 -85.345208)
			(xy 73.958849 -85.381638) (xy 74.003677 -85.423786) (xy 74.023728 -85.447124) (xy 74.03835 -85.463931)
			(xy 74.072408 -85.492644) (xy 74.110947 -85.514984) (xy 74.152789 -85.530268) (xy 74.196654 -85.538029)
			(xy 74.2412 -85.538029) (xy 74.285065 -85.530268) (xy 74.326907 -85.514984) (xy 74.365446 -85.492644)
			(xy 74.399504 -85.463931) (xy 74.414126 -85.447124) (xy 74.434383 -85.42351) (xy 74.479761 -85.380942)
			(xy 74.529995 -85.34423) (xy 74.584333 -85.313922) (xy 74.641964 -85.290472) (xy 74.702025 -85.27423)
			(xy 74.763619 -85.265438) (xy 74.825827 -85.264228) (xy 74.887716 -85.270618) (xy 74.948364 -85.284513)
			(xy 75.006863 -85.305705) (xy 75.062338 -85.333877) (xy 75.113961 -85.368608) (xy 75.16096 -85.409379)
			(xy 75.202633 -85.455581) (xy 75.238356 -85.506522) (xy 75.267595 -85.561443) (xy 75.289915 -85.61952)
			(xy 75.30498 -85.679888) (xy 75.312566 -85.741643) (xy 75.313032 -85.772752) (xy 75.313032 -86.745318)
			(xy 75.312483 -86.778052) (xy 75.304053 -86.842975) (xy 75.28736 -86.90628) (xy 75.262681 -86.966918)
			(xy 75.230423 -87.023888) (xy 75.211178 -87.050372) (xy 75.186032 -87.084154) (xy 75.186032 -87.101172)
			(xy 75.170538 -87.101172) (xy 75.134724 -87.131652) (xy 75.109547 -87.152505) (xy 75.054815 -87.188256)
			(xy 74.99595 -87.216695) (xy 74.933925 -87.23735) (xy 74.869763 -87.249881) (xy 74.804524 -87.254081)
			(xy 74.739285 -87.249881) (xy 74.675123 -87.23735) (xy 74.613098 -87.216695) (xy 74.554233 -87.188256)
			(xy 74.499501 -87.152505) (xy 74.474324 -87.131652) (xy 74.43851 -87.101172) (xy 74.423016 -87.101172)
			(xy 74.423016 -87.084154) (xy 74.39787 -87.050372) (xy 74.379532 -87.025185) (xy 74.348453 -86.971188)
			(xy 74.335894 -86.942676) (xy 74.328992 -86.927609) (xy 74.308731 -86.901401) (xy 74.282398 -86.881302)
			(xy 74.251773 -86.868672) (xy 74.218927 -86.864365) (xy 74.186081 -86.868672) (xy 74.155456 -86.881302)
			(xy 74.129123 -86.901401) (xy 74.108862 -86.927609) (xy 74.10196 -86.942676) (xy 74.089402 -86.971189)
			(xy 74.058328 -87.02519) (xy 74.039984 -87.050372) (xy 74.014584 -87.084154) (xy 74.014584 -87.101172)
			(xy 73.999344 -87.101172) (xy 73.96353 -87.131652) (xy 73.938353 -87.152505) (xy 73.883621 -87.188256)
			(xy 73.824756 -87.216695) (xy 73.762731 -87.23735) (xy 73.698569 -87.249881) (xy 73.63333 -87.254081)
			(xy 73.568091 -87.249881) (xy 73.503929 -87.23735) (xy 73.441904 -87.216695) (xy 73.383039 -87.188256)
			(xy 73.328307 -87.152505) (xy 73.30313 -87.131652) (xy 73.267316 -87.101172) (xy 73.252076 -87.101172)
			(xy 73.252076 -87.084154) (xy 73.226676 -87.050372) (xy 73.216123 -87.036051) (xy 73.196801 -87.006179)
			(xy 73.188068 -86.990682) (xy 73.18042 -86.977672) (xy 73.160069 -86.955399) (xy 73.135054 -86.938533)
			(xy 73.106774 -86.92802) (xy 73.076816 -86.924449) (xy 73.046858 -86.92802) (xy 73.018578 -86.938533)
			(xy 72.993563 -86.955399) (xy 72.973212 -86.977672) (xy 72.965564 -86.990682) (xy 72.956841 -87.006185)
			(xy 72.937519 -87.036058) (xy 72.926956 -87.050372) (xy 72.901556 -87.084154) (xy 72.901556 -87.101172)
			(xy 72.886316 -87.101172) (xy 72.850502 -87.131652) (xy 72.825325 -87.152505) (xy 72.770593 -87.188256)
			(xy 72.711728 -87.216695) (xy 72.649703 -87.23735) (xy 72.585541 -87.249881) (xy 72.520302 -87.254081)
			(xy 72.455063 -87.249881) (xy 72.390901 -87.23735) (xy 72.328876 -87.216695) (xy 72.270011 -87.188256)
			(xy 72.215279 -87.152505) (xy 72.190102 -87.131652) (xy 72.154288 -87.101172) (xy 72.139048 -87.101172)
			(xy 72.139048 -87.084154) (xy 72.113648 -87.050372) (xy 72.101285 -87.033537) (xy 72.079028 -86.998189)
			(xy 72.069198 -86.97976) (xy 72.061709 -86.96627) (xy 72.041337 -86.943107) (xy 72.015995 -86.92552)
			(xy 71.987169 -86.914537) (xy 71.956549 -86.910803) (xy 71.925929 -86.914537) (xy 71.897103 -86.92552)
			(xy 71.871761 -86.943107) (xy 71.851389 -86.96627) (xy 71.8439 -86.97976) (xy 71.834078 -86.998194)
			(xy 71.811822 -87.033543) (xy 71.79945 -87.050372) (xy 71.774304 -87.084154) (xy 71.774304 -87.101172)
			(xy 71.75881 -87.101172) (xy 71.722996 -87.131652) (xy 71.697819 -87.152505) (xy 71.643087 -87.188256)
			(xy 71.584222 -87.216695) (xy 71.522197 -87.23735) (xy 71.458035 -87.249881) (xy 71.392796 -87.254081)
			(xy 71.327557 -87.249881) (xy 71.263395 -87.23735) (xy 71.20137 -87.216695) (xy 71.142505 -87.188256)
			(xy 71.087773 -87.152505) (xy 71.062596 -87.131652) (xy 71.026782 -87.101172) (xy 71.011288 -87.101172)
			(xy 71.011288 -87.084154) (xy 70.986142 -87.050372) (xy 70.966878 -87.0239) (xy 70.934617 -86.966929)
			(xy 70.909935 -86.906287) (xy 70.893241 -86.84298) (xy 70.88481 -86.778054) (xy 70.884288 -86.745318)
			(xy 29.24048 -86.745318) (xy 29.24048 -89.81186) (xy 29.241057 -89.828493) (xy 29.249732 -89.860612)
			(xy 29.266422 -89.889391) (xy 29.277818 -89.901522) (xy 29.99232 -90.616024) (xy 32.26943 -90.616024)
			(xy 33.77692 -92.123514) (xy 33.77692 -93.033358) (xy 34.599874 -93.033358) (xy 34.599874 -92.946458)
			(xy 34.607892 -92.859929) (xy 34.62386 -92.774509) (xy 34.647641 -92.690927) (xy 34.679033 -92.609895)
			(xy 34.717767 -92.532106) (xy 34.763514 -92.458222) (xy 34.815883 -92.388875) (xy 34.874427 -92.324655)
			(xy 34.938647 -92.266111) (xy 35.007994 -92.213742) (xy 35.081878 -92.167995) (xy 35.159667 -92.129261)
			(xy 35.240699 -92.097869) (xy 35.324281 -92.074088) (xy 35.409701 -92.05812) (xy 35.49623 -92.050102)
			(xy 35.58313 -92.050102) (xy 35.669659 -92.05812) (xy 35.755079 -92.074088) (xy 35.838661 -92.097869)
			(xy 35.919693 -92.129261) (xy 35.997482 -92.167995) (xy 36.071366 -92.213742) (xy 36.140713 -92.266111)
			(xy 36.204933 -92.324655) (xy 36.263477 -92.388875) (xy 36.315846 -92.458222) (xy 36.361593 -92.532106)
			(xy 36.400327 -92.609895) (xy 36.431719 -92.690927) (xy 36.4555 -92.774509) (xy 36.471468 -92.859929)
			(xy 36.479486 -92.946458) (xy 36.479988 -92.989908) (xy 36.479486 -93.033358) (xy 36.471468 -93.119887)
			(xy 36.4555 -93.205307) (xy 36.431719 -93.288889) (xy 36.400327 -93.369921) (xy 36.361593 -93.44771)
			(xy 36.315846 -93.521594) (xy 36.263477 -93.590941) (xy 36.204933 -93.655161) (xy 36.140713 -93.713705)
			(xy 36.071366 -93.766074) (xy 35.997482 -93.811821) (xy 35.919693 -93.850555) (xy 35.838661 -93.881947)
			(xy 35.755079 -93.905728) (xy 35.669659 -93.921696) (xy 35.58313 -93.929714) (xy 35.49623 -93.929714)
			(xy 35.409701 -93.921696) (xy 35.324281 -93.905728) (xy 35.240699 -93.881947) (xy 35.159667 -93.850555)
			(xy 35.081878 -93.811821) (xy 35.007994 -93.766074) (xy 34.938647 -93.713705) (xy 34.874427 -93.655161)
			(xy 34.815883 -93.590941) (xy 34.763514 -93.521594) (xy 34.717767 -93.44771) (xy 34.679033 -93.369921)
			(xy 34.647641 -93.288889) (xy 34.62386 -93.205307) (xy 34.607892 -93.119887) (xy 34.599874 -93.033358)
			(xy 33.77692 -93.033358) (xy 33.77692 -95.573358) (xy 34.599874 -95.573358) (xy 34.599874 -95.486458)
			(xy 34.607892 -95.399929) (xy 34.62386 -95.314509) (xy 34.647641 -95.230927) (xy 34.679033 -95.149895)
			(xy 34.717767 -95.072106) (xy 34.763514 -94.998222) (xy 34.815883 -94.928875) (xy 34.874427 -94.864655)
			(xy 34.938647 -94.806111) (xy 35.007994 -94.753742) (xy 35.081878 -94.707995) (xy 35.159667 -94.669261)
			(xy 35.240699 -94.637869) (xy 35.324281 -94.614088) (xy 35.409701 -94.59812) (xy 35.49623 -94.590102)
			(xy 35.58313 -94.590102) (xy 35.669659 -94.59812) (xy 35.755079 -94.614088) (xy 35.838661 -94.637869)
			(xy 35.919693 -94.669261) (xy 35.997482 -94.707995) (xy 36.071366 -94.753742) (xy 36.140713 -94.806111)
			(xy 36.204933 -94.864655) (xy 36.263477 -94.928875) (xy 36.315846 -94.998222) (xy 36.361593 -95.072106)
			(xy 36.400327 -95.149895) (xy 36.431719 -95.230927) (xy 36.4555 -95.314509) (xy 36.471468 -95.399929)
			(xy 36.479486 -95.486458) (xy 36.479988 -95.529908) (xy 36.479486 -95.573358) (xy 36.471468 -95.659887)
			(xy 36.4555 -95.745307) (xy 36.437073 -95.81007) (xy 39.818063 -95.81007) (xy 39.82207 -95.694046)
			(xy 39.834072 -95.578574) (xy 39.854012 -95.464206) (xy 39.881795 -95.351486) (xy 39.917289 -95.240952)
			(xy 39.960324 -95.133129) (xy 40.010695 -95.028532) (xy 40.068162 -94.92766) (xy 40.132452 -94.830993)
			(xy 40.203257 -94.738992) (xy 40.280241 -94.652095) (xy 40.363037 -94.570716) (xy 40.45125 -94.495243)
			(xy 40.54446 -94.426036) (xy 40.642223 -94.363424) (xy 40.744072 -94.307707) (xy 40.849522 -94.259149)
			(xy 40.958071 -94.217981) (xy 41.069202 -94.184401) (xy 41.182385 -94.158568) (xy 41.29708 -94.140605)
			(xy 41.412742 -94.130597) (xy 41.528818 -94.128594) (xy 41.644756 -94.134603) (xy 41.760003 -94.148596)
			(xy 41.874009 -94.170507) (xy 41.986233 -94.200232) (xy 42.096139 -94.237628) (xy 42.203202 -94.282517)
			(xy 42.306914 -94.334686) (xy 42.406779 -94.393886) (xy 42.502322 -94.459835) (xy 42.502604 -94.46006)
			(xy 43.327577 -94.46006) (xy 43.331612 -94.384356) (xy 43.343671 -94.309511) (xy 43.363617 -94.23637)
			(xy 43.391224 -94.165765) (xy 43.42618 -94.098494) (xy 43.468088 -94.035319) (xy 43.516474 -93.976957)
			(xy 43.57079 -93.924069) (xy 43.630419 -93.877254) (xy 43.694687 -93.837042) (xy 43.762864 -93.80389)
			(xy 43.83418 -93.778172) (xy 43.907825 -93.76018) (xy 43.982965 -93.750118) (xy 44.058749 -93.748099)
			(xy 44.134319 -93.754148) (xy 44.208817 -93.768195) (xy 44.2814 -93.790081) (xy 44.351246 -93.819558)
			(xy 44.417563 -93.856293) (xy 44.479599 -93.899868) (xy 44.536652 -93.94979) (xy 44.588076 -94.005494)
			(xy 44.633287 -94.066349) (xy 44.671774 -94.131664) (xy 44.7031 -94.2007) (xy 44.72691 -94.272675)
			(xy 44.742935 -94.346773) (xy 44.750994 -94.422154) (xy 44.751498 -94.46006) (xy 45.867577 -94.46006)
			(xy 45.871612 -94.384356) (xy 45.883671 -94.309511) (xy 45.903617 -94.23637) (xy 45.931224 -94.165765)
			(xy 45.96618 -94.098494) (xy 46.008088 -94.035319) (xy 46.056474 -93.976957) (xy 46.11079 -93.924069)
			(xy 46.170419 -93.877254) (xy 46.234687 -93.837042) (xy 46.302864 -93.80389) (xy 46.37418 -93.778172)
			(xy 46.447825 -93.76018) (xy 46.522965 -93.750118) (xy 46.598749 -93.748099) (xy 46.674319 -93.754148)
			(xy 46.748817 -93.768195) (xy 46.8214 -93.790081) (xy 46.891246 -93.819558) (xy 46.957563 -93.856293)
			(xy 47.019599 -93.899868) (xy 47.076652 -93.94979) (xy 47.128076 -94.005494) (xy 47.173287 -94.066349)
			(xy 47.211774 -94.131664) (xy 47.2431 -94.2007) (xy 47.26691 -94.272675) (xy 47.282935 -94.346773)
			(xy 47.290994 -94.422154) (xy 47.291498 -94.46006) (xy 48.407577 -94.46006) (xy 48.411612 -94.384356)
			(xy 48.423671 -94.309511) (xy 48.443617 -94.23637) (xy 48.471224 -94.165765) (xy 48.50618 -94.098494)
			(xy 48.548088 -94.035319) (xy 48.596474 -93.976957) (xy 48.65079 -93.924069) (xy 48.710419 -93.877254)
			(xy 48.774687 -93.837042) (xy 48.842864 -93.80389) (xy 48.91418 -93.778172) (xy 48.987825 -93.76018)
			(xy 49.062965 -93.750118) (xy 49.138749 -93.748099) (xy 49.214319 -93.754148) (xy 49.288817 -93.768195)
			(xy 49.3614 -93.790081) (xy 49.431246 -93.819558) (xy 49.497563 -93.856293) (xy 49.559599 -93.899868)
			(xy 49.616652 -93.94979) (xy 49.668076 -94.005494) (xy 49.713287 -94.066349) (xy 49.751774 -94.131664)
			(xy 49.7831 -94.2007) (xy 49.80691 -94.272675) (xy 49.822935 -94.346773) (xy 49.830994 -94.422154)
			(xy 49.831498 -94.46006) (xy 50.947577 -94.46006) (xy 50.951612 -94.384356) (xy 50.963671 -94.309511)
			(xy 50.983617 -94.23637) (xy 51.011224 -94.165765) (xy 51.04618 -94.098494) (xy 51.088088 -94.035319)
			(xy 51.136474 -93.976957) (xy 51.19079 -93.924069) (xy 51.250419 -93.877254) (xy 51.314687 -93.837042)
			(xy 51.382864 -93.80389) (xy 51.45418 -93.778172) (xy 51.527825 -93.76018) (xy 51.602965 -93.750118)
			(xy 51.678749 -93.748099) (xy 51.754319 -93.754148) (xy 51.828817 -93.768195) (xy 51.9014 -93.790081)
			(xy 51.971246 -93.819558) (xy 52.037563 -93.856293) (xy 52.099599 -93.899868) (xy 52.156652 -93.94979)
			(xy 52.208076 -94.005494) (xy 52.253287 -94.066349) (xy 52.291774 -94.131664) (xy 52.3231 -94.2007)
			(xy 52.34691 -94.272675) (xy 52.362935 -94.346773) (xy 52.370994 -94.422154) (xy 52.371498 -94.46006)
			(xy 53.487577 -94.46006) (xy 53.491612 -94.384356) (xy 53.503671 -94.309511) (xy 53.523617 -94.23637)
			(xy 53.551224 -94.165765) (xy 53.58618 -94.098494) (xy 53.628088 -94.035319) (xy 53.676474 -93.976957)
			(xy 53.73079 -93.924069) (xy 53.790419 -93.877254) (xy 53.854687 -93.837042) (xy 53.922864 -93.80389)
			(xy 53.99418 -93.778172) (xy 54.067825 -93.76018) (xy 54.142965 -93.750118) (xy 54.218749 -93.748099)
			(xy 54.294319 -93.754148) (xy 54.368817 -93.768195) (xy 54.4414 -93.790081) (xy 54.511246 -93.819558)
			(xy 54.577563 -93.856293) (xy 54.639599 -93.899868) (xy 54.696652 -93.94979) (xy 54.748076 -94.005494)
			(xy 54.793287 -94.066349) (xy 54.831774 -94.131664) (xy 54.8631 -94.2007) (xy 54.88691 -94.272675)
			(xy 54.902935 -94.346773) (xy 54.910994 -94.422154) (xy 54.911498 -94.46006) (xy 56.027577 -94.46006)
			(xy 56.031612 -94.384356) (xy 56.043671 -94.309511) (xy 56.063617 -94.23637) (xy 56.091224 -94.165765)
			(xy 56.12618 -94.098494) (xy 56.168088 -94.035319) (xy 56.216474 -93.976957) (xy 56.27079 -93.924069)
			(xy 56.330419 -93.877254) (xy 56.394687 -93.837042) (xy 56.462864 -93.80389) (xy 56.53418 -93.778172)
			(xy 56.607825 -93.76018) (xy 56.682965 -93.750118) (xy 56.758749 -93.748099) (xy 56.834319 -93.754148)
			(xy 56.908817 -93.768195) (xy 56.9814 -93.790081) (xy 57.051246 -93.819558) (xy 57.117563 -93.856293)
			(xy 57.179599 -93.899868) (xy 57.236652 -93.94979) (xy 57.288076 -94.005494) (xy 57.333287 -94.066349)
			(xy 57.371774 -94.131664) (xy 57.4031 -94.2007) (xy 57.42691 -94.272675) (xy 57.442935 -94.346773)
			(xy 57.450994 -94.422154) (xy 57.451498 -94.46006) (xy 58.567577 -94.46006) (xy 58.571612 -94.384356)
			(xy 58.583671 -94.309511) (xy 58.603617 -94.23637) (xy 58.631224 -94.165765) (xy 58.66618 -94.098494)
			(xy 58.708088 -94.035319) (xy 58.756474 -93.976957) (xy 58.81079 -93.924069) (xy 58.870419 -93.877254)
			(xy 58.934687 -93.837042) (xy 59.002864 -93.80389) (xy 59.07418 -93.778172) (xy 59.147825 -93.76018)
			(xy 59.222965 -93.750118) (xy 59.298749 -93.748099) (xy 59.374319 -93.754148) (xy 59.448817 -93.768195)
			(xy 59.5214 -93.790081) (xy 59.591246 -93.819558) (xy 59.657563 -93.856293) (xy 59.719599 -93.899868)
			(xy 59.776652 -93.94979) (xy 59.828076 -94.005494) (xy 59.873287 -94.066349) (xy 59.911774 -94.131664)
			(xy 59.9431 -94.2007) (xy 59.96691 -94.272675) (xy 59.982935 -94.346773) (xy 59.990994 -94.422154)
			(xy 59.991498 -94.46006) (xy 61.107577 -94.46006) (xy 61.111612 -94.384356) (xy 61.123671 -94.309511)
			(xy 61.143617 -94.23637) (xy 61.171224 -94.165765) (xy 61.20618 -94.098494) (xy 61.248088 -94.035319)
			(xy 61.296474 -93.976957) (xy 61.35079 -93.924069) (xy 61.410419 -93.877254) (xy 61.474687 -93.837042)
			(xy 61.542864 -93.80389) (xy 61.61418 -93.778172) (xy 61.687825 -93.76018) (xy 61.762965 -93.750118)
			(xy 61.838749 -93.748099) (xy 61.914319 -93.754148) (xy 61.988817 -93.768195) (xy 62.0614 -93.790081)
			(xy 62.131246 -93.819558) (xy 62.197563 -93.856293) (xy 62.259599 -93.899868) (xy 62.265544 -93.90507)
			(xy 86.197697 -93.90507) (xy 86.201732 -93.829366) (xy 86.213791 -93.754521) (xy 86.233737 -93.68138)
			(xy 86.261344 -93.610775) (xy 86.2963 -93.543504) (xy 86.338208 -93.480329) (xy 86.386594 -93.421967)
			(xy 86.44091 -93.369079) (xy 86.500539 -93.322264) (xy 86.564807 -93.282052) (xy 86.632984 -93.2489)
			(xy 86.7043 -93.223182) (xy 86.777945 -93.20519) (xy 86.853085 -93.195128) (xy 86.928869 -93.193109)
			(xy 87.004439 -93.199158) (xy 87.078937 -93.213205) (xy 87.15152 -93.235091) (xy 87.221366 -93.264568)
			(xy 87.287683 -93.301303) (xy 87.349719 -93.344878) (xy 87.406772 -93.3948) (xy 87.458196 -93.450504)
			(xy 87.503407 -93.511359) (xy 87.541894 -93.576674) (xy 87.57322 -93.64571) (xy 87.59703 -93.717685)
			(xy 87.613055 -93.791783) (xy 87.621114 -93.867164) (xy 87.621618 -93.90507) (xy 88.737697 -93.90507)
			(xy 88.741732 -93.829366) (xy 88.753791 -93.754521) (xy 88.773737 -93.68138) (xy 88.801344 -93.610775)
			(xy 88.8363 -93.543504) (xy 88.878208 -93.480329) (xy 88.926594 -93.421967) (xy 88.98091 -93.369079)
			(xy 89.040539 -93.322264) (xy 89.104807 -93.282052) (xy 89.172984 -93.2489) (xy 89.2443 -93.223182)
			(xy 89.317945 -93.20519) (xy 89.393085 -93.195128) (xy 89.468869 -93.193109) (xy 89.544439 -93.199158)
			(xy 89.618937 -93.213205) (xy 89.69152 -93.235091) (xy 89.761366 -93.264568) (xy 89.827683 -93.301303)
			(xy 89.889719 -93.344878) (xy 89.946772 -93.3948) (xy 89.998196 -93.450504) (xy 90.043407 -93.511359)
			(xy 90.081894 -93.576674) (xy 90.11322 -93.64571) (xy 90.13703 -93.717685) (xy 90.153055 -93.791783)
			(xy 90.161114 -93.867164) (xy 90.161618 -93.90507) (xy 91.277697 -93.90507) (xy 91.281732 -93.829366)
			(xy 91.293791 -93.754521) (xy 91.313737 -93.68138) (xy 91.341344 -93.610775) (xy 91.3763 -93.543504)
			(xy 91.418208 -93.480329) (xy 91.466594 -93.421967) (xy 91.52091 -93.369079) (xy 91.580539 -93.322264)
			(xy 91.644807 -93.282052) (xy 91.712984 -93.2489) (xy 91.7843 -93.223182) (xy 91.857945 -93.20519)
			(xy 91.933085 -93.195128) (xy 92.008869 -93.193109) (xy 92.084439 -93.199158) (xy 92.158937 -93.213205)
			(xy 92.23152 -93.235091) (xy 92.301366 -93.264568) (xy 92.367683 -93.301303) (xy 92.429719 -93.344878)
			(xy 92.486772 -93.3948) (xy 92.538196 -93.450504) (xy 92.583407 -93.511359) (xy 92.621894 -93.576674)
			(xy 92.65322 -93.64571) (xy 92.67703 -93.717685) (xy 92.693055 -93.791783) (xy 92.701114 -93.867164)
			(xy 92.701618 -93.90507) (xy 92.701114 -93.942976) (xy 92.693055 -94.018357) (xy 92.67703 -94.092455)
			(xy 92.65322 -94.16443) (xy 92.621894 -94.233466) (xy 92.583407 -94.298781) (xy 92.538196 -94.359636)
			(xy 92.486772 -94.41534) (xy 92.429719 -94.465262) (xy 92.367683 -94.508837) (xy 92.301366 -94.545572)
			(xy 92.23152 -94.575049) (xy 92.158937 -94.596935) (xy 92.084439 -94.610982) (xy 92.008869 -94.617031)
			(xy 91.933085 -94.615012) (xy 91.857945 -94.60495) (xy 91.7843 -94.586958) (xy 91.712984 -94.56124)
			(xy 91.644807 -94.528088) (xy 91.580539 -94.487876) (xy 91.52091 -94.441061) (xy 91.466594 -94.388173)
			(xy 91.418208 -94.329811) (xy 91.3763 -94.266636) (xy 91.341344 -94.199365) (xy 91.313737 -94.12876)
			(xy 91.293791 -94.055619) (xy 91.281732 -93.980774) (xy 91.277697 -93.90507) (xy 90.161618 -93.90507)
			(xy 90.161114 -93.942976) (xy 90.153055 -94.018357) (xy 90.13703 -94.092455) (xy 90.11322 -94.16443)
			(xy 90.081894 -94.233466) (xy 90.043407 -94.298781) (xy 89.998196 -94.359636) (xy 89.946772 -94.41534)
			(xy 89.889719 -94.465262) (xy 89.827683 -94.508837) (xy 89.761366 -94.545572) (xy 89.69152 -94.575049)
			(xy 89.618937 -94.596935) (xy 89.544439 -94.610982) (xy 89.468869 -94.617031) (xy 89.393085 -94.615012)
			(xy 89.317945 -94.60495) (xy 89.2443 -94.586958) (xy 89.172984 -94.56124) (xy 89.104807 -94.528088)
			(xy 89.040539 -94.487876) (xy 88.98091 -94.441061) (xy 88.926594 -94.388173) (xy 88.878208 -94.329811)
			(xy 88.8363 -94.266636) (xy 88.801344 -94.199365) (xy 88.773737 -94.12876) (xy 88.753791 -94.055619)
			(xy 88.741732 -93.980774) (xy 88.737697 -93.90507) (xy 87.621618 -93.90507) (xy 87.621114 -93.942976)
			(xy 87.613055 -94.018357) (xy 87.59703 -94.092455) (xy 87.57322 -94.16443) (xy 87.541894 -94.233466)
			(xy 87.503407 -94.298781) (xy 87.458196 -94.359636) (xy 87.406772 -94.41534) (xy 87.349719 -94.465262)
			(xy 87.287683 -94.508837) (xy 87.221366 -94.545572) (xy 87.15152 -94.575049) (xy 87.078937 -94.596935)
			(xy 87.004439 -94.610982) (xy 86.928869 -94.617031) (xy 86.853085 -94.615012) (xy 86.777945 -94.60495)
			(xy 86.7043 -94.586958) (xy 86.632984 -94.56124) (xy 86.564807 -94.528088) (xy 86.500539 -94.487876)
			(xy 86.44091 -94.441061) (xy 86.386594 -94.388173) (xy 86.338208 -94.329811) (xy 86.2963 -94.266636)
			(xy 86.261344 -94.199365) (xy 86.233737 -94.12876) (xy 86.213791 -94.055619) (xy 86.201732 -93.980774)
			(xy 86.197697 -93.90507) (xy 62.265544 -93.90507) (xy 62.316652 -93.94979) (xy 62.368076 -94.005494)
			(xy 62.413287 -94.066349) (xy 62.451774 -94.131664) (xy 62.4831 -94.2007) (xy 62.50691 -94.272675)
			(xy 62.522935 -94.346773) (xy 62.530994 -94.422154) (xy 62.531498 -94.46006) (xy 62.530994 -94.497966)
			(xy 62.522935 -94.573347) (xy 62.50691 -94.647445) (xy 62.4831 -94.71942) (xy 62.451774 -94.788456)
			(xy 62.413287 -94.853771) (xy 62.368076 -94.914626) (xy 62.316652 -94.97033) (xy 62.259599 -95.020252)
			(xy 62.197563 -95.063827) (xy 62.131246 -95.100562) (xy 62.0614 -95.130039) (xy 61.988817 -95.151925)
			(xy 61.914319 -95.165972) (xy 61.838749 -95.172021) (xy 61.762965 -95.170002) (xy 61.687825 -95.15994)
			(xy 61.61418 -95.141948) (xy 61.542864 -95.11623) (xy 61.474687 -95.083078) (xy 61.410419 -95.042866)
			(xy 61.35079 -94.996051) (xy 61.296474 -94.943163) (xy 61.248088 -94.884801) (xy 61.20618 -94.821626)
			(xy 61.171224 -94.754355) (xy 61.143617 -94.68375) (xy 61.123671 -94.610609) (xy 61.111612 -94.535764)
			(xy 61.107577 -94.46006) (xy 59.991498 -94.46006) (xy 59.990994 -94.497966) (xy 59.982935 -94.573347)
			(xy 59.96691 -94.647445) (xy 59.9431 -94.71942) (xy 59.911774 -94.788456) (xy 59.873287 -94.853771)
			(xy 59.828076 -94.914626) (xy 59.776652 -94.97033) (xy 59.719599 -95.020252) (xy 59.657563 -95.063827)
			(xy 59.591246 -95.100562) (xy 59.5214 -95.130039) (xy 59.448817 -95.151925) (xy 59.374319 -95.165972)
			(xy 59.298749 -95.172021) (xy 59.222965 -95.170002) (xy 59.147825 -95.15994) (xy 59.07418 -95.141948)
			(xy 59.002864 -95.11623) (xy 58.934687 -95.083078) (xy 58.870419 -95.042866) (xy 58.81079 -94.996051)
			(xy 58.756474 -94.943163) (xy 58.708088 -94.884801) (xy 58.66618 -94.821626) (xy 58.631224 -94.754355)
			(xy 58.603617 -94.68375) (xy 58.583671 -94.610609) (xy 58.571612 -94.535764) (xy 58.567577 -94.46006)
			(xy 57.451498 -94.46006) (xy 57.450994 -94.497966) (xy 57.442935 -94.573347) (xy 57.42691 -94.647445)
			(xy 57.4031 -94.71942) (xy 57.371774 -94.788456) (xy 57.333287 -94.853771) (xy 57.288076 -94.914626)
			(xy 57.236652 -94.97033) (xy 57.179599 -95.020252) (xy 57.117563 -95.063827) (xy 57.051246 -95.100562)
			(xy 56.9814 -95.130039) (xy 56.908817 -95.151925) (xy 56.834319 -95.165972) (xy 56.758749 -95.172021)
			(xy 56.682965 -95.170002) (xy 56.607825 -95.15994) (xy 56.53418 -95.141948) (xy 56.462864 -95.11623)
			(xy 56.394687 -95.083078) (xy 56.330419 -95.042866) (xy 56.27079 -94.996051) (xy 56.216474 -94.943163)
			(xy 56.168088 -94.884801) (xy 56.12618 -94.821626) (xy 56.091224 -94.754355) (xy 56.063617 -94.68375)
			(xy 56.043671 -94.610609) (xy 56.031612 -94.535764) (xy 56.027577 -94.46006) (xy 54.911498 -94.46006)
			(xy 54.910994 -94.497966) (xy 54.902935 -94.573347) (xy 54.88691 -94.647445) (xy 54.8631 -94.71942)
			(xy 54.831774 -94.788456) (xy 54.793287 -94.853771) (xy 54.748076 -94.914626) (xy 54.696652 -94.97033)
			(xy 54.639599 -95.020252) (xy 54.577563 -95.063827) (xy 54.511246 -95.100562) (xy 54.4414 -95.130039)
			(xy 54.368817 -95.151925) (xy 54.294319 -95.165972) (xy 54.218749 -95.172021) (xy 54.142965 -95.170002)
			(xy 54.067825 -95.15994) (xy 53.99418 -95.141948) (xy 53.922864 -95.11623) (xy 53.854687 -95.083078)
			(xy 53.790419 -95.042866) (xy 53.73079 -94.996051) (xy 53.676474 -94.943163) (xy 53.628088 -94.884801)
			(xy 53.58618 -94.821626) (xy 53.551224 -94.754355) (xy 53.523617 -94.68375) (xy 53.503671 -94.610609)
			(xy 53.491612 -94.535764) (xy 53.487577 -94.46006) (xy 52.371498 -94.46006) (xy 52.370994 -94.497966)
			(xy 52.362935 -94.573347) (xy 52.34691 -94.647445) (xy 52.3231 -94.71942) (xy 52.291774 -94.788456)
			(xy 52.253287 -94.853771) (xy 52.208076 -94.914626) (xy 52.156652 -94.97033) (xy 52.099599 -95.020252)
			(xy 52.037563 -95.063827) (xy 51.971246 -95.100562) (xy 51.9014 -95.130039) (xy 51.828817 -95.151925)
			(xy 51.754319 -95.165972) (xy 51.678749 -95.172021) (xy 51.602965 -95.170002) (xy 51.527825 -95.15994)
			(xy 51.45418 -95.141948) (xy 51.382864 -95.11623) (xy 51.314687 -95.083078) (xy 51.250419 -95.042866)
			(xy 51.19079 -94.996051) (xy 51.136474 -94.943163) (xy 51.088088 -94.884801) (xy 51.04618 -94.821626)
			(xy 51.011224 -94.754355) (xy 50.983617 -94.68375) (xy 50.963671 -94.610609) (xy 50.951612 -94.535764)
			(xy 50.947577 -94.46006) (xy 49.831498 -94.46006) (xy 49.830994 -94.497966) (xy 49.822935 -94.573347)
			(xy 49.80691 -94.647445) (xy 49.7831 -94.71942) (xy 49.751774 -94.788456) (xy 49.713287 -94.853771)
			(xy 49.668076 -94.914626) (xy 49.616652 -94.97033) (xy 49.559599 -95.020252) (xy 49.497563 -95.063827)
			(xy 49.431246 -95.100562) (xy 49.3614 -95.130039) (xy 49.288817 -95.151925) (xy 49.214319 -95.165972)
			(xy 49.138749 -95.172021) (xy 49.062965 -95.170002) (xy 48.987825 -95.15994) (xy 48.91418 -95.141948)
			(xy 48.842864 -95.11623) (xy 48.774687 -95.083078) (xy 48.710419 -95.042866) (xy 48.65079 -94.996051)
			(xy 48.596474 -94.943163) (xy 48.548088 -94.884801) (xy 48.50618 -94.821626) (xy 48.471224 -94.754355)
			(xy 48.443617 -94.68375) (xy 48.423671 -94.610609) (xy 48.411612 -94.535764) (xy 48.407577 -94.46006)
			(xy 47.291498 -94.46006) (xy 47.290994 -94.497966) (xy 47.282935 -94.573347) (xy 47.26691 -94.647445)
			(xy 47.2431 -94.71942) (xy 47.211774 -94.788456) (xy 47.173287 -94.853771) (xy 47.128076 -94.914626)
			(xy 47.076652 -94.97033) (xy 47.019599 -95.020252) (xy 46.957563 -95.063827) (xy 46.891246 -95.100562)
			(xy 46.8214 -95.130039) (xy 46.748817 -95.151925) (xy 46.674319 -95.165972) (xy 46.598749 -95.172021)
			(xy 46.522965 -95.170002) (xy 46.447825 -95.15994) (xy 46.37418 -95.141948) (xy 46.302864 -95.11623)
			(xy 46.234687 -95.083078) (xy 46.170419 -95.042866) (xy 46.11079 -94.996051) (xy 46.056474 -94.943163)
			(xy 46.008088 -94.884801) (xy 45.96618 -94.821626) (xy 45.931224 -94.754355) (xy 45.903617 -94.68375)
			(xy 45.883671 -94.610609) (xy 45.871612 -94.535764) (xy 45.867577 -94.46006) (xy 44.751498 -94.46006)
			(xy 44.750994 -94.497966) (xy 44.742935 -94.573347) (xy 44.72691 -94.647445) (xy 44.7031 -94.71942)
			(xy 44.671774 -94.788456) (xy 44.633287 -94.853771) (xy 44.588076 -94.914626) (xy 44.536652 -94.97033)
			(xy 44.479599 -95.020252) (xy 44.417563 -95.063827) (xy 44.351246 -95.100562) (xy 44.2814 -95.130039)
			(xy 44.208817 -95.151925) (xy 44.134319 -95.165972) (xy 44.058749 -95.172021) (xy 43.982965 -95.170002)
			(xy 43.907825 -95.15994) (xy 43.83418 -95.141948) (xy 43.762864 -95.11623) (xy 43.694687 -95.083078)
			(xy 43.630419 -95.042866) (xy 43.57079 -94.996051) (xy 43.516474 -94.943163) (xy 43.468088 -94.884801)
			(xy 43.42618 -94.821626) (xy 43.391224 -94.754355) (xy 43.363617 -94.68375) (xy 43.343671 -94.610609)
			(xy 43.331612 -94.535764) (xy 43.327577 -94.46006) (xy 42.502604 -94.46006) (xy 42.593088 -94.532218)
			(xy 42.678643 -94.610691) (xy 42.758581 -94.694879) (xy 42.83252 -94.784381) (xy 42.900108 -94.878772)
			(xy 42.961022 -94.9776) (xy 43.014974 -95.080396) (xy 43.056604 -95.17507) (xy 84.927697 -95.17507)
			(xy 84.931732 -95.099366) (xy 84.943791 -95.024521) (xy 84.963737 -94.95138) (xy 84.991344 -94.880775)
			(xy 85.0263 -94.813504) (xy 85.068208 -94.750329) (xy 85.116594 -94.691967) (xy 85.17091 -94.639079)
			(xy 85.230539 -94.592264) (xy 85.294807 -94.552052) (xy 85.362984 -94.5189) (xy 85.4343 -94.493182)
			(xy 85.507945 -94.47519) (xy 85.583085 -94.465128) (xy 85.658869 -94.463109) (xy 85.734439 -94.469158)
			(xy 85.808937 -94.483205) (xy 85.88152 -94.505091) (xy 85.951366 -94.534568) (xy 86.017683 -94.571303)
			(xy 86.079719 -94.614878) (xy 86.136772 -94.6648) (xy 86.188196 -94.720504) (xy 86.233407 -94.781359)
			(xy 86.271894 -94.846674) (xy 86.30322 -94.91571) (xy 86.32703 -94.987685) (xy 86.343055 -95.061783)
			(xy 86.351114 -95.137164) (xy 86.351618 -95.17507) (xy 87.467697 -95.17507) (xy 87.471732 -95.099366)
			(xy 87.483791 -95.024521) (xy 87.503737 -94.95138) (xy 87.531344 -94.880775) (xy 87.5663 -94.813504)
			(xy 87.608208 -94.750329) (xy 87.656594 -94.691967) (xy 87.71091 -94.639079) (xy 87.770539 -94.592264)
			(xy 87.834807 -94.552052) (xy 87.902984 -94.5189) (xy 87.9743 -94.493182) (xy 88.047945 -94.47519)
			(xy 88.123085 -94.465128) (xy 88.198869 -94.463109) (xy 88.274439 -94.469158) (xy 88.348937 -94.483205)
			(xy 88.42152 -94.505091) (xy 88.491366 -94.534568) (xy 88.557683 -94.571303) (xy 88.619719 -94.614878)
			(xy 88.676772 -94.6648) (xy 88.728196 -94.720504) (xy 88.773407 -94.781359) (xy 88.811894 -94.846674)
			(xy 88.84322 -94.91571) (xy 88.86703 -94.987685) (xy 88.883055 -95.061783) (xy 88.891114 -95.137164)
			(xy 88.891618 -95.17507) (xy 90.007697 -95.17507) (xy 90.011732 -95.099366) (xy 90.023791 -95.024521)
			(xy 90.043737 -94.95138) (xy 90.071344 -94.880775) (xy 90.1063 -94.813504) (xy 90.148208 -94.750329)
			(xy 90.196594 -94.691967) (xy 90.25091 -94.639079) (xy 90.310539 -94.592264) (xy 90.374807 -94.552052)
			(xy 90.442984 -94.5189) (xy 90.5143 -94.493182) (xy 90.587945 -94.47519) (xy 90.663085 -94.465128)
			(xy 90.738869 -94.463109) (xy 90.814439 -94.469158) (xy 90.888937 -94.483205) (xy 90.96152 -94.505091)
			(xy 91.031366 -94.534568) (xy 91.097683 -94.571303) (xy 91.159719 -94.614878) (xy 91.216772 -94.6648)
			(xy 91.268196 -94.720504) (xy 91.313407 -94.781359) (xy 91.351894 -94.846674) (xy 91.38322 -94.91571)
			(xy 91.40703 -94.987685) (xy 91.423055 -95.061783) (xy 91.431114 -95.137164) (xy 91.431618 -95.17507)
			(xy 91.431114 -95.212976) (xy 91.423055 -95.288357) (xy 91.40703 -95.362455) (xy 91.38322 -95.43443)
			(xy 91.351894 -95.503466) (xy 91.313407 -95.568781) (xy 91.268196 -95.629636) (xy 91.216772 -95.68534)
			(xy 91.159719 -95.735262) (xy 91.097683 -95.778837) (xy 91.031366 -95.815572) (xy 90.96152 -95.845049)
			(xy 90.888937 -95.866935) (xy 90.814439 -95.880982) (xy 90.738869 -95.887031) (xy 90.663085 -95.885012)
			(xy 90.587945 -95.87495) (xy 90.5143 -95.856958) (xy 90.442984 -95.83124) (xy 90.374807 -95.798088)
			(xy 90.310539 -95.757876) (xy 90.25091 -95.711061) (xy 90.196594 -95.658173) (xy 90.148208 -95.599811)
			(xy 90.1063 -95.536636) (xy 90.071344 -95.469365) (xy 90.043737 -95.39876) (xy 90.023791 -95.325619)
			(xy 90.011732 -95.250774) (xy 90.007697 -95.17507) (xy 88.891618 -95.17507) (xy 88.891114 -95.212976)
			(xy 88.883055 -95.288357) (xy 88.86703 -95.362455) (xy 88.84322 -95.43443) (xy 88.811894 -95.503466)
			(xy 88.773407 -95.568781) (xy 88.728196 -95.629636) (xy 88.676772 -95.68534) (xy 88.619719 -95.735262)
			(xy 88.557683 -95.778837) (xy 88.491366 -95.815572) (xy 88.42152 -95.845049) (xy 88.348937 -95.866935)
			(xy 88.274439 -95.880982) (xy 88.198869 -95.887031) (xy 88.123085 -95.885012) (xy 88.047945 -95.87495)
			(xy 87.9743 -95.856958) (xy 87.902984 -95.83124) (xy 87.834807 -95.798088) (xy 87.770539 -95.757876)
			(xy 87.71091 -95.711061) (xy 87.656594 -95.658173) (xy 87.608208 -95.599811) (xy 87.5663 -95.536636)
			(xy 87.531344 -95.469365) (xy 87.503737 -95.39876) (xy 87.483791 -95.325619) (xy 87.471732 -95.250774)
			(xy 87.467697 -95.17507) (xy 86.351618 -95.17507) (xy 86.351114 -95.212976) (xy 86.343055 -95.288357)
			(xy 86.32703 -95.362455) (xy 86.30322 -95.43443) (xy 86.271894 -95.503466) (xy 86.233407 -95.568781)
			(xy 86.188196 -95.629636) (xy 86.136772 -95.68534) (xy 86.079719 -95.735262) (xy 86.017683 -95.778837)
			(xy 85.951366 -95.815572) (xy 85.88152 -95.845049) (xy 85.808937 -95.866935) (xy 85.734439 -95.880982)
			(xy 85.658869 -95.887031) (xy 85.583085 -95.885012) (xy 85.507945 -95.87495) (xy 85.4343 -95.856958)
			(xy 85.362984 -95.83124) (xy 85.294807 -95.798088) (xy 85.230539 -95.757876) (xy 85.17091 -95.711061)
			(xy 85.116594 -95.658173) (xy 85.068208 -95.599811) (xy 85.0263 -95.536636) (xy 84.991344 -95.469365)
			(xy 84.963737 -95.39876) (xy 84.943791 -95.325619) (xy 84.931732 -95.250774) (xy 84.927697 -95.17507)
			(xy 43.056604 -95.17507) (xy 43.061704 -95.186669) (xy 43.100992 -95.295913) (xy 43.132649 -95.407606)
			(xy 43.156525 -95.521218) (xy 43.172506 -95.636206) (xy 43.180515 -95.752023) (xy 43.181016 -95.81007)
			(xy 43.180515 -95.868117) (xy 43.172506 -95.983934) (xy 43.156525 -96.098922) (xy 43.132649 -96.212534)
			(xy 43.100992 -96.324227) (xy 43.061704 -96.433471) (xy 43.056604 -96.44507) (xy 86.197697 -96.44507)
			(xy 86.201732 -96.369366) (xy 86.213791 -96.294521) (xy 86.233737 -96.22138) (xy 86.261344 -96.150775)
			(xy 86.2963 -96.083504) (xy 86.338208 -96.020329) (xy 86.386594 -95.961967) (xy 86.44091 -95.909079)
			(xy 86.500539 -95.862264) (xy 86.564807 -95.822052) (xy 86.632984 -95.7889) (xy 86.7043 -95.763182)
			(xy 86.777945 -95.74519) (xy 86.853085 -95.735128) (xy 86.928869 -95.733109) (xy 87.004439 -95.739158)
			(xy 87.078937 -95.753205) (xy 87.15152 -95.775091) (xy 87.221366 -95.804568) (xy 87.287683 -95.841303)
			(xy 87.349719 -95.884878) (xy 87.406772 -95.9348) (xy 87.458196 -95.990504) (xy 87.503407 -96.051359)
			(xy 87.541894 -96.116674) (xy 87.57322 -96.18571) (xy 87.59703 -96.257685) (xy 87.613055 -96.331783)
			(xy 87.621114 -96.407164) (xy 87.621618 -96.44507) (xy 88.737697 -96.44507) (xy 88.741732 -96.369366)
			(xy 88.753791 -96.294521) (xy 88.773737 -96.22138) (xy 88.801344 -96.150775) (xy 88.8363 -96.083504)
			(xy 88.878208 -96.020329) (xy 88.926594 -95.961967) (xy 88.98091 -95.909079) (xy 89.040539 -95.862264)
			(xy 89.104807 -95.822052) (xy 89.172984 -95.7889) (xy 89.2443 -95.763182) (xy 89.317945 -95.74519)
			(xy 89.393085 -95.735128) (xy 89.468869 -95.733109) (xy 89.544439 -95.739158) (xy 89.618937 -95.753205)
			(xy 89.69152 -95.775091) (xy 89.761366 -95.804568) (xy 89.827683 -95.841303) (xy 89.889719 -95.884878)
			(xy 89.946772 -95.9348) (xy 89.998196 -95.990504) (xy 90.043407 -96.051359) (xy 90.081894 -96.116674)
			(xy 90.11322 -96.18571) (xy 90.13703 -96.257685) (xy 90.153055 -96.331783) (xy 90.161114 -96.407164)
			(xy 90.161618 -96.44507) (xy 91.277697 -96.44507) (xy 91.281732 -96.369366) (xy 91.293791 -96.294521)
			(xy 91.313737 -96.22138) (xy 91.341344 -96.150775) (xy 91.3763 -96.083504) (xy 91.418208 -96.020329)
			(xy 91.466594 -95.961967) (xy 91.52091 -95.909079) (xy 91.580539 -95.862264) (xy 91.644807 -95.822052)
			(xy 91.712984 -95.7889) (xy 91.7843 -95.763182) (xy 91.857945 -95.74519) (xy 91.933085 -95.735128)
			(xy 92.008869 -95.733109) (xy 92.084439 -95.739158) (xy 92.158937 -95.753205) (xy 92.23152 -95.775091)
			(xy 92.301366 -95.804568) (xy 92.367683 -95.841303) (xy 92.429719 -95.884878) (xy 92.486772 -95.9348)
			(xy 92.538196 -95.990504) (xy 92.583407 -96.051359) (xy 92.621894 -96.116674) (xy 92.65322 -96.18571)
			(xy 92.67703 -96.257685) (xy 92.693055 -96.331783) (xy 92.701114 -96.407164) (xy 92.701618 -96.44507)
			(xy 92.701114 -96.482976) (xy 92.693055 -96.558357) (xy 92.67703 -96.632455) (xy 92.65322 -96.70443)
			(xy 92.621894 -96.773466) (xy 92.583407 -96.838781) (xy 92.538196 -96.899636) (xy 92.486772 -96.95534)
			(xy 92.429719 -97.005262) (xy 92.367683 -97.048837) (xy 92.301366 -97.085572) (xy 92.23152 -97.115049)
			(xy 92.158937 -97.136935) (xy 92.084439 -97.150982) (xy 92.008869 -97.157031) (xy 91.933085 -97.155012)
			(xy 91.857945 -97.14495) (xy 91.7843 -97.126958) (xy 91.712984 -97.10124) (xy 91.644807 -97.068088)
			(xy 91.580539 -97.027876) (xy 91.52091 -96.981061) (xy 91.466594 -96.928173) (xy 91.418208 -96.869811)
			(xy 91.3763 -96.806636) (xy 91.341344 -96.739365) (xy 91.313737 -96.66876) (xy 91.293791 -96.595619)
			(xy 91.281732 -96.520774) (xy 91.277697 -96.44507) (xy 90.161618 -96.44507) (xy 90.161114 -96.482976)
			(xy 90.153055 -96.558357) (xy 90.13703 -96.632455) (xy 90.11322 -96.70443) (xy 90.081894 -96.773466)
			(xy 90.043407 -96.838781) (xy 89.998196 -96.899636) (xy 89.946772 -96.95534) (xy 89.889719 -97.005262)
			(xy 89.827683 -97.048837) (xy 89.761366 -97.085572) (xy 89.69152 -97.115049) (xy 89.618937 -97.136935)
			(xy 89.544439 -97.150982) (xy 89.468869 -97.157031) (xy 89.393085 -97.155012) (xy 89.317945 -97.14495)
			(xy 89.2443 -97.126958) (xy 89.172984 -97.10124) (xy 89.104807 -97.068088) (xy 89.040539 -97.027876)
			(xy 88.98091 -96.981061) (xy 88.926594 -96.928173) (xy 88.878208 -96.869811) (xy 88.8363 -96.806636)
			(xy 88.801344 -96.739365) (xy 88.773737 -96.66876) (xy 88.753791 -96.595619) (xy 88.741732 -96.520774)
			(xy 88.737697 -96.44507) (xy 87.621618 -96.44507) (xy 87.621114 -96.482976) (xy 87.613055 -96.558357)
			(xy 87.59703 -96.632455) (xy 87.57322 -96.70443) (xy 87.541894 -96.773466) (xy 87.503407 -96.838781)
			(xy 87.458196 -96.899636) (xy 87.406772 -96.95534) (xy 87.349719 -97.005262) (xy 87.287683 -97.048837)
			(xy 87.221366 -97.085572) (xy 87.15152 -97.115049) (xy 87.078937 -97.136935) (xy 87.004439 -97.150982)
			(xy 86.928869 -97.157031) (xy 86.853085 -97.155012) (xy 86.777945 -97.14495) (xy 86.7043 -97.126958)
			(xy 86.632984 -97.10124) (xy 86.564807 -97.068088) (xy 86.500539 -97.027876) (xy 86.44091 -96.981061)
			(xy 86.386594 -96.928173) (xy 86.338208 -96.869811) (xy 86.2963 -96.806636) (xy 86.261344 -96.739365)
			(xy 86.233737 -96.66876) (xy 86.213791 -96.595619) (xy 86.201732 -96.520774) (xy 86.197697 -96.44507)
			(xy 43.056604 -96.44507) (xy 43.055152 -96.448372) (xy 43.328336 -96.448372) (xy 44.751244 -96.448372)
			(xy 44.751244 -97.16008) (xy 45.867577 -97.16008) (xy 45.871612 -97.084376) (xy 45.883671 -97.009531)
			(xy 45.903617 -96.93639) (xy 45.931224 -96.865785) (xy 45.96618 -96.798514) (xy 46.008088 -96.735339)
			(xy 46.056474 -96.676977) (xy 46.11079 -96.624089) (xy 46.170419 -96.577274) (xy 46.234687 -96.537062)
			(xy 46.302864 -96.50391) (xy 46.37418 -96.478192) (xy 46.447825 -96.4602) (xy 46.522965 -96.450138)
			(xy 46.598749 -96.448119) (xy 46.674319 -96.454168) (xy 46.748817 -96.468215) (xy 46.8214 -96.490101)
			(xy 46.891246 -96.519578) (xy 46.957563 -96.556313) (xy 47.019599 -96.599888) (xy 47.076652 -96.64981)
			(xy 47.128076 -96.705514) (xy 47.173287 -96.766369) (xy 47.211774 -96.831684) (xy 47.2431 -96.90072)
			(xy 47.26691 -96.972695) (xy 47.282935 -97.046793) (xy 47.290994 -97.122174) (xy 47.291498 -97.16008)
			(xy 48.407577 -97.16008) (xy 48.411612 -97.084376) (xy 48.423671 -97.009531) (xy 48.443617 -96.93639)
			(xy 48.471224 -96.865785) (xy 48.50618 -96.798514) (xy 48.548088 -96.735339) (xy 48.596474 -96.676977)
			(xy 48.65079 -96.624089) (xy 48.710419 -96.577274) (xy 48.774687 -96.537062) (xy 48.842864 -96.50391)
			(xy 48.91418 -96.478192) (xy 48.987825 -96.4602) (xy 49.062965 -96.450138) (xy 49.138749 -96.448119)
			(xy 49.214319 -96.454168) (xy 49.288817 -96.468215) (xy 49.3614 -96.490101) (xy 49.431246 -96.519578)
			(xy 49.497563 -96.556313) (xy 49.559599 -96.599888) (xy 49.616652 -96.64981) (xy 49.668076 -96.705514)
			(xy 49.713287 -96.766369) (xy 49.751774 -96.831684) (xy 49.7831 -96.90072) (xy 49.80691 -96.972695)
			(xy 49.822935 -97.046793) (xy 49.830994 -97.122174) (xy 49.831498 -97.16008) (xy 50.947577 -97.16008)
			(xy 50.951612 -97.084376) (xy 50.963671 -97.009531) (xy 50.983617 -96.93639) (xy 51.011224 -96.865785)
			(xy 51.04618 -96.798514) (xy 51.088088 -96.735339) (xy 51.136474 -96.676977) (xy 51.19079 -96.624089)
			(xy 51.250419 -96.577274) (xy 51.314687 -96.537062) (xy 51.382864 -96.50391) (xy 51.45418 -96.478192)
			(xy 51.527825 -96.4602) (xy 51.602965 -96.450138) (xy 51.678749 -96.448119) (xy 51.754319 -96.454168)
			(xy 51.828817 -96.468215) (xy 51.9014 -96.490101) (xy 51.971246 -96.519578) (xy 52.037563 -96.556313)
			(xy 52.099599 -96.599888) (xy 52.156652 -96.64981) (xy 52.208076 -96.705514) (xy 52.253287 -96.766369)
			(xy 52.291774 -96.831684) (xy 52.3231 -96.90072) (xy 52.34691 -96.972695) (xy 52.362935 -97.046793)
			(xy 52.370994 -97.122174) (xy 52.371498 -97.16008) (xy 53.487577 -97.16008) (xy 53.491612 -97.084376)
			(xy 53.503671 -97.009531) (xy 53.523617 -96.93639) (xy 53.551224 -96.865785) (xy 53.58618 -96.798514)
			(xy 53.628088 -96.735339) (xy 53.676474 -96.676977) (xy 53.73079 -96.624089) (xy 53.790419 -96.577274)
			(xy 53.854687 -96.537062) (xy 53.922864 -96.50391) (xy 53.99418 -96.478192) (xy 54.067825 -96.4602)
			(xy 54.142965 -96.450138) (xy 54.218749 -96.448119) (xy 54.294319 -96.454168) (xy 54.368817 -96.468215)
			(xy 54.4414 -96.490101) (xy 54.511246 -96.519578) (xy 54.577563 -96.556313) (xy 54.639599 -96.599888)
			(xy 54.696652 -96.64981) (xy 54.748076 -96.705514) (xy 54.793287 -96.766369) (xy 54.831774 -96.831684)
			(xy 54.8631 -96.90072) (xy 54.88691 -96.972695) (xy 54.902935 -97.046793) (xy 54.910994 -97.122174)
			(xy 54.911498 -97.16008) (xy 56.027577 -97.16008) (xy 56.031612 -97.084376) (xy 56.043671 -97.009531)
			(xy 56.063617 -96.93639) (xy 56.091224 -96.865785) (xy 56.12618 -96.798514) (xy 56.168088 -96.735339)
			(xy 56.216474 -96.676977) (xy 56.27079 -96.624089) (xy 56.330419 -96.577274) (xy 56.394687 -96.537062)
			(xy 56.462864 -96.50391) (xy 56.53418 -96.478192) (xy 56.607825 -96.4602) (xy 56.682965 -96.450138)
			(xy 56.758749 -96.448119) (xy 56.834319 -96.454168) (xy 56.908817 -96.468215) (xy 56.9814 -96.490101)
			(xy 57.051246 -96.519578) (xy 57.117563 -96.556313) (xy 57.179599 -96.599888) (xy 57.236652 -96.64981)
			(xy 57.288076 -96.705514) (xy 57.333287 -96.766369) (xy 57.371774 -96.831684) (xy 57.4031 -96.90072)
			(xy 57.42691 -96.972695) (xy 57.442935 -97.046793) (xy 57.450994 -97.122174) (xy 57.451498 -97.16008)
			(xy 58.567577 -97.16008) (xy 58.571612 -97.084376) (xy 58.583671 -97.009531) (xy 58.603617 -96.93639)
			(xy 58.631224 -96.865785) (xy 58.66618 -96.798514) (xy 58.708088 -96.735339) (xy 58.756474 -96.676977)
			(xy 58.81079 -96.624089) (xy 58.870419 -96.577274) (xy 58.934687 -96.537062) (xy 59.002864 -96.50391)
			(xy 59.07418 -96.478192) (xy 59.147825 -96.4602) (xy 59.222965 -96.450138) (xy 59.298749 -96.448119)
			(xy 59.374319 -96.454168) (xy 59.448817 -96.468215) (xy 59.5214 -96.490101) (xy 59.591246 -96.519578)
			(xy 59.657563 -96.556313) (xy 59.719599 -96.599888) (xy 59.776652 -96.64981) (xy 59.828076 -96.705514)
			(xy 59.873287 -96.766369) (xy 59.911774 -96.831684) (xy 59.9431 -96.90072) (xy 59.96691 -96.972695)
			(xy 59.982935 -97.046793) (xy 59.990994 -97.122174) (xy 59.991498 -97.16008) (xy 61.107577 -97.16008)
			(xy 61.111612 -97.084376) (xy 61.123671 -97.009531) (xy 61.143617 -96.93639) (xy 61.171224 -96.865785)
			(xy 61.20618 -96.798514) (xy 61.248088 -96.735339) (xy 61.296474 -96.676977) (xy 61.35079 -96.624089)
			(xy 61.410419 -96.577274) (xy 61.474687 -96.537062) (xy 61.542864 -96.50391) (xy 61.61418 -96.478192)
			(xy 61.687825 -96.4602) (xy 61.762965 -96.450138) (xy 61.838749 -96.448119) (xy 61.914319 -96.454168)
			(xy 61.988817 -96.468215) (xy 62.0614 -96.490101) (xy 62.131246 -96.519578) (xy 62.197563 -96.556313)
			(xy 62.259599 -96.599888) (xy 62.316652 -96.64981) (xy 62.368076 -96.705514) (xy 62.413287 -96.766369)
			(xy 62.451774 -96.831684) (xy 62.4831 -96.90072) (xy 62.50691 -96.972695) (xy 62.522935 -97.046793)
			(xy 62.530994 -97.122174) (xy 62.531498 -97.16008) (xy 62.530994 -97.197986) (xy 62.522935 -97.273367)
			(xy 62.50691 -97.347465) (xy 62.4831 -97.41944) (xy 62.451774 -97.488476) (xy 62.413287 -97.553791)
			(xy 62.368076 -97.614646) (xy 62.316652 -97.67035) (xy 62.265544 -97.71507) (xy 84.927697 -97.71507)
			(xy 84.931732 -97.639366) (xy 84.943791 -97.564521) (xy 84.963737 -97.49138) (xy 84.991344 -97.420775)
			(xy 85.0263 -97.353504) (xy 85.068208 -97.290329) (xy 85.116594 -97.231967) (xy 85.17091 -97.179079)
			(xy 85.230539 -97.132264) (xy 85.294807 -97.092052) (xy 85.362984 -97.0589) (xy 85.4343 -97.033182)
			(xy 85.507945 -97.01519) (xy 85.583085 -97.005128) (xy 85.658869 -97.003109) (xy 85.734439 -97.009158)
			(xy 85.808937 -97.023205) (xy 85.88152 -97.045091) (xy 85.951366 -97.074568) (xy 86.017683 -97.111303)
			(xy 86.079719 -97.154878) (xy 86.136772 -97.2048) (xy 86.188196 -97.260504) (xy 86.233407 -97.321359)
			(xy 86.271894 -97.386674) (xy 86.30322 -97.45571) (xy 86.32703 -97.527685) (xy 86.343055 -97.601783)
			(xy 86.351114 -97.677164) (xy 86.351618 -97.71507) (xy 87.467697 -97.71507) (xy 87.471732 -97.639366)
			(xy 87.483791 -97.564521) (xy 87.503737 -97.49138) (xy 87.531344 -97.420775) (xy 87.5663 -97.353504)
			(xy 87.608208 -97.290329) (xy 87.656594 -97.231967) (xy 87.71091 -97.179079) (xy 87.770539 -97.132264)
			(xy 87.834807 -97.092052) (xy 87.902984 -97.0589) (xy 87.9743 -97.033182) (xy 88.047945 -97.01519)
			(xy 88.123085 -97.005128) (xy 88.198869 -97.003109) (xy 88.274439 -97.009158) (xy 88.348937 -97.023205)
			(xy 88.42152 -97.045091) (xy 88.491366 -97.074568) (xy 88.557683 -97.111303) (xy 88.619719 -97.154878)
			(xy 88.676772 -97.2048) (xy 88.728196 -97.260504) (xy 88.773407 -97.321359) (xy 88.811894 -97.386674)
			(xy 88.84322 -97.45571) (xy 88.86703 -97.527685) (xy 88.883055 -97.601783) (xy 88.891114 -97.677164)
			(xy 88.891618 -97.71507) (xy 90.007697 -97.71507) (xy 90.011732 -97.639366) (xy 90.023791 -97.564521)
			(xy 90.043737 -97.49138) (xy 90.071344 -97.420775) (xy 90.1063 -97.353504) (xy 90.148208 -97.290329)
			(xy 90.196594 -97.231967) (xy 90.25091 -97.179079) (xy 90.310539 -97.132264) (xy 90.374807 -97.092052)
			(xy 90.442984 -97.0589) (xy 90.5143 -97.033182) (xy 90.587945 -97.01519) (xy 90.663085 -97.005128)
			(xy 90.738869 -97.003109) (xy 90.814439 -97.009158) (xy 90.888937 -97.023205) (xy 90.96152 -97.045091)
			(xy 91.031366 -97.074568) (xy 91.097683 -97.111303) (xy 91.159719 -97.154878) (xy 91.165664 -97.16008)
			(xy 93.154506 -97.16008) (xy 93.158522 -97.04381) (xy 93.170549 -96.928095) (xy 93.190531 -96.813485)
			(xy 93.218373 -96.700526) (xy 93.253942 -96.589758) (xy 93.297068 -96.481707) (xy 93.347545 -96.376889)
			(xy 93.405134 -96.275804) (xy 93.46956 -96.178932) (xy 93.540515 -96.086736) (xy 93.617662 -95.999655)
			(xy 93.700633 -95.918104) (xy 93.789033 -95.842472) (xy 93.88244 -95.773118) (xy 93.980409 -95.710375)
			(xy 94.082473 -95.654539) (xy 94.188147 -95.605878) (xy 94.296926 -95.564624) (xy 94.408291 -95.530973)
			(xy 94.521714 -95.505085) (xy 94.636651 -95.487084) (xy 94.752557 -95.477055) (xy 94.868879 -95.475047)
			(xy 94.985062 -95.481069) (xy 95.100553 -95.495092) (xy 95.214801 -95.51705) (xy 95.327262 -95.546837)
			(xy 95.4374 -95.584312) (xy 95.54469 -95.629297) (xy 95.648621 -95.681576) (xy 95.748697 -95.740901)
			(xy 95.844443 -95.806989) (xy 95.9354 -95.879525) (xy 96.021136 -95.958164) (xy 96.101243 -96.04253)
			(xy 96.175339 -96.132222) (xy 96.243069 -96.226812) (xy 96.304113 -96.32585) (xy 96.358178 -96.428863)
			(xy 96.405008 -96.53536) (xy 96.444379 -96.644835) (xy 96.476103 -96.756765) (xy 96.500029 -96.870617)
			(xy 96.516043 -96.985849) (xy 96.52407 -97.101911) (xy 96.524572 -97.16008) (xy 96.52407 -97.218249)
			(xy 96.516043 -97.334311) (xy 96.500029 -97.449543) (xy 96.476103 -97.563395) (xy 96.444379 -97.675325)
			(xy 96.405008 -97.7848) (xy 96.358178 -97.891297) (xy 96.304113 -97.99431) (xy 96.243069 -98.093348)
			(xy 96.175339 -98.187938) (xy 96.101243 -98.27763) (xy 96.021136 -98.361996) (xy 95.9354 -98.440635)
			(xy 95.844443 -98.513171) (xy 95.748697 -98.579259) (xy 95.648621 -98.638584) (xy 95.54469 -98.690863)
			(xy 95.4374 -98.735848) (xy 95.327262 -98.773323) (xy 95.214801 -98.80311) (xy 95.100553 -98.825068)
			(xy 94.985062 -98.839091) (xy 94.868879 -98.845113) (xy 94.752557 -98.843105) (xy 94.636651 -98.833076)
			(xy 94.521714 -98.815075) (xy 94.408291 -98.789187) (xy 94.296926 -98.755536) (xy 94.188147 -98.714282)
			(xy 94.082473 -98.665621) (xy 93.980409 -98.609785) (xy 93.88244 -98.547042) (xy 93.789033 -98.477688)
			(xy 93.700633 -98.402056) (xy 93.617662 -98.320505) (xy 93.540515 -98.233424) (xy 93.46956 -98.141228)
			(xy 93.405134 -98.044356) (xy 93.347545 -97.943271) (xy 93.297068 -97.838453) (xy 93.253942 -97.730402)
			(xy 93.218373 -97.619634) (xy 93.190531 -97.506675) (xy 93.170549 -97.392065) (xy 93.158522 -97.27635)
			(xy 93.154506 -97.16008) (xy 91.165664 -97.16008) (xy 91.216772 -97.2048) (xy 91.268196 -97.260504)
			(xy 91.313407 -97.321359) (xy 91.351894 -97.386674) (xy 91.38322 -97.45571) (xy 91.40703 -97.527685)
			(xy 91.423055 -97.601783) (xy 91.431114 -97.677164) (xy 91.431618 -97.71507) (xy 91.431114 -97.752976)
			(xy 91.423055 -97.828357) (xy 91.40703 -97.902455) (xy 91.38322 -97.97443) (xy 91.351894 -98.043466)
			(xy 91.313407 -98.108781) (xy 91.268196 -98.169636) (xy 91.216772 -98.22534) (xy 91.159719 -98.275262)
			(xy 91.097683 -98.318837) (xy 91.031366 -98.355572) (xy 90.96152 -98.385049) (xy 90.888937 -98.406935)
			(xy 90.814439 -98.420982) (xy 90.738869 -98.427031) (xy 90.663085 -98.425012) (xy 90.587945 -98.41495)
			(xy 90.5143 -98.396958) (xy 90.442984 -98.37124) (xy 90.374807 -98.338088) (xy 90.310539 -98.297876)
			(xy 90.25091 -98.251061) (xy 90.196594 -98.198173) (xy 90.148208 -98.139811) (xy 90.1063 -98.076636)
			(xy 90.071344 -98.009365) (xy 90.043737 -97.93876) (xy 90.023791 -97.865619) (xy 90.011732 -97.790774)
			(xy 90.007697 -97.71507) (xy 88.891618 -97.71507) (xy 88.891114 -97.752976) (xy 88.883055 -97.828357)
			(xy 88.86703 -97.902455) (xy 88.84322 -97.97443) (xy 88.811894 -98.043466) (xy 88.773407 -98.108781)
			(xy 88.728196 -98.169636) (xy 88.676772 -98.22534) (xy 88.619719 -98.275262) (xy 88.557683 -98.318837)
			(xy 88.491366 -98.355572) (xy 88.42152 -98.385049) (xy 88.348937 -98.406935) (xy 88.274439 -98.420982)
			(xy 88.198869 -98.427031) (xy 88.123085 -98.425012) (xy 88.047945 -98.41495) (xy 87.9743 -98.396958)
			(xy 87.902984 -98.37124) (xy 87.834807 -98.338088) (xy 87.770539 -98.297876) (xy 87.71091 -98.251061)
			(xy 87.656594 -98.198173) (xy 87.608208 -98.139811) (xy 87.5663 -98.076636) (xy 87.531344 -98.009365)
			(xy 87.503737 -97.93876) (xy 87.483791 -97.865619) (xy 87.471732 -97.790774) (xy 87.467697 -97.71507)
			(xy 86.351618 -97.71507) (xy 86.351114 -97.752976) (xy 86.343055 -97.828357) (xy 86.32703 -97.902455)
			(xy 86.30322 -97.97443) (xy 86.271894 -98.043466) (xy 86.233407 -98.108781) (xy 86.188196 -98.169636)
			(xy 86.136772 -98.22534) (xy 86.079719 -98.275262) (xy 86.017683 -98.318837) (xy 85.951366 -98.355572)
			(xy 85.88152 -98.385049) (xy 85.808937 -98.406935) (xy 85.734439 -98.420982) (xy 85.658869 -98.427031)
			(xy 85.583085 -98.425012) (xy 85.507945 -98.41495) (xy 85.4343 -98.396958) (xy 85.362984 -98.37124)
			(xy 85.294807 -98.338088) (xy 85.230539 -98.297876) (xy 85.17091 -98.251061) (xy 85.116594 -98.198173)
			(xy 85.068208 -98.139811) (xy 85.0263 -98.076636) (xy 84.991344 -98.009365) (xy 84.963737 -97.93876)
			(xy 84.943791 -97.865619) (xy 84.931732 -97.790774) (xy 84.927697 -97.71507) (xy 62.265544 -97.71507)
			(xy 62.259599 -97.720272) (xy 62.197563 -97.763847) (xy 62.131246 -97.800582) (xy 62.0614 -97.830059)
			(xy 61.988817 -97.851945) (xy 61.914319 -97.865992) (xy 61.838749 -97.872041) (xy 61.762965 -97.870022)
			(xy 61.687825 -97.85996) (xy 61.61418 -97.841968) (xy 61.542864 -97.81625) (xy 61.474687 -97.783098)
			(xy 61.410419 -97.742886) (xy 61.35079 -97.696071) (xy 61.296474 -97.643183) (xy 61.248088 -97.584821)
			(xy 61.20618 -97.521646) (xy 61.171224 -97.454375) (xy 61.143617 -97.38377) (xy 61.123671 -97.310629)
			(xy 61.111612 -97.235784) (xy 61.107577 -97.16008) (xy 59.991498 -97.16008) (xy 59.990994 -97.197986)
			(xy 59.982935 -97.273367) (xy 59.96691 -97.347465) (xy 59.9431 -97.41944) (xy 59.911774 -97.488476)
			(xy 59.873287 -97.553791) (xy 59.828076 -97.614646) (xy 59.776652 -97.67035) (xy 59.719599 -97.720272)
			(xy 59.657563 -97.763847) (xy 59.591246 -97.800582) (xy 59.5214 -97.830059) (xy 59.448817 -97.851945)
			(xy 59.374319 -97.865992) (xy 59.298749 -97.872041) (xy 59.222965 -97.870022) (xy 59.147825 -97.85996)
			(xy 59.07418 -97.841968) (xy 59.002864 -97.81625) (xy 58.934687 -97.783098) (xy 58.870419 -97.742886)
			(xy 58.81079 -97.696071) (xy 58.756474 -97.643183) (xy 58.708088 -97.584821) (xy 58.66618 -97.521646)
			(xy 58.631224 -97.454375) (xy 58.603617 -97.38377) (xy 58.583671 -97.310629) (xy 58.571612 -97.235784)
			(xy 58.567577 -97.16008) (xy 57.451498 -97.16008) (xy 57.450994 -97.197986) (xy 57.442935 -97.273367)
			(xy 57.42691 -97.347465) (xy 57.4031 -97.41944) (xy 57.371774 -97.488476) (xy 57.333287 -97.553791)
			(xy 57.288076 -97.614646) (xy 57.236652 -97.67035) (xy 57.179599 -97.720272) (xy 57.117563 -97.763847)
			(xy 57.051246 -97.800582) (xy 56.9814 -97.830059) (xy 56.908817 -97.851945) (xy 56.834319 -97.865992)
			(xy 56.758749 -97.872041) (xy 56.682965 -97.870022) (xy 56.607825 -97.85996) (xy 56.53418 -97.841968)
			(xy 56.462864 -97.81625) (xy 56.394687 -97.783098) (xy 56.330419 -97.742886) (xy 56.27079 -97.696071)
			(xy 56.216474 -97.643183) (xy 56.168088 -97.584821) (xy 56.12618 -97.521646) (xy 56.091224 -97.454375)
			(xy 56.063617 -97.38377) (xy 56.043671 -97.310629) (xy 56.031612 -97.235784) (xy 56.027577 -97.16008)
			(xy 54.911498 -97.16008) (xy 54.910994 -97.197986) (xy 54.902935 -97.273367) (xy 54.88691 -97.347465)
			(xy 54.8631 -97.41944) (xy 54.831774 -97.488476) (xy 54.793287 -97.553791) (xy 54.748076 -97.614646)
			(xy 54.696652 -97.67035) (xy 54.639599 -97.720272) (xy 54.577563 -97.763847) (xy 54.511246 -97.800582)
			(xy 54.4414 -97.830059) (xy 54.368817 -97.851945) (xy 54.294319 -97.865992) (xy 54.218749 -97.872041)
			(xy 54.142965 -97.870022) (xy 54.067825 -97.85996) (xy 53.99418 -97.841968) (xy 53.922864 -97.81625)
			(xy 53.854687 -97.783098) (xy 53.790419 -97.742886) (xy 53.73079 -97.696071) (xy 53.676474 -97.643183)
			(xy 53.628088 -97.584821) (xy 53.58618 -97.521646) (xy 53.551224 -97.454375) (xy 53.523617 -97.38377)
			(xy 53.503671 -97.310629) (xy 53.491612 -97.235784) (xy 53.487577 -97.16008) (xy 52.371498 -97.16008)
			(xy 52.370994 -97.197986) (xy 52.362935 -97.273367) (xy 52.34691 -97.347465) (xy 52.3231 -97.41944)
			(xy 52.291774 -97.488476) (xy 52.253287 -97.553791) (xy 52.208076 -97.614646) (xy 52.156652 -97.67035)
			(xy 52.099599 -97.720272) (xy 52.037563 -97.763847) (xy 51.971246 -97.800582) (xy 51.9014 -97.830059)
			(xy 51.828817 -97.851945) (xy 51.754319 -97.865992) (xy 51.678749 -97.872041) (xy 51.602965 -97.870022)
			(xy 51.527825 -97.85996) (xy 51.45418 -97.841968) (xy 51.382864 -97.81625) (xy 51.314687 -97.783098)
			(xy 51.250419 -97.742886) (xy 51.19079 -97.696071) (xy 51.136474 -97.643183) (xy 51.088088 -97.584821)
			(xy 51.04618 -97.521646) (xy 51.011224 -97.454375) (xy 50.983617 -97.38377) (xy 50.963671 -97.310629)
			(xy 50.951612 -97.235784) (xy 50.947577 -97.16008) (xy 49.831498 -97.16008) (xy 49.830994 -97.197986)
			(xy 49.822935 -97.273367) (xy 49.80691 -97.347465) (xy 49.7831 -97.41944) (xy 49.751774 -97.488476)
			(xy 49.713287 -97.553791) (xy 49.668076 -97.614646) (xy 49.616652 -97.67035) (xy 49.559599 -97.720272)
			(xy 49.497563 -97.763847) (xy 49.431246 -97.800582) (xy 49.3614 -97.830059) (xy 49.288817 -97.851945)
			(xy 49.214319 -97.865992) (xy 49.138749 -97.872041) (xy 49.062965 -97.870022) (xy 48.987825 -97.85996)
			(xy 48.91418 -97.841968) (xy 48.842864 -97.81625) (xy 48.774687 -97.783098) (xy 48.710419 -97.742886)
			(xy 48.65079 -97.696071) (xy 48.596474 -97.643183) (xy 48.548088 -97.584821) (xy 48.50618 -97.521646)
			(xy 48.471224 -97.454375) (xy 48.443617 -97.38377) (xy 48.423671 -97.310629) (xy 48.411612 -97.235784)
			(xy 48.407577 -97.16008) (xy 47.291498 -97.16008) (xy 47.290994 -97.197986) (xy 47.282935 -97.273367)
			(xy 47.26691 -97.347465) (xy 47.2431 -97.41944) (xy 47.211774 -97.488476) (xy 47.173287 -97.553791)
			(xy 47.128076 -97.614646) (xy 47.076652 -97.67035) (xy 47.019599 -97.720272) (xy 46.957563 -97.763847)
			(xy 46.891246 -97.800582) (xy 46.8214 -97.830059) (xy 46.748817 -97.851945) (xy 46.674319 -97.865992)
			(xy 46.598749 -97.872041) (xy 46.522965 -97.870022) (xy 46.447825 -97.85996) (xy 46.37418 -97.841968)
			(xy 46.302864 -97.81625) (xy 46.234687 -97.783098) (xy 46.170419 -97.742886) (xy 46.11079 -97.696071)
			(xy 46.056474 -97.643183) (xy 46.008088 -97.584821) (xy 45.96618 -97.521646) (xy 45.931224 -97.454375)
			(xy 45.903617 -97.38377) (xy 45.883671 -97.310629) (xy 45.871612 -97.235784) (xy 45.867577 -97.16008)
			(xy 44.751244 -97.16008) (xy 44.751244 -97.871788) (xy 43.328336 -97.871788) (xy 43.328336 -96.448372)
			(xy 43.055152 -96.448372) (xy 43.014974 -96.539744) (xy 42.961022 -96.64254) (xy 42.900108 -96.741368)
			(xy 42.83252 -96.835759) (xy 42.758581 -96.925261) (xy 42.678643 -97.009449) (xy 42.593088 -97.087922)
			(xy 42.502322 -97.160305) (xy 42.406779 -97.226254) (xy 42.306914 -97.285454) (xy 42.203202 -97.337623)
			(xy 42.096139 -97.382512) (xy 41.986233 -97.419908) (xy 41.874009 -97.449633) (xy 41.760003 -97.471544)
			(xy 41.644756 -97.485537) (xy 41.528818 -97.491546) (xy 41.412742 -97.489543) (xy 41.29708 -97.479535)
			(xy 41.182385 -97.461572) (xy 41.069202 -97.435739) (xy 40.958071 -97.402159) (xy 40.849522 -97.360991)
			(xy 40.744072 -97.312433) (xy 40.642223 -97.256716) (xy 40.54446 -97.194104) (xy 40.45125 -97.124897)
			(xy 40.363037 -97.049424) (xy 40.280241 -96.968045) (xy 40.203257 -96.881148) (xy 40.132452 -96.789147)
			(xy 40.068162 -96.69248) (xy 40.010695 -96.591608) (xy 39.960324 -96.487011) (xy 39.917289 -96.379188)
			(xy 39.881795 -96.268654) (xy 39.854012 -96.155934) (xy 39.834072 -96.041566) (xy 39.82207 -95.926094)
			(xy 39.818063 -95.81007) (xy 36.437073 -95.81007) (xy 36.431719 -95.828889) (xy 36.400327 -95.909921)
			(xy 36.361593 -95.98771) (xy 36.315846 -96.061594) (xy 36.263477 -96.130941) (xy 36.204933 -96.195161)
			(xy 36.140713 -96.253705) (xy 36.071366 -96.306074) (xy 35.997482 -96.351821) (xy 35.919693 -96.390555)
			(xy 35.838661 -96.421947) (xy 35.755079 -96.445728) (xy 35.669659 -96.461696) (xy 35.58313 -96.469714)
			(xy 35.49623 -96.469714) (xy 35.409701 -96.461696) (xy 35.324281 -96.445728) (xy 35.240699 -96.421947)
			(xy 35.159667 -96.390555) (xy 35.081878 -96.351821) (xy 35.007994 -96.306074) (xy 34.938647 -96.253705)
			(xy 34.874427 -96.195161) (xy 34.815883 -96.130941) (xy 34.763514 -96.061594) (xy 34.717767 -95.98771)
			(xy 34.679033 -95.909921) (xy 34.647641 -95.828889) (xy 34.62386 -95.745307) (xy 34.607892 -95.659887)
			(xy 34.599874 -95.573358) (xy 33.77692 -95.573358) (xy 33.77692 -98.113358) (xy 34.599874 -98.113358)
			(xy 34.599874 -98.026458) (xy 34.607892 -97.939929) (xy 34.62386 -97.854509) (xy 34.647641 -97.770927)
			(xy 34.679033 -97.689895) (xy 34.717767 -97.612106) (xy 34.763514 -97.538222) (xy 34.815883 -97.468875)
			(xy 34.874427 -97.404655) (xy 34.938647 -97.346111) (xy 35.007994 -97.293742) (xy 35.081878 -97.247995)
			(xy 35.159667 -97.209261) (xy 35.240699 -97.177869) (xy 35.324281 -97.154088) (xy 35.409701 -97.13812)
			(xy 35.49623 -97.130102) (xy 35.58313 -97.130102) (xy 35.669659 -97.13812) (xy 35.755079 -97.154088)
			(xy 35.838661 -97.177869) (xy 35.919693 -97.209261) (xy 35.997482 -97.247995) (xy 36.071366 -97.293742)
			(xy 36.140713 -97.346111) (xy 36.204933 -97.404655) (xy 36.263477 -97.468875) (xy 36.315846 -97.538222)
			(xy 36.361593 -97.612106) (xy 36.400327 -97.689895) (xy 36.431719 -97.770927) (xy 36.4555 -97.854509)
			(xy 36.471468 -97.939929) (xy 36.479486 -98.026458) (xy 36.479988 -98.069908) (xy 36.479486 -98.113358)
			(xy 36.471468 -98.199887) (xy 36.4555 -98.285307) (xy 36.431719 -98.368889) (xy 36.400327 -98.449921)
			(xy 36.361593 -98.52771) (xy 36.315846 -98.601594) (xy 36.263477 -98.670941) (xy 36.204933 -98.735161)
			(xy 36.140713 -98.793705) (xy 36.071366 -98.846074) (xy 35.997482 -98.891821) (xy 35.919693 -98.930555)
			(xy 35.838661 -98.961947) (xy 35.755079 -98.985728) (xy 35.669659 -99.001696) (xy 35.58313 -99.009714)
			(xy 35.49623 -99.009714) (xy 35.409701 -99.001696) (xy 35.324281 -98.985728) (xy 35.240699 -98.961947)
			(xy 35.159667 -98.930555) (xy 35.081878 -98.891821) (xy 35.007994 -98.846074) (xy 34.938647 -98.793705)
			(xy 34.874427 -98.735161) (xy 34.815883 -98.670941) (xy 34.763514 -98.601594) (xy 34.717767 -98.52771)
			(xy 34.679033 -98.449921) (xy 34.647641 -98.368889) (xy 34.62386 -98.285307) (xy 34.607892 -98.199887)
			(xy 34.599874 -98.113358) (xy 33.77692 -98.113358) (xy 33.77692 -100.609893) (xy 34.598816 -100.609893)
			(xy 34.60275 -100.523943) (xy 34.61452 -100.438712) (xy 34.634027 -100.354912) (xy 34.661107 -100.273245)
			(xy 34.695534 -100.194393) (xy 34.73702 -100.119015) (xy 34.785218 -100.047743) (xy 34.839726 -99.981171)
			(xy 34.900087 -99.919857) (xy 34.965797 -99.864314) (xy 35.036306 -99.815005) (xy 35.111025 -99.772344)
			(xy 35.189328 -99.736686) (xy 35.270561 -99.708331) (xy 35.354045 -99.687514) (xy 35.439082 -99.674411)
			(xy 35.524959 -99.669131) (xy 35.61096 -99.671718) (xy 35.696366 -99.682151) (xy 35.780461 -99.700341)
			(xy 35.862542 -99.726138) (xy 35.941924 -99.759324) (xy 36.017943 -99.799624) (xy 36.089962 -99.8467)
			(xy 36.15738 -99.900157) (xy 36.219632 -99.95955) (xy 36.276199 -100.024381) (xy 36.326607 -100.094109)
			(xy 36.370434 -100.168149) (xy 36.38931 -100.20681) (xy 36.405058 -100.23983) (xy 36.467034 -100.2792)
			(xy 38.683946 -100.2792) (xy 39.941246 -101.5365) (xy 39.968678 -101.546152) (xy 39.995412 -101.556004)
			(xy 40.045867 -101.582466) (xy 40.091825 -101.616138) (xy 40.132264 -101.65627) (xy 40.166285 -101.70197)
			(xy 40.193131 -101.752222) (xy 40.212204 -101.805908) (xy 40.223082 -101.861833) (xy 40.22552 -101.918754)
			(xy 40.219466 -101.975404) (xy 40.212772 -102.003098) (xy 40.212772 -102.027736) (xy 86.51062 -102.027736)
			(xy 86.514691 -101.972114) (xy 86.526817 -101.917677) (xy 86.54674 -101.865586) (xy 86.574036 -101.816951)
			(xy 86.608122 -101.772808) (xy 86.648271 -101.734099) (xy 86.693629 -101.701648) (xy 86.743229 -101.676147)
			(xy 86.796013 -101.65814) (xy 86.850856 -101.64801) (xy 86.90659 -101.645973) (xy 86.962027 -101.652073)
			(xy 87.015984 -101.666179) (xy 87.067313 -101.687991) (xy 87.114919 -101.717045) (xy 87.157787 -101.75272)
			(xy 87.195004 -101.794257) (xy 87.225777 -101.84077) (xy 87.249449 -101.891267) (xy 87.265517 -101.944674)
			(xy 87.273637 -101.99985) (xy 87.274146 -102.027736) (xy 87.273757 -102.049072) (xy 92.029532 -102.049072)
			(xy 92.033603 -101.99345) (xy 92.045729 -101.939013) (xy 92.065652 -101.886922) (xy 92.092948 -101.838287)
			(xy 92.127034 -101.794144) (xy 92.167183 -101.755435) (xy 92.212541 -101.722984) (xy 92.262141 -101.697483)
			(xy 92.314925 -101.679476) (xy 92.369768 -101.669346) (xy 92.425502 -101.667309) (xy 92.480939 -101.673409)
			(xy 92.534896 -101.687515) (xy 92.586225 -101.709327) (xy 92.633831 -101.738381) (xy 92.676699 -101.774056)
			(xy 92.713916 -101.815593) (xy 92.744689 -101.862106) (xy 92.768361 -101.912603) (xy 92.77228 -101.925628)
			(xy 94.75165 -101.925628) (xy 94.755721 -101.870006) (xy 94.767847 -101.815569) (xy 94.78777 -101.763478)
			(xy 94.815066 -101.714843) (xy 94.849152 -101.6707) (xy 94.889301 -101.631991) (xy 94.934659 -101.59954)
			(xy 94.984259 -101.574039) (xy 95.037043 -101.556032) (xy 95.091886 -101.545902) (xy 95.14762 -101.543865)
			(xy 95.203057 -101.549965) (xy 95.257014 -101.564071) (xy 95.308343 -101.585883) (xy 95.355949 -101.614937)
			(xy 95.398817 -101.650612) (xy 95.436034 -101.692149) (xy 95.466807 -101.738662) (xy 95.490479 -101.789159)
			(xy 95.506547 -101.842566) (xy 95.514667 -101.897742) (xy 95.515176 -101.925628) (xy 95.514667 -101.953514)
			(xy 95.506547 -102.00869) (xy 95.490479 -102.062097) (xy 95.466807 -102.112594) (xy 95.436034 -102.159107)
			(xy 95.398817 -102.200644) (xy 95.355949 -102.236319) (xy 95.308343 -102.265373) (xy 95.257014 -102.287185)
			(xy 95.203057 -102.301291) (xy 95.14762 -102.307391) (xy 95.091886 -102.305354) (xy 95.037043 -102.295224)
			(xy 94.984259 -102.277217) (xy 94.934659 -102.251716) (xy 94.889301 -102.219265) (xy 94.849152 -102.180556)
			(xy 94.815066 -102.136413) (xy 94.78777 -102.087778) (xy 94.767847 -102.035687) (xy 94.755721 -101.98125)
			(xy 94.75165 -101.925628) (xy 92.77228 -101.925628) (xy 92.784429 -101.96601) (xy 92.792549 -102.021186)
			(xy 92.793058 -102.049072) (xy 92.792549 -102.076958) (xy 92.784429 -102.132134) (xy 92.768361 -102.185541)
			(xy 92.744689 -102.236038) (xy 92.713916 -102.282551) (xy 92.676699 -102.324088) (xy 92.633831 -102.359763)
			(xy 92.586225 -102.388817) (xy 92.534896 -102.410629) (xy 92.480939 -102.424735) (xy 92.425502 -102.430835)
			(xy 92.369768 -102.428798) (xy 92.314925 -102.418668) (xy 92.262141 -102.400661) (xy 92.212541 -102.37516)
			(xy 92.167183 -102.342709) (xy 92.127034 -102.304) (xy 92.092948 -102.259857) (xy 92.065652 -102.211222)
			(xy 92.045729 -102.159131) (xy 92.033603 -102.104694) (xy 92.029532 -102.049072) (xy 87.273757 -102.049072)
			(xy 87.273637 -102.055622) (xy 87.265517 -102.110798) (xy 87.249449 -102.164205) (xy 87.225777 -102.214702)
			(xy 87.195004 -102.261215) (xy 87.157787 -102.302752) (xy 87.114919 -102.338427) (xy 87.067313 -102.367481)
			(xy 87.015984 -102.389293) (xy 86.962027 -102.403399) (xy 86.90659 -102.409499) (xy 86.850856 -102.407462)
			(xy 86.796013 -102.397332) (xy 86.743229 -102.379325) (xy 86.693629 -102.353824) (xy 86.648271 -102.321373)
			(xy 86.608122 -102.282664) (xy 86.574036 -102.238521) (xy 86.54674 -102.189886) (xy 86.526817 -102.137795)
			(xy 86.514691 -102.083358) (xy 86.51062 -102.027736) (xy 40.212772 -102.027736) (xy 40.212772 -102.570026)
			(xy 40.158452 -102.624382) (xy 84.84057 -102.624382) (xy 84.844641 -102.56876) (xy 84.856767 -102.514323)
			(xy 84.87669 -102.462232) (xy 84.903986 -102.413597) (xy 84.938072 -102.369454) (xy 84.978221 -102.330745)
			(xy 85.023579 -102.298294) (xy 85.073179 -102.272793) (xy 85.125963 -102.254786) (xy 85.180806 -102.244656)
			(xy 85.23654 -102.242619) (xy 85.291977 -102.248719) (xy 85.345934 -102.262825) (xy 85.397263 -102.284637)
			(xy 85.444869 -102.313691) (xy 85.487737 -102.349366) (xy 85.524954 -102.390903) (xy 85.555727 -102.437416)
			(xy 85.579399 -102.487913) (xy 85.595467 -102.54132) (xy 85.603587 -102.596496) (xy 85.604096 -102.624382)
			(xy 85.603587 -102.652268) (xy 85.597411 -102.694232) (xy 93.32036 -102.694232) (xy 93.324431 -102.63861)
			(xy 93.336557 -102.584173) (xy 93.35648 -102.532082) (xy 93.383776 -102.483447) (xy 93.417862 -102.439304)
			(xy 93.458011 -102.400595) (xy 93.503369 -102.368144) (xy 93.552969 -102.342643) (xy 93.605753 -102.324636)
			(xy 93.660596 -102.314506) (xy 93.71633 -102.312469) (xy 93.771767 -102.318569) (xy 93.825724 -102.332675)
			(xy 93.877053 -102.354487) (xy 93.924659 -102.383541) (xy 93.967527 -102.419216) (xy 94.004744 -102.460753)
			(xy 94.035517 -102.507266) (xy 94.059189 -102.557763) (xy 94.075257 -102.61117) (xy 94.07593 -102.615746)
			(xy 96.360994 -102.615746) (xy 96.365065 -102.560124) (xy 96.377191 -102.505687) (xy 96.397114 -102.453596)
			(xy 96.42441 -102.404961) (xy 96.458496 -102.360818) (xy 96.498645 -102.322109) (xy 96.544003 -102.289658)
			(xy 96.593603 -102.264157) (xy 96.646387 -102.24615) (xy 96.70123 -102.23602) (xy 96.756964 -102.233983)
			(xy 96.812401 -102.240083) (xy 96.866358 -102.254189) (xy 96.917687 -102.276001) (xy 96.965293 -102.305055)
			(xy 97.008161 -102.34073) (xy 97.045378 -102.382267) (xy 97.076151 -102.42878) (xy 97.099823 -102.479277)
			(xy 97.115891 -102.532684) (xy 97.124011 -102.58786) (xy 97.12452 -102.615746) (xy 97.124011 -102.643632)
			(xy 97.115891 -102.698808) (xy 97.099823 -102.752215) (xy 97.076151 -102.802712) (xy 97.045378 -102.849225)
			(xy 97.008161 -102.890762) (xy 96.965293 -102.926437) (xy 96.917687 -102.955491) (xy 96.866358 -102.977303)
			(xy 96.812401 -102.991409) (xy 96.756964 -102.997509) (xy 96.70123 -102.995472) (xy 96.646387 -102.985342)
			(xy 96.593603 -102.967335) (xy 96.544003 -102.941834) (xy 96.498645 -102.909383) (xy 96.458496 -102.870674)
			(xy 96.42441 -102.826531) (xy 96.397114 -102.777896) (xy 96.377191 -102.725805) (xy 96.365065 -102.671368)
			(xy 96.360994 -102.615746) (xy 94.07593 -102.615746) (xy 94.083377 -102.666346) (xy 94.083886 -102.694232)
			(xy 94.083377 -102.722118) (xy 94.075257 -102.777294) (xy 94.059189 -102.830701) (xy 94.035517 -102.881198)
			(xy 94.004744 -102.927711) (xy 93.967527 -102.969248) (xy 93.924659 -103.004923) (xy 93.877053 -103.033977)
			(xy 93.825724 -103.055789) (xy 93.771767 -103.069895) (xy 93.71633 -103.075995) (xy 93.660596 -103.073958)
			(xy 93.605753 -103.063828) (xy 93.552969 -103.045821) (xy 93.503369 -103.02032) (xy 93.458011 -102.987869)
			(xy 93.417862 -102.94916) (xy 93.383776 -102.905017) (xy 93.35648 -102.856382) (xy 93.336557 -102.804291)
			(xy 93.324431 -102.749854) (xy 93.32036 -102.694232) (xy 85.597411 -102.694232) (xy 85.595467 -102.707444)
			(xy 85.579399 -102.760851) (xy 85.555727 -102.811348) (xy 85.524954 -102.857861) (xy 85.487737 -102.899398)
			(xy 85.444869 -102.935073) (xy 85.397263 -102.964127) (xy 85.345934 -102.985939) (xy 85.291977 -103.000045)
			(xy 85.23654 -103.006145) (xy 85.180806 -103.004108) (xy 85.125963 -102.993978) (xy 85.073179 -102.975971)
			(xy 85.023579 -102.95047) (xy 84.978221 -102.918019) (xy 84.938072 -102.87931) (xy 84.903986 -102.835167)
			(xy 84.87669 -102.786532) (xy 84.856767 -102.734441) (xy 84.844641 -102.680004) (xy 84.84057 -102.624382)
			(xy 40.158452 -102.624382) (xy 39.825676 -102.957376) (xy 39.825676 -103.058214) (xy 39.837614 -103.070152)
			(xy 39.849956 -103.081766) (xy 39.879324 -103.098651) (xy 39.912103 -103.107202) (xy 39.945976 -103.106816)
			(xy 39.978552 -103.09752) (xy 39.993316 -103.089202) (xy 40.023212 -103.071799) (xy 40.086707 -103.044351)
			(xy 40.153338 -103.025764) (xy 40.221873 -103.016381) (xy 40.25646 -103.015796) (xy 40.989758 -103.015796)
			(xy 41.021709 -103.016174) (xy 41.085108 -103.024178) (xy 41.147004 -103.040066) (xy 41.206421 -103.063586)
			(xy 41.262421 -103.094368) (xy 41.314121 -103.131927) (xy 41.360705 -103.175669) (xy 41.40144 -103.224905)
			(xy 41.435682 -103.278859) (xy 41.462892 -103.336679) (xy 41.464516 -103.341678) (xy 94.72625 -103.341678)
			(xy 94.730321 -103.286056) (xy 94.742447 -103.231619) (xy 94.76237 -103.179528) (xy 94.789666 -103.130893)
			(xy 94.823752 -103.08675) (xy 94.863901 -103.048041) (xy 94.909259 -103.01559) (xy 94.958859 -102.990089)
			(xy 95.011643 -102.972082) (xy 95.066486 -102.961952) (xy 95.12222 -102.959915) (xy 95.177657 -102.966015)
			(xy 95.231614 -102.980121) (xy 95.282943 -103.001933) (xy 95.330549 -103.030987) (xy 95.373417 -103.066662)
			(xy 95.410634 -103.108199) (xy 95.441407 -103.154712) (xy 95.465079 -103.205209) (xy 95.481147 -103.258616)
			(xy 95.489267 -103.313792) (xy 95.489776 -103.341678) (xy 95.489267 -103.369564) (xy 95.481147 -103.42474)
			(xy 95.465079 -103.478147) (xy 95.441407 -103.528644) (xy 95.410634 -103.575157) (xy 95.373417 -103.616694)
			(xy 95.330549 -103.652369) (xy 95.282943 -103.681423) (xy 95.231614 -103.703235) (xy 95.177657 -103.717341)
			(xy 95.12222 -103.723441) (xy 95.066486 -103.721404) (xy 95.011643 -103.711274) (xy 94.958859 -103.693267)
			(xy 94.909259 -103.667766) (xy 94.863901 -103.635315) (xy 94.823752 -103.596606) (xy 94.789666 -103.552463)
			(xy 94.76237 -103.503828) (xy 94.742447 -103.451737) (xy 94.730321 -103.3973) (xy 94.72625 -103.341678)
			(xy 41.464516 -103.341678) (xy 41.48264 -103.397453) (xy 41.494615 -103.460224) (xy 41.498628 -103.524)
			(xy 41.494615 -103.587776) (xy 41.48264 -103.650547) (xy 41.462892 -103.711321) (xy 41.435682 -103.769141)
			(xy 41.40144 -103.823095) (xy 41.360705 -103.872331) (xy 41.314121 -103.916073) (xy 41.279996 -103.940864)
			(xy 83.171282 -103.940864) (xy 83.175353 -103.885242) (xy 83.187479 -103.830805) (xy 83.207402 -103.778714)
			(xy 83.234698 -103.730079) (xy 83.268784 -103.685936) (xy 83.308933 -103.647227) (xy 83.354291 -103.614776)
			(xy 83.403891 -103.589275) (xy 83.456675 -103.571268) (xy 83.511518 -103.561138) (xy 83.567252 -103.559101)
			(xy 83.622689 -103.565201) (xy 83.676646 -103.579307) (xy 83.727975 -103.601119) (xy 83.775581 -103.630173)
			(xy 83.818449 -103.665848) (xy 83.855666 -103.707385) (xy 83.886439 -103.753898) (xy 83.910111 -103.804395)
			(xy 83.926179 -103.857802) (xy 83.934299 -103.912978) (xy 83.934808 -103.940864) (xy 83.934299 -103.96875)
			(xy 83.926179 -104.023926) (xy 83.910111 -104.077333) (xy 83.886439 -104.12783) (xy 83.855666 -104.174343)
			(xy 83.818449 -104.21588) (xy 83.775581 -104.251555) (xy 83.727975 -104.280609) (xy 83.676646 -104.302421)
			(xy 83.622689 -104.316527) (xy 83.567252 -104.322627) (xy 83.511518 -104.32059) (xy 83.456675 -104.31046)
			(xy 83.403891 -104.292453) (xy 83.354291 -104.266952) (xy 83.308933 -104.234501) (xy 83.268784 -104.195792)
			(xy 83.234698 -104.151649) (xy 83.207402 -104.103014) (xy 83.187479 -104.050923) (xy 83.175353 -103.996486)
			(xy 83.171282 -103.940864) (xy 41.279996 -103.940864) (xy 41.262421 -103.953632) (xy 41.206421 -103.984414)
			(xy 41.147004 -104.007934) (xy 41.085108 -104.023822) (xy 41.021709 -104.031826) (xy 40.989758 -104.032304)
			(xy 40.256206 -104.032304) (xy 40.223538 -104.031806) (xy 40.15874 -104.023433) (xy 40.095549 -104.006825)
			(xy 40.035009 -103.982256) (xy 39.978116 -103.95013) (xy 39.95166 -103.930958) (xy 39.917878 -103.905558)
			(xy 39.100252 -103.905558) (xy 39.100252 -103.621332) (xy 39.094101 -103.597482) (xy 39.087468 -103.548677)
			(xy 39.087044 -103.52405) (xy 39.087044 -102.65156) (xy 39.43731 -102.301294) (xy 39.448746 -102.289194)
			(xy 39.465447 -102.260405) (xy 39.474123 -102.228272) (xy 39.474648 -102.211632) (xy 39.474648 -102.006654)
			(xy 39.473632 -102.004114) (xy 38.410134 -100.940616) (xy 36.467034 -100.940616) (xy 36.405058 -100.979986)
			(xy 36.38931 -101.013006) (xy 36.370427 -101.051664) (xy 36.326599 -101.125704) (xy 36.27619 -101.19543)
			(xy 36.219622 -101.260261) (xy 36.157369 -101.319652) (xy 36.08995 -101.373109) (xy 36.01793 -101.420183)
			(xy 35.941911 -101.460482) (xy 35.862529 -101.493667) (xy 35.780447 -101.519463) (xy 35.696351 -101.537652)
			(xy 35.610946 -101.548083) (xy 35.524945 -101.550669) (xy 35.439067 -101.545387) (xy 35.354031 -101.532283)
			(xy 35.270548 -101.511465) (xy 35.189315 -101.483109) (xy 35.111012 -101.44745) (xy 35.036294 -101.404787)
			(xy 34.965786 -101.355477) (xy 34.900077 -101.299933) (xy 34.839717 -101.238618) (xy 34.78521 -101.172046)
			(xy 34.737012 -101.100772) (xy 34.695527 -101.025394) (xy 34.661101 -100.946542) (xy 34.634023 -100.864874)
			(xy 34.614518 -100.781074) (xy 34.602749 -100.695843) (xy 34.598816 -100.609893) (xy 33.77692 -100.609893)
			(xy 33.77692 -103.193358) (xy 34.599874 -103.193358) (xy 34.599874 -103.106458) (xy 34.607892 -103.019929)
			(xy 34.62386 -102.934509) (xy 34.647641 -102.850927) (xy 34.679033 -102.769895) (xy 34.717767 -102.692106)
			(xy 34.763514 -102.618222) (xy 34.815883 -102.548875) (xy 34.874427 -102.484655) (xy 34.938647 -102.426111)
			(xy 35.007994 -102.373742) (xy 35.081878 -102.327995) (xy 35.159667 -102.289261) (xy 35.240699 -102.257869)
			(xy 35.324281 -102.234088) (xy 35.409701 -102.21812) (xy 35.49623 -102.210102) (xy 35.58313 -102.210102)
			(xy 35.669659 -102.21812) (xy 35.755079 -102.234088) (xy 35.838661 -102.257869) (xy 35.919693 -102.289261)
			(xy 35.997482 -102.327995) (xy 36.071366 -102.373742) (xy 36.140713 -102.426111) (xy 36.204933 -102.484655)
			(xy 36.263477 -102.548875) (xy 36.315846 -102.618222) (xy 36.361593 -102.692106) (xy 36.400327 -102.769895)
			(xy 36.431719 -102.850927) (xy 36.4555 -102.934509) (xy 36.471468 -103.019929) (xy 36.479486 -103.106458)
			(xy 36.479988 -103.149908) (xy 36.479486 -103.193358) (xy 36.471468 -103.279887) (xy 36.4555 -103.365307)
			(xy 36.431719 -103.448889) (xy 36.400327 -103.529921) (xy 36.361593 -103.60771) (xy 36.315846 -103.681594)
			(xy 36.263477 -103.750941) (xy 36.204933 -103.815161) (xy 36.140713 -103.873705) (xy 36.071366 -103.926074)
			(xy 35.997482 -103.971821) (xy 35.919693 -104.010555) (xy 35.838661 -104.041947) (xy 35.755079 -104.065728)
			(xy 35.669659 -104.081696) (xy 35.58313 -104.089714) (xy 35.49623 -104.089714) (xy 35.409701 -104.081696)
			(xy 35.324281 -104.065728) (xy 35.240699 -104.041947) (xy 35.159667 -104.010555) (xy 35.081878 -103.971821)
			(xy 35.007994 -103.926074) (xy 34.938647 -103.873705) (xy 34.874427 -103.815161) (xy 34.815883 -103.750941)
			(xy 34.763514 -103.681594) (xy 34.717767 -103.60771) (xy 34.679033 -103.529921) (xy 34.647641 -103.448889)
			(xy 34.62386 -103.365307) (xy 34.607892 -103.279887) (xy 34.599874 -103.193358) (xy 33.77692 -103.193358)
			(xy 33.77692 -107.173268) (xy 34.325052 -107.7214) (xy 34.682176 -107.7214) (xy 34.697007 -107.720963)
			(xy 34.725867 -107.714115) (xy 34.752375 -107.700804) (xy 34.775105 -107.681748) (xy 34.784284 -107.670092)
			(xy 34.809867 -107.636336) (xy 34.866203 -107.573081) (xy 34.928 -107.515149) (xy 34.994758 -107.463011)
			(xy 35.065935 -107.41709) (xy 35.140955 -107.377758) (xy 35.219209 -107.345334) (xy 35.300062 -107.32008)
			(xy 35.382859 -107.302202) (xy 35.466928 -107.291845) (xy 35.551589 -107.289092) (xy 35.636153 -107.293966)
			(xy 35.67811 -107.29976) (xy 35.708082 -107.304332) (xy 35.764978 -107.285536) (xy 36.813236 -106.237278)
			(xy 36.824598 -106.22513) (xy 36.841204 -106.196326) (xy 36.849797 -106.164208) (xy 36.849792 -106.130959)
			(xy 36.841191 -106.098843) (xy 36.824578 -106.070043) (xy 36.801082 -106.046519) (xy 36.772303 -106.02987)
			(xy 36.740197 -106.021228) (xy 36.723574 -106.020616) (xy 36.467034 -106.020616) (xy 36.405058 -106.059986)
			(xy 36.38931 -106.093006) (xy 36.370433 -106.131667) (xy 36.326605 -106.205707) (xy 36.276195 -106.275435)
			(xy 36.219627 -106.340265) (xy 36.157373 -106.399657) (xy 36.089954 -106.453114) (xy 36.017934 -106.500189)
			(xy 35.941914 -106.540488) (xy 35.862531 -106.573674) (xy 35.780448 -106.599469) (xy 35.696352 -106.617659)
			(xy 35.610946 -106.62809) (xy 35.524945 -106.630675) (xy 35.439066 -106.625394) (xy 35.35403 -106.61229)
			(xy 35.270546 -106.591472) (xy 35.189312 -106.563115) (xy 35.111009 -106.527456) (xy 35.03629 -106.484793)
			(xy 34.965782 -106.435483) (xy 34.900072 -106.379938) (xy 34.839711 -106.318623) (xy 34.785204 -106.25205)
			(xy 34.737006 -106.180776) (xy 34.695521 -106.105397) (xy 34.661095 -106.026544) (xy 34.634016 -105.944876)
			(xy 34.614511 -105.861075) (xy 34.602742 -105.775843) (xy 34.598809 -105.689893) (xy 34.602744 -105.603942)
			(xy 34.614513 -105.51871) (xy 34.63402 -105.43491) (xy 34.6611 -105.353242) (xy 34.695527 -105.27439)
			(xy 34.737014 -105.199012) (xy 34.785213 -105.127739) (xy 34.839721 -105.061167) (xy 34.900083 -104.999852)
			(xy 34.965793 -104.944308) (xy 35.036303 -104.894999) (xy 35.111022 -104.852338) (xy 35.189326 -104.81668)
			(xy 35.270559 -104.788324) (xy 35.354044 -104.767508) (xy 35.439081 -104.754405) (xy 35.524959 -104.749124)
			(xy 35.610961 -104.751711) (xy 35.696367 -104.762144) (xy 35.780462 -104.780334) (xy 35.862545 -104.806131)
			(xy 35.941927 -104.839318) (xy 36.017946 -104.879618) (xy 36.089966 -104.926694) (xy 36.157384 -104.980152)
			(xy 36.219637 -105.039545) (xy 36.276204 -105.104377) (xy 36.326613 -105.174105) (xy 36.37044 -105.248146)
			(xy 36.38931 -105.28681) (xy 36.405058 -105.31983) (xy 36.467034 -105.3592) (xy 37.370512 -105.3592)
			(xy 37.638228 -105.091484) (xy 39.324026 -105.091484) (xy 39.324026 -105.066084) (xy 40.087042 -105.066084)
			(xy 40.087042 -105.090976) (xy 40.577516 -105.090976) (xy 40.577516 -105.065322) (xy 41.340532 -105.065322)
			(xy 41.340532 -105.88498) (xy 41.360438 -105.908261) (xy 41.395123 -105.95875) (xy 41.423492 -106.013041)
			(xy 41.445134 -106.070346) (xy 41.459735 -106.129835) (xy 41.467084 -106.190648) (xy 41.467532 -106.221276)
			(xy 41.467532 -106.900726) (xy 41.467031 -106.932671) (xy 41.459023 -106.996057) (xy 41.443134 -107.05794)
			(xy 41.419615 -107.117344) (xy 41.395898 -107.160483) (xy 47.373784 -107.160483) (xy 47.373784 -107.079373)
			(xy 47.381734 -106.998654) (xy 47.397557 -106.919103) (xy 47.421102 -106.841487) (xy 47.452141 -106.766551)
			(xy 47.490376 -106.695019) (xy 47.535438 -106.627579) (xy 47.586893 -106.56488) (xy 47.644246 -106.507527)
			(xy 47.706945 -106.456072) (xy 47.774385 -106.41101) (xy 47.845917 -106.372775) (xy 47.920853 -106.341736)
			(xy 47.998469 -106.318191) (xy 48.07802 -106.302368) (xy 48.158739 -106.294418) (xy 48.239849 -106.294418)
			(xy 48.320568 -106.302368) (xy 48.400119 -106.318191) (xy 48.477735 -106.341736) (xy 48.552671 -106.372775)
			(xy 48.624203 -106.41101) (xy 48.691643 -106.456072) (xy 48.754342 -106.507527) (xy 48.811695 -106.56488)
			(xy 48.86315 -106.627579) (xy 48.908212 -106.695019) (xy 48.946447 -106.766551) (xy 48.977486 -106.841487)
			(xy 49.001031 -106.919103) (xy 49.012532 -106.976926) (xy 71.010272 -106.976926) (xy 71.010272 -106.00436)
			(xy 71.010895 -105.968302) (xy 71.021099 -105.896912) (xy 71.030592 -105.86212) (xy 71.035672 -105.844594)
			(xy 71.035672 -105.470452) (xy 72.00138 -105.470452) (xy 72.00138 -105.844594) (xy 72.00646 -105.86212)
			(xy 72.015944 -105.896913) (xy 72.026147 -105.968303) (xy 72.02678 -106.00436) (xy 72.02678 -106.132376)
			(xy 72.304656 -106.132376) (xy 72.304656 -105.15981) (xy 72.305164 -105.127084) (xy 72.313557 -105.062172)
			(xy 72.330206 -104.998873) (xy 72.354835 -104.938232) (xy 72.387039 -104.88125) (xy 72.406256 -104.854756)
			(xy 72.431656 -104.820974) (xy 72.431656 -104.803956) (xy 72.446896 -104.803956) (xy 72.48271 -104.773476)
			(xy 72.507887 -104.752623) (xy 72.562619 -104.716872) (xy 72.621484 -104.688433) (xy 72.683509 -104.667778)
			(xy 72.747671 -104.655247) (xy 72.81291 -104.651047) (xy 72.878149 -104.655247) (xy 72.942311 -104.667778)
			(xy 73.004336 -104.688433) (xy 73.063201 -104.716872) (xy 73.117933 -104.752623) (xy 73.14311 -104.773476)
			(xy 73.178924 -104.803956) (xy 73.194164 -104.803956) (xy 73.194164 -104.820974) (xy 73.219564 -104.854756)
			(xy 73.228754 -104.867184) (xy 73.245783 -104.892983) (xy 73.2536 -104.906318) (xy 73.262359 -104.92052)
			(xy 73.285932 -104.944119) (xy 73.314813 -104.960807) (xy 73.347031 -104.969446) (xy 73.380387 -104.969446)
			(xy 73.412605 -104.960807) (xy 73.441486 -104.944119) (xy 73.465059 -104.92052) (xy 73.473818 -104.906318)
			(xy 73.48163 -104.89298) (xy 73.498662 -104.867183) (xy 73.507854 -104.854756) (xy 73.533 -104.820974)
			(xy 73.533 -104.803956) (xy 73.548494 -104.803956) (xy 73.584308 -104.773476) (xy 73.609485 -104.752623)
			(xy 73.664217 -104.716872) (xy 73.723082 -104.688433) (xy 73.785107 -104.667778) (xy 73.849269 -104.655247)
			(xy 73.914508 -104.651047) (xy 73.979747 -104.655247) (xy 74.043909 -104.667778) (xy 74.105934 -104.688433)
			(xy 74.164799 -104.716872) (xy 74.219531 -104.752623) (xy 74.244708 -104.773476) (xy 74.280522 -104.803956)
			(xy 74.296016 -104.803956) (xy 74.296016 -104.820974) (xy 74.321162 -104.854756) (xy 74.340395 -104.88125)
			(xy 74.37266 -104.938215) (xy 74.397348 -104.998851) (xy 74.41405 -105.062153) (xy 74.422489 -105.127076)
			(xy 74.422881 -105.151428) (xy 82.471766 -105.151428) (xy 82.475837 -105.095806) (xy 82.487963 -105.041369)
			(xy 82.507886 -104.989278) (xy 82.535182 -104.940643) (xy 82.569268 -104.8965) (xy 82.609417 -104.857791)
			(xy 82.654775 -104.82534) (xy 82.704375 -104.799839) (xy 82.757159 -104.781832) (xy 82.812002 -104.771702)
			(xy 82.867736 -104.769665) (xy 82.923173 -104.775765) (xy 82.97713 -104.789871) (xy 83.028459 -104.811683)
			(xy 83.076065 -104.840737) (xy 83.118933 -104.876412) (xy 83.15615 -104.917949) (xy 83.186923 -104.964462)
			(xy 83.210595 -105.014959) (xy 83.226663 -105.068366) (xy 83.234783 -105.123542) (xy 83.235292 -105.151428)
			(xy 83.234783 -105.179314) (xy 83.226663 -105.23449) (xy 83.210595 -105.287897) (xy 83.186923 -105.338394)
			(xy 83.15615 -105.384907) (xy 83.118933 -105.426444) (xy 83.076065 -105.462119) (xy 83.028459 -105.491173)
			(xy 82.97713 -105.512985) (xy 82.923173 -105.527091) (xy 82.867736 -105.533191) (xy 82.812002 -105.531154)
			(xy 82.757159 -105.521024) (xy 82.704375 -105.503017) (xy 82.654775 -105.477516) (xy 82.609417 -105.445065)
			(xy 82.569268 -105.406356) (xy 82.535182 -105.362213) (xy 82.507886 -105.313578) (xy 82.487963 -105.261487)
			(xy 82.475837 -105.20705) (xy 82.471766 -105.151428) (xy 74.422881 -105.151428) (xy 74.423016 -105.15981)
			(xy 74.423016 -106.132376) (xy 74.422453 -106.164203) (xy 74.414498 -106.227357) (xy 74.408321 -106.251502)
			(xy 81.739484 -106.251502) (xy 81.743555 -106.19588) (xy 81.755681 -106.141443) (xy 81.775604 -106.089352)
			(xy 81.8029 -106.040717) (xy 81.836986 -105.996574) (xy 81.877135 -105.957865) (xy 81.922493 -105.925414)
			(xy 81.972093 -105.899913) (xy 82.024877 -105.881906) (xy 82.07972 -105.871776) (xy 82.135454 -105.869739)
			(xy 82.190891 -105.875839) (xy 82.244848 -105.889945) (xy 82.296177 -105.911757) (xy 82.343783 -105.940811)
			(xy 82.386651 -105.976486) (xy 82.423868 -106.018023) (xy 82.454641 -106.064536) (xy 82.478313 -106.115033)
			(xy 82.494381 -106.16844) (xy 82.502501 -106.223616) (xy 82.50301 -106.251502) (xy 82.502501 -106.279388)
			(xy 82.494381 -106.334564) (xy 82.478313 -106.387971) (xy 82.454641 -106.438468) (xy 82.423868 -106.484981)
			(xy 82.386651 -106.526518) (xy 82.343783 -106.562193) (xy 82.296177 -106.591247) (xy 82.244848 -106.613059)
			(xy 82.190891 -106.627165) (xy 82.135454 -106.633265) (xy 82.07972 -106.631228) (xy 82.024877 -106.621098)
			(xy 81.972093 -106.603091) (xy 81.922493 -106.57759) (xy 81.877135 -106.545139) (xy 81.836986 -106.50643)
			(xy 81.8029 -106.462287) (xy 81.775604 -106.413652) (xy 81.755681 -106.361561) (xy 81.743555 -106.307124)
			(xy 81.739484 -106.251502) (xy 74.408321 -106.251502) (xy 74.398722 -106.289025) (xy 74.375372 -106.348241)
			(xy 74.344814 -106.404079) (xy 74.307524 -106.455667) (xy 74.264087 -106.502196) (xy 74.215181 -106.542939)
			(xy 74.161573 -106.577259) (xy 74.104099 -106.60462) (xy 74.04366 -106.624592) (xy 73.981201 -106.636864)
			(xy 73.917699 -106.641244) (xy 73.854146 -106.637663) (xy 73.791537 -106.626177) (xy 73.730852 -106.606965)
			(xy 73.673039 -106.58033) (xy 73.619004 -106.546686) (xy 73.56959 -106.50656) (xy 73.547224 -106.483912)
			(xy 73.531122 -106.467745) (xy 73.494226 -106.440908) (xy 73.453127 -106.421097) (xy 73.409149 -106.408949)
			(xy 73.363709 -106.404856) (xy 73.318269 -106.408949) (xy 73.274291 -106.421097) (xy 73.233192 -106.440908)
			(xy 73.196296 -106.467745) (xy 73.180194 -106.483912) (xy 73.157797 -106.506519) (xy 73.108392 -106.546629)
			(xy 73.054366 -106.580259) (xy 72.996566 -106.606882) (xy 72.935895 -106.626083) (xy 72.873301 -106.637561)
			(xy 72.809765 -106.641136) (xy 72.746279 -106.636753) (xy 72.683836 -106.62448) (xy 72.623414 -106.60451)
			(xy 72.565957 -106.577153) (xy 72.512364 -106.54284) (xy 72.463473 -106.502105) (xy 72.420048 -106.455586)
			(xy 72.38277 -106.404011) (xy 72.35222 -106.348186) (xy 72.328877 -106.288985) (xy 72.313106 -106.227333)
			(xy 72.305154 -106.164194) (xy 72.304656 -106.132376) (xy 72.02678 -106.132376) (xy 72.02678 -106.976926)
			(xy 72.026279 -107.008871) (xy 72.018271 -107.072257) (xy 72.002382 -107.13414) (xy 71.978863 -107.193544)
			(xy 71.948083 -107.249531) (xy 71.91053 -107.30122) (xy 71.866794 -107.347794) (xy 71.817566 -107.388519)
			(xy 71.763621 -107.422753) (xy 71.705812 -107.449956) (xy 71.645049 -107.469699) (xy 71.58229 -107.481671)
			(xy 71.518526 -107.485683) (xy 71.454762 -107.481671) (xy 71.392003 -107.469699) (xy 71.33124 -107.449956)
			(xy 71.273431 -107.422753) (xy 71.219486 -107.388519) (xy 71.170258 -107.347794) (xy 71.126522 -107.30122)
			(xy 71.088969 -107.249531) (xy 71.058189 -107.193544) (xy 71.03467 -107.13414) (xy 71.018781 -107.072257)
			(xy 71.010773 -107.008871) (xy 71.010272 -106.976926) (xy 49.012532 -106.976926) (xy 49.016854 -106.998654)
			(xy 49.024804 -107.079373) (xy 49.025302 -107.119928) (xy 49.024804 -107.160483) (xy 49.016854 -107.241202)
			(xy 49.001031 -107.320753) (xy 48.977486 -107.398369) (xy 48.946447 -107.473305) (xy 48.932632 -107.49915)
			(xy 81.146902 -107.49915) (xy 81.150973 -107.443528) (xy 81.163099 -107.389091) (xy 81.183022 -107.337)
			(xy 81.210318 -107.288365) (xy 81.244404 -107.244222) (xy 81.284553 -107.205513) (xy 81.329911 -107.173062)
			(xy 81.379511 -107.147561) (xy 81.432295 -107.129554) (xy 81.487138 -107.119424) (xy 81.542872 -107.117387)
			(xy 81.598309 -107.123487) (xy 81.652266 -107.137593) (xy 81.703595 -107.159405) (xy 81.751201 -107.188459)
			(xy 81.794069 -107.224134) (xy 81.831286 -107.265671) (xy 81.862059 -107.312184) (xy 81.885731 -107.362681)
			(xy 81.901799 -107.416088) (xy 81.909919 -107.471264) (xy 81.910428 -107.49915) (xy 81.909919 -107.527036)
			(xy 81.901799 -107.582212) (xy 81.885731 -107.635619) (xy 81.862059 -107.686116) (xy 81.831286 -107.732629)
			(xy 81.794069 -107.774166) (xy 81.751201 -107.809841) (xy 81.703595 -107.838895) (xy 81.652266 -107.860707)
			(xy 81.598309 -107.874813) (xy 81.542872 -107.880913) (xy 81.487138 -107.878876) (xy 81.432295 -107.868746)
			(xy 81.379511 -107.850739) (xy 81.329911 -107.825238) (xy 81.284553 -107.792787) (xy 81.244404 -107.754078)
			(xy 81.210318 -107.709935) (xy 81.183022 -107.6613) (xy 81.163099 -107.609209) (xy 81.150973 -107.554772)
			(xy 81.146902 -107.49915) (xy 48.932632 -107.49915) (xy 48.908212 -107.544837) (xy 48.86315 -107.612277)
			(xy 48.811695 -107.674976) (xy 48.754342 -107.732329) (xy 48.691643 -107.783784) (xy 48.624203 -107.828846)
			(xy 48.552671 -107.867081) (xy 48.477735 -107.89812) (xy 48.400119 -107.921665) (xy 48.320568 -107.937488)
			(xy 48.239849 -107.945438) (xy 48.158739 -107.945438) (xy 48.07802 -107.937488) (xy 47.998469 -107.921665)
			(xy 47.920853 -107.89812) (xy 47.845917 -107.867081) (xy 47.774385 -107.828846) (xy 47.706945 -107.783784)
			(xy 47.644246 -107.732329) (xy 47.586893 -107.674976) (xy 47.535438 -107.612277) (xy 47.490376 -107.544837)
			(xy 47.452141 -107.473305) (xy 47.421102 -107.398369) (xy 47.397557 -107.320753) (xy 47.381734 -107.241202)
			(xy 47.373784 -107.160483) (xy 41.395898 -107.160483) (xy 41.388835 -107.173331) (xy 41.351282 -107.22502)
			(xy 41.307546 -107.271594) (xy 41.258318 -107.312319) (xy 41.204373 -107.346553) (xy 41.146564 -107.373756)
			(xy 41.085801 -107.393499) (xy 41.023042 -107.405471) (xy 40.959278 -107.409483) (xy 40.895514 -107.405471)
			(xy 40.832755 -107.393499) (xy 40.771992 -107.373756) (xy 40.714183 -107.346553) (xy 40.660238 -107.312319)
			(xy 40.61101 -107.271594) (xy 40.567274 -107.22502) (xy 40.529721 -107.173331) (xy 40.498941 -107.117344)
			(xy 40.475422 -107.05794) (xy 40.459533 -106.996057) (xy 40.451525 -106.932671) (xy 40.451024 -106.900726)
			(xy 40.451024 -106.368342) (xy 40.450534 -106.351682) (xy 40.441921 -106.319496) (xy 40.42527 -106.290637)
			(xy 40.401716 -106.267071) (xy 40.372865 -106.250405) (xy 40.340683 -106.241774) (xy 40.324024 -106.241342)
			(xy 40.306988 -106.241894) (xy 40.274129 -106.250914) (xy 40.24482 -106.268291) (xy 40.221142 -106.292793)
			(xy 40.204775 -106.322678) (xy 40.200326 -106.339132) (xy 40.191758 -106.372908) (xy 40.166627 -106.4379)
			(xy 40.132858 -106.498853) (xy 40.112442 -106.527092) (xy 40.087042 -106.560874) (xy 40.087042 -106.5784)
			(xy 40.068246 -106.5784) (xy 40.044271 -106.602056) (xy 39.991167 -106.643487) (xy 39.933059 -106.677546)
			(xy 39.870964 -106.703638) (xy 39.805969 -106.721305) (xy 39.739211 -106.730239) (xy 39.705534 -106.7308)
			(xy 37.757862 -106.7308) (xy 36.484052 -108.00461) (xy 36.465256 -108.061506) (xy 36.469828 -108.091478)
			(xy 36.475687 -108.134079) (xy 36.480536 -108.21994) (xy 36.477524 -108.305885) (xy 36.466677 -108.391197)
			(xy 36.448085 -108.475161) (xy 36.421903 -108.557077) (xy 36.388351 -108.636259) (xy 36.347708 -108.712048)
			(xy 36.300314 -108.783808) (xy 36.246566 -108.85094) (xy 36.189574 -108.91012) (xy 86.39887 -108.91012)
			(xy 86.402874 -108.710022) (xy 86.414881 -108.510244) (xy 86.434872 -108.311107) (xy 86.462814 -108.112929)
			(xy 86.498662 -107.916027) (xy 86.54236 -107.720718) (xy 86.593837 -107.527313) (xy 86.653011 -107.336123)
			(xy 86.719787 -107.147453) (xy 86.794059 -106.961606) (xy 86.875706 -106.778879) (xy 86.964599 -106.599566)
			(xy 87.060595 -106.423952) (xy 87.16354 -106.25232) (xy 87.27327 -106.084944) (xy 87.389608 -105.922093)
			(xy 87.512369 -105.764026) (xy 87.641356 -105.610998) (xy 87.776363 -105.463253) (xy 87.917172 -105.321027)
			(xy 88.063559 -105.18455) (xy 88.215289 -105.054038) (xy 88.37212 -104.929702) (xy 88.533799 -104.81174)
			(xy 88.700069 -104.700341) (xy 88.870662 -104.595684) (xy 89.045306 -104.497936) (xy 89.223722 -104.407253)
			(xy 89.405622 -104.323782) (xy 89.590717 -104.247655) (xy 89.778709 -104.178995) (xy 89.969298 -104.117911)
			(xy 90.162178 -104.064501) (xy 90.35704 -104.018852) (xy 90.553573 -103.981035) (xy 90.751462 -103.951111)
			(xy 90.950389 -103.929129) (xy 91.150037 -103.915124) (xy 91.350085 -103.909118) (xy 91.550213 -103.91112)
			(xy 91.750101 -103.921128) (xy 91.949428 -103.939125) (xy 92.147876 -103.965083) (xy 92.345126 -103.99896)
			(xy 92.540863 -104.040702) (xy 92.734773 -104.090241) (xy 92.926546 -104.147499) (xy 92.987673 -104.168448)
			(xy 96.295208 -104.168448) (xy 96.299279 -104.112826) (xy 96.311405 -104.058389) (xy 96.331328 -104.006298)
			(xy 96.358624 -103.957663) (xy 96.39271 -103.91352) (xy 96.432859 -103.874811) (xy 96.478217 -103.84236)
			(xy 96.527817 -103.816859) (xy 96.580601 -103.798852) (xy 96.635444 -103.788722) (xy 96.691178 -103.786685)
			(xy 96.746615 -103.792785) (xy 96.800572 -103.806891) (xy 96.851901 -103.828703) (xy 96.899507 -103.857757)
			(xy 96.942375 -103.893432) (xy 96.979592 -103.934969) (xy 97.010365 -103.981482) (xy 97.034037 -104.031979)
			(xy 97.050105 -104.085386) (xy 97.058225 -104.140562) (xy 97.058734 -104.168448) (xy 97.058225 -104.196334)
			(xy 97.050105 -104.25151) (xy 97.034037 -104.304917) (xy 97.010365 -104.355414) (xy 96.979592 -104.401927)
			(xy 96.942375 -104.443464) (xy 96.899507 -104.479139) (xy 96.851901 -104.508193) (xy 96.800572 -104.530005)
			(xy 96.746615 -104.544111) (xy 96.691178 -104.550211) (xy 96.635444 -104.548174) (xy 96.580601 -104.538044)
			(xy 96.527817 -104.520037) (xy 96.478217 -104.494536) (xy 96.432859 -104.462085) (xy 96.39271 -104.423376)
			(xy 96.358624 -104.379233) (xy 96.331328 -104.330598) (xy 96.311405 -104.278507) (xy 96.299279 -104.22407)
			(xy 96.295208 -104.168448) (xy 92.987673 -104.168448) (xy 93.115875 -104.212384) (xy 93.302455 -104.284792)
			(xy 93.48599 -104.364608) (xy 93.666184 -104.451702) (xy 93.842749 -104.545936) (xy 94.015402 -104.647159)
			(xy 94.183867 -104.755209) (xy 94.347875 -104.869912) (xy 94.507162 -104.991086) (xy 94.661473 -105.118535)
			(xy 94.810561 -105.252056) (xy 94.954188 -105.391436) (xy 95.092124 -105.53645) (xy 95.224147 -105.686867)
			(xy 95.350046 -105.842445) (xy 95.46962 -106.002937) (xy 95.582676 -106.168083) (xy 95.689035 -106.337621)
			(xy 95.788526 -106.511279) (xy 95.880989 -106.688778) (xy 95.966276 -106.869834) (xy 96.044251 -107.054158)
			(xy 96.114788 -107.241454) (xy 96.177776 -107.431422) (xy 96.233113 -107.623758) (xy 96.28071 -107.818154)
			(xy 96.320491 -108.014299) (xy 96.352393 -108.211878) (xy 96.376364 -108.410575) (xy 96.392366 -108.610073)
			(xy 96.400373 -108.810051) (xy 96.400874 -108.91012) (xy 96.400373 -109.010189) (xy 96.392366 -109.210167)
			(xy 96.376364 -109.409665) (xy 96.352393 -109.608362) (xy 96.320491 -109.805941) (xy 96.28071 -110.002086)
			(xy 96.233113 -110.196482) (xy 96.177776 -110.388818) (xy 96.114788 -110.578786) (xy 96.044251 -110.766082)
			(xy 95.966276 -110.950406) (xy 95.880989 -111.131462) (xy 95.788526 -111.308961) (xy 95.689035 -111.482619)
			(xy 95.582676 -111.652157) (xy 95.46962 -111.817303) (xy 95.350046 -111.977795) (xy 95.224147 -112.133373)
			(xy 95.092124 -112.28379) (xy 94.954188 -112.428804) (xy 94.810561 -112.568184) (xy 94.661473 -112.701705)
			(xy 94.507162 -112.829154) (xy 94.347875 -112.950328) (xy 94.183867 -113.065031) (xy 94.015402 -113.173081)
			(xy 93.842749 -113.274304) (xy 93.666184 -113.368538) (xy 93.48599 -113.455632) (xy 93.302455 -113.535448)
			(xy 93.115875 -113.607856) (xy 92.926546 -113.672741) (xy 92.734773 -113.729999) (xy 92.540863 -113.779538)
			(xy 92.345126 -113.82128) (xy 92.147876 -113.855157) (xy 91.949428 -113.881115) (xy 91.750101 -113.899112)
			(xy 91.550213 -113.90912) (xy 91.350085 -113.911122) (xy 91.150037 -113.905116) (xy 90.950389 -113.891111)
			(xy 90.751462 -113.869129) (xy 90.553573 -113.839205) (xy 90.35704 -113.801388) (xy 90.162178 -113.755739)
			(xy 89.969298 -113.702329) (xy 89.778709 -113.641245) (xy 89.590717 -113.572585) (xy 89.405622 -113.496458)
			(xy 89.223722 -113.412987) (xy 89.045306 -113.322304) (xy 88.870662 -113.224556) (xy 88.700069 -113.119899)
			(xy 88.533799 -113.0085) (xy 88.37212 -112.890538) (xy 88.215289 -112.766202) (xy 88.063559 -112.63569)
			(xy 87.917172 -112.499213) (xy 87.776363 -112.356987) (xy 87.641356 -112.209242) (xy 87.512369 -112.056214)
			(xy 87.389608 -111.898147) (xy 87.27327 -111.735296) (xy 87.16354 -111.56792) (xy 87.060595 -111.396288)
			(xy 86.964599 -111.220674) (xy 86.875706 -111.041361) (xy 86.794059 -110.858634) (xy 86.719787 -110.672787)
			(xy 86.653011 -110.484117) (xy 86.593837 -110.292927) (xy 86.54236 -110.099522) (xy 86.498662 -109.904213)
			(xy 86.462814 -109.707311) (xy 86.434872 -109.509133) (xy 86.414881 -109.309996) (xy 86.402874 -109.110218)
			(xy 86.39887 -108.91012) (xy 36.189574 -108.91012) (xy 36.186912 -108.912884) (xy 36.121851 -108.969122)
			(xy 36.051926 -109.019184) (xy 35.977722 -109.062652) (xy 35.899858 -109.099162) (xy 35.818987 -109.128409)
			(xy 35.735782 -109.15015) (xy 35.65094 -109.164202) (xy 35.565169 -109.170447) (xy 35.479186 -109.168835)
			(xy 35.393709 -109.159377) (xy 35.309453 -109.142154) (xy 35.227122 -109.117309) (xy 35.147404 -109.08505)
			(xy 35.070964 -109.045646) (xy 34.998443 -108.999426) (xy 34.930444 -108.946778) (xy 34.867537 -108.88814)
			(xy 34.810248 -108.824002) (xy 34.784284 -108.789724) (xy 34.775134 -108.778032) (xy 34.752429 -108.758913)
			(xy 34.725908 -108.745584) (xy 34.697018 -108.738772) (xy 34.682176 -108.738416) (xy 33.90392 -108.738416)
			(xy 32.759904 -107.5944) (xy 32.759904 -92.544646) (xy 31.848298 -91.63304) (xy 29.99232 -91.63304)
			(xy 28.591861 -93.033358) (xy 29.519874 -93.033358) (xy 29.519874 -92.946458) (xy 29.527892 -92.859929)
			(xy 29.54386 -92.774509) (xy 29.567641 -92.690927) (xy 29.599033 -92.609895) (xy 29.637767 -92.532106)
			(xy 29.683514 -92.458222) (xy 29.735883 -92.388875) (xy 29.794427 -92.324655) (xy 29.858647 -92.266111)
			(xy 29.927994 -92.213742) (xy 30.001878 -92.167995) (xy 30.079667 -92.129261) (xy 30.160699 -92.097869)
			(xy 30.244281 -92.074088) (xy 30.329701 -92.05812) (xy 30.41623 -92.050102) (xy 30.50313 -92.050102)
			(xy 30.589659 -92.05812) (xy 30.675079 -92.074088) (xy 30.758661 -92.097869) (xy 30.839693 -92.129261)
			(xy 30.917482 -92.167995) (xy 30.991366 -92.213742) (xy 31.060713 -92.266111) (xy 31.124933 -92.324655)
			(xy 31.183477 -92.388875) (xy 31.235846 -92.458222) (xy 31.281593 -92.532106) (xy 31.320327 -92.609895)
			(xy 31.351719 -92.690927) (xy 31.3755 -92.774509) (xy 31.391468 -92.859929) (xy 31.399486 -92.946458)
			(xy 31.399988 -92.989908) (xy 31.399486 -93.033358) (xy 31.391468 -93.119887) (xy 31.3755 -93.205307)
			(xy 31.351719 -93.288889) (xy 31.320327 -93.369921) (xy 31.281593 -93.44771) (xy 31.235846 -93.521594)
			(xy 31.183477 -93.590941) (xy 31.124933 -93.655161) (xy 31.060713 -93.713705) (xy 30.991366 -93.766074)
			(xy 30.917482 -93.811821) (xy 30.839693 -93.850555) (xy 30.758661 -93.881947) (xy 30.675079 -93.905728)
			(xy 30.589659 -93.921696) (xy 30.50313 -93.929714) (xy 30.41623 -93.929714) (xy 30.329701 -93.921696)
			(xy 30.244281 -93.905728) (xy 30.160699 -93.881947) (xy 30.079667 -93.850555) (xy 30.001878 -93.811821)
			(xy 29.927994 -93.766074) (xy 29.858647 -93.713705) (xy 29.794427 -93.655161) (xy 29.735883 -93.590941)
			(xy 29.683514 -93.521594) (xy 29.637767 -93.44771) (xy 29.599033 -93.369921) (xy 29.567641 -93.288889)
			(xy 29.54386 -93.205307) (xy 29.527892 -93.119887) (xy 29.519874 -93.033358) (xy 28.591861 -93.033358)
			(xy 27.46629 -94.158816) (xy 26.81478 -94.158816) (xy 26.798134 -94.159362) (xy 26.765978 -94.167983)
			(xy 26.737149 -94.184633) (xy 26.713611 -94.208178) (xy 26.696969 -94.237011) (xy 26.688357 -94.26917)
			(xy 26.68778 -94.285816) (xy 26.68778 -94.846394) (xy 26.66238 -94.846394) (xy 26.66238 -95.269812)
			(xy 26.68778 -95.269812) (xy 26.73858 -95.320612) (xy 26.898092 -95.320612) (xy 26.929588 -95.300546)
			(xy 26.94893 -95.28845) (xy 26.989935 -95.268459) (xy 27.011376 -95.260668) (xy 27.038808 -95.251016)
			(xy 27.090624 -95.1992) (xy 29.532326 -95.1992) (xy 29.594302 -95.15983) (xy 29.61005 -95.12681)
			(xy 29.628926 -95.088147) (xy 29.672754 -95.014102) (xy 29.723163 -94.944371) (xy 29.779731 -94.879536)
			(xy 29.841985 -94.820139) (xy 29.909405 -94.766678) (xy 29.981427 -94.719599) (xy 30.057449 -94.679297)
			(xy 30.136834 -94.646107) (xy 30.218919 -94.620309) (xy 30.303017 -94.602116) (xy 30.388426 -94.591682)
			(xy 30.474431 -94.589094) (xy 30.560313 -94.594374) (xy 30.645353 -94.607477) (xy 30.728841 -94.628293)
			(xy 30.810078 -94.656649) (xy 30.888386 -94.692308) (xy 30.963108 -94.734971) (xy 31.03362 -94.784281)
			(xy 31.099334 -94.839827) (xy 31.159698 -94.901143) (xy 31.214209 -94.967718) (xy 31.26241 -95.038993)
			(xy 31.303898 -95.114374) (xy 31.338327 -95.19323) (xy 31.365408 -95.274901) (xy 31.384916 -95.358704)
			(xy 31.396686 -95.443939) (xy 31.400621 -95.529893) (xy 31.396687 -95.615847) (xy 31.384918 -95.701082)
			(xy 31.365412 -95.784886) (xy 31.338332 -95.866557) (xy 31.303904 -95.945413) (xy 31.262417 -96.020794)
			(xy 31.214217 -96.092071) (xy 31.159708 -96.158646) (xy 31.099344 -96.219963) (xy 31.033632 -96.27551)
			(xy 30.96312 -96.324822) (xy 30.888399 -96.367486) (xy 30.810092 -96.403145) (xy 30.728855 -96.431503)
			(xy 30.645368 -96.45232) (xy 30.560327 -96.465425) (xy 30.474446 -96.470705) (xy 30.388441 -96.468119)
			(xy 30.303032 -96.457686) (xy 30.218933 -96.439495) (xy 30.136847 -96.413698) (xy 30.057462 -96.380509)
			(xy 29.98144 -96.340208) (xy 29.909417 -96.29313) (xy 29.841996 -96.23967) (xy 29.779741 -96.180275)
			(xy 29.723172 -96.115441) (xy 29.672762 -96.04571) (xy 29.628932 -95.971666) (xy 29.61005 -95.933006)
			(xy 29.594302 -95.899986) (xy 29.532326 -95.860616) (xy 27.488896 -95.860616) (xy 27.472636 -95.861109)
			(xy 27.441172 -95.869336) (xy 27.412813 -95.885252) (xy 27.400758 -95.896176) (xy 27.379725 -95.915681)
			(xy 27.332888 -95.948795) (xy 27.28162 -95.974522) (xy 27.227079 -95.992284) (xy 27.170492 -96.001678)
			(xy 27.113137 -96.002493) (xy 27.056307 -95.994711) (xy 27.028648 -95.987108) (xy 27.011122 -95.982028)
			(xy 26.73858 -95.982028) (xy 26.68778 -96.032828) (xy 26.66238 -96.032828) (xy 26.66238 -96.490536)
			(xy 26.68778 -96.490536) (xy 26.68778 -97.253552) (xy 26.16708 -97.253552) (xy 26.150431 -97.254097)
			(xy 26.118268 -97.262718) (xy 26.089431 -97.279366) (xy 26.065883 -97.302909) (xy 26.049229 -97.331742)
			(xy 26.040601 -97.363903) (xy 26.04008 -97.380552) (xy 26.04008 -97.595182) (xy 26.040621 -97.611833)
			(xy 26.049235 -97.644001) (xy 26.065882 -97.672843) (xy 26.089426 -97.696395) (xy 26.118264 -97.71305)
			(xy 26.150429 -97.721674) (xy 26.16708 -97.722182) (xy 26.68778 -97.722182) (xy 26.68778 -98.485198)
			(xy 26.66238 -98.485198) (xy 26.66238 -98.988372) (xy 26.68778 -98.988372) (xy 26.73858 -99.039172)
			(xy 26.911046 -99.039172) (xy 26.937208 -99.026472) (xy 26.963295 -99.014367) (xy 27.0182 -98.997264)
			(xy 27.07505 -98.988592) (xy 27.132558 -98.988547) (xy 27.189421 -98.997131) (xy 27.244353 -99.014149)
			(xy 27.270456 -99.026218) (xy 27.296618 -99.039172) (xy 28.970478 -99.039172) (xy 28.987122 -99.038654)
			(xy 29.019263 -99.02999) (xy 29.048065 -99.013299) (xy 29.06014 -99.001834) (xy 29.570172 -98.491802)
			(xy 29.586428 -98.420174) (xy 29.573982 -98.38563) (xy 29.559992 -98.344948) (xy 29.538628 -98.261609)
			(xy 29.524966 -98.176666) (xy 29.519121 -98.09083) (xy 29.521142 -98.00482) (xy 29.531012 -97.919353)
			(xy 29.548648 -97.835146) (xy 29.573902 -97.752902) (xy 29.606564 -97.673308) (xy 29.64636 -97.597031)
			(xy 29.692958 -97.524709) (xy 29.745968 -97.456945) (xy 29.804947 -97.394308) (xy 29.869401 -97.33732)
			(xy 29.938791 -97.286459) (xy 30.012538 -97.242149) (xy 30.090024 -97.204761) (xy 30.170601 -97.174608)
			(xy 30.253596 -97.151942) (xy 30.338315 -97.136952) (xy 30.424048 -97.129764) (xy 30.51008 -97.130438)
			(xy 30.59569 -97.138969) (xy 30.680164 -97.155284) (xy 30.762793 -97.179248) (xy 30.842888 -97.21066)
			(xy 30.919779 -97.249258) (xy 30.992822 -97.294718) (xy 31.061407 -97.346661) (xy 31.12496 -97.404651)
			(xy 31.182949 -97.468205) (xy 31.234891 -97.536791) (xy 31.28035 -97.609835) (xy 31.318946 -97.686726)
			(xy 31.350357 -97.766821) (xy 31.374319 -97.849451) (xy 31.390633 -97.933925) (xy 31.399162 -98.019535)
			(xy 31.399835 -98.105567) (xy 31.392646 -98.191301) (xy 31.377655 -98.276019) (xy 31.354987 -98.359014)
			(xy 31.324833 -98.43959) (xy 31.287444 -98.517076) (xy 31.243133 -98.590822) (xy 31.19227 -98.660211)
			(xy 31.135281 -98.724664) (xy 31.072643 -98.783642) (xy 31.004879 -98.83665) (xy 30.932556 -98.883247)
			(xy 30.856278 -98.923042) (xy 30.776684 -98.955703) (xy 30.694439 -98.980956) (xy 30.610232 -98.998591)
			(xy 30.524765 -99.008459) (xy 30.438754 -99.010478) (xy 30.352919 -99.004632) (xy 30.267976 -98.990969)
			(xy 30.184637 -98.969604) (xy 30.143958 -98.955606) (xy 30.109414 -98.94316) (xy 30.037786 -98.959416)
			(xy 29.296868 -99.70008) (xy 27.296618 -99.70008) (xy 27.270456 -99.713034) (xy 27.244409 -99.725052)
			(xy 27.189611 -99.742011) (xy 27.132894 -99.750587) (xy 27.075532 -99.750587) (xy 27.018815 -99.742011)
			(xy 26.964017 -99.725052) (xy 26.93797 -99.713034) (xy 26.911808 -99.700588) (xy 26.73858 -99.700588)
			(xy 26.68778 -99.751388) (xy 26.66238 -99.751388) (xy 26.66238 -100.208588) (xy 26.68778 -100.208588)
			(xy 26.68778 -100.656875) (xy 28.701115 -100.656875) (xy 28.702127 -100.602222) (xy 28.710931 -100.548273)
			(xy 28.727346 -100.496134) (xy 28.751036 -100.446872) (xy 28.781516 -100.401496) (xy 28.818161 -100.360936)
			(xy 28.860222 -100.326024) (xy 28.906835 -100.297473) (xy 28.957047 -100.275869) (xy 29.009829 -100.261654)
			(xy 29.0641 -100.25512) (xy 29.118747 -100.256401) (xy 29.172652 -100.265469) (xy 29.198824 -100.273358)
			(xy 29.217874 -100.2792) (xy 29.532326 -100.2792) (xy 29.594302 -100.23983) (xy 29.61005 -100.20681)
			(xy 29.628919 -100.168144) (xy 29.672748 -100.094098) (xy 29.723157 -100.024366) (xy 29.779726 -99.959531)
			(xy 29.841981 -99.900134) (xy 29.909401 -99.846672) (xy 29.981424 -99.799593) (xy 30.057446 -99.759291)
			(xy 30.136831 -99.726101) (xy 30.218917 -99.700302) (xy 30.303016 -99.68211) (xy 30.388426 -99.671676)
			(xy 30.474431 -99.669088) (xy 30.560314 -99.674367) (xy 30.645355 -99.68747) (xy 30.728843 -99.708287)
			(xy 30.810081 -99.736643) (xy 30.888389 -99.772302) (xy 30.963112 -99.814965) (xy 31.033625 -99.864276)
			(xy 31.099338 -99.919822) (xy 31.159703 -99.981139) (xy 31.214214 -100.047714) (xy 31.262415 -100.11899)
			(xy 31.303904 -100.194371) (xy 31.338333 -100.273227) (xy 31.365415 -100.354899) (xy 31.384922 -100.438703)
			(xy 31.396693 -100.523938) (xy 31.400628 -100.609893) (xy 31.396694 -100.695847) (xy 31.384925 -100.781083)
			(xy 31.365419 -100.864887) (xy 31.338338 -100.946559) (xy 31.303911 -101.025416) (xy 31.262423 -101.100798)
			(xy 31.214223 -101.172075) (xy 31.159713 -101.23865) (xy 31.099349 -101.299968) (xy 31.033636 -101.355515)
			(xy 30.963124 -101.404827) (xy 30.888402 -101.447492) (xy 30.810094 -101.483152) (xy 30.728857 -101.511509)
			(xy 30.645369 -101.532327) (xy 30.560328 -101.545431) (xy 30.474446 -101.550712) (xy 30.38844 -101.548125)
			(xy 30.303031 -101.537693) (xy 30.218931 -101.519502) (xy 30.136845 -101.493704) (xy 30.057459 -101.460516)
			(xy 29.981436 -101.420214) (xy 29.909413 -101.373136) (xy 29.841992 -101.319676) (xy 29.779736 -101.26028)
			(xy 29.723166 -101.195445) (xy 29.672756 -101.125714) (xy 29.628926 -101.051669) (xy 29.61005 -101.013006)
			(xy 29.594302 -100.979986) (xy 29.532326 -100.940616) (xy 29.315918 -100.940616) (xy 29.28493 -100.95992)
			(xy 29.261489 -100.973984) (xy 29.211492 -100.996081) (xy 29.158853 -101.010813) (xy 29.104649 -101.01788)
			(xy 29.049992 -101.017137) (xy 28.996 -101.008599) (xy 28.943781 -100.99244) (xy 28.894403 -100.968993)
			(xy 28.848878 -100.938736) (xy 28.808139 -100.90229) (xy 28.77302 -100.860402) (xy 28.74424 -100.813929)
			(xy 28.72239 -100.763824) (xy 28.707916 -100.711113) (xy 28.701115 -100.656875) (xy 26.68778 -100.656875)
			(xy 26.68778 -100.971604) (xy 25.870154 -100.971604) (xy 25.836372 -100.997004) (xy 25.808926 -101.016834)
			(xy 25.7498 -101.049834) (xy 25.718516 -101.06279) (xy 25.682194 -101.077268) (xy 25.638252 -101.141784)
			(xy 25.638252 -101.1809) (xy 25.638795 -101.197551) (xy 25.647412 -101.229718) (xy 25.664059 -101.25856)
			(xy 25.687602 -101.282112) (xy 25.716438 -101.298769) (xy 25.748602 -101.307399) (xy 25.765252 -101.3079)
			(xy 26.757884 -101.3079) (xy 26.808684 -101.3587) (xy 29.120338 -101.3587) (xy 30.02661 -102.264972)
			(xy 30.098746 -102.28072) (xy 30.133798 -102.267766) (xy 30.174309 -102.253305) (xy 30.257385 -102.230974)
			(xy 30.342153 -102.216325) (xy 30.427904 -102.209481) (xy 30.513923 -102.210498) (xy 30.599489 -102.219369)
			(xy 30.683887 -102.236018) (xy 30.766411 -102.260308) (xy 30.846371 -102.292033) (xy 30.923099 -102.330931)
			(xy 30.995953 -102.376674) (xy 31.064325 -102.428882) (xy 31.127641 -102.487116) (xy 31.185373 -102.550891)
			(xy 31.237038 -102.619672) (xy 31.282205 -102.692886) (xy 31.320495 -102.769919) (xy 31.351588 -102.850127)
			(xy 31.375224 -102.932841) (xy 31.391206 -103.017368) (xy 31.3994 -103.103001) (xy 31.399738 -103.189025)
			(xy 31.392216 -103.27472) (xy 31.376898 -103.359369) (xy 31.353911 -103.442266) (xy 31.323448 -103.522716)
			(xy 31.285764 -103.600047) (xy 31.241174 -103.673612) (xy 31.19005 -103.742797) (xy 31.13282 -103.807023)
			(xy 31.069962 -103.865752) (xy 31.002003 -103.918495) (xy 30.92951 -103.964808) (xy 30.85309 -104.004307)
			(xy 30.773381 -104.036659) (xy 30.69105 -104.061595) (xy 30.606785 -104.078906) (xy 30.521291 -104.088448)
			(xy 30.435283 -104.09014) (xy 30.349481 -104.083969) (xy 30.2646 -104.069986) (xy 30.181352 -104.048308)
			(xy 30.100432 -104.019116) (xy 30.022517 -103.982654) (xy 29.948258 -103.939228) (xy 29.878277 -103.8892)
			(xy 29.813158 -103.832989) (xy 29.753446 -103.771064) (xy 29.69964 -103.703944) (xy 29.65219 -103.632189)
			(xy 29.611493 -103.5564) (xy 29.57789 -103.47721) (xy 29.55166 -103.395282) (xy 29.533024 -103.311301)
			(xy 29.522137 -103.225968) (xy 29.51909 -103.139998) (xy 29.523909 -103.054108) (xy 29.536554 -102.969018)
			(xy 29.556918 -102.885439) (xy 29.570426 -102.8446) (xy 29.582364 -102.810056) (xy 29.565854 -102.739444)
			(xy 28.846526 -102.020116) (xy 26.808684 -102.020116) (xy 26.757884 -102.070916) (xy 26.61031 -102.070916)
			(xy 26.587274 -102.071416) (xy 26.541958 -102.079719) (xy 26.49888 -102.096055) (xy 26.459453 -102.119889)
			(xy 26.424968 -102.150439) (xy 26.396555 -102.186706) (xy 26.375145 -102.2275) (xy 26.36144 -102.271486)
			(xy 26.355888 -102.317221) (xy 26.358671 -102.363208) (xy 26.369699 -102.40794) (xy 26.388609 -102.449951)
			(xy 26.414783 -102.487865) (xy 26.430732 -102.504494) (xy 26.88209 -102.955852) (xy 26.909522 -102.965504)
			(xy 26.935407 -102.974991) (xy 26.984353 -103.000356) (xy 27.029137 -103.032503) (xy 27.068828 -103.070763)
			(xy 27.102596 -103.114338) (xy 27.129741 -103.162321) (xy 27.149694 -103.213711) (xy 27.162042 -103.267439)
			(xy 27.166526 -103.322384) (xy 27.163054 -103.377403) (xy 27.151698 -103.431349) (xy 27.132693 -103.483098)
			(xy 27.106437 -103.531572) (xy 27.073476 -103.575761) (xy 27.034497 -103.614745) (xy 26.990312 -103.647712)
			(xy 26.941841 -103.673974) (xy 26.890094 -103.692985) (xy 26.83615 -103.704348) (xy 26.781131 -103.707827)
			(xy 26.726185 -103.703349) (xy 26.672456 -103.691008) (xy 26.621063 -103.671061) (xy 26.573077 -103.643923)
			(xy 26.529498 -103.610159) (xy 26.491234 -103.570474) (xy 26.459081 -103.525693) (xy 26.433709 -103.47675)
			(xy 26.424128 -103.450898) (xy 26.414476 -103.423466) (xy 25.270968 -102.279958) (xy 25.270968 -102.070916)
			(xy 25.245568 -102.070916) (xy 25.245568 -101.225604) (xy 25.245074 -101.20895) (xy 25.236453 -101.176778)
			(xy 25.219797 -101.147935) (xy 25.196243 -101.124385) (xy 25.167396 -101.107736) (xy 25.135222 -101.099123)
			(xy 25.118568 -101.098604) (xy 24.801322 -101.098604) (xy 24.770159 -101.098133) (xy 24.7083 -101.090519)
			(xy 24.647836 -101.0754) (xy 24.589673 -101.053006) (xy 24.534683 -101.02367) (xy 24.48369 -100.987833)
			(xy 24.43746 -100.946033) (xy 24.396685 -100.898896) (xy 24.361978 -100.847128) (xy 24.333857 -100.791507)
			(xy 24.312745 -100.732866) (xy 24.298959 -100.672084) (xy 24.292705 -100.610073) (xy 24.294077 -100.547762)
			(xy 24.303054 -100.486086) (xy 24.319502 -100.42597) (xy 24.343174 -100.368315) (xy 24.373716 -100.313985)
			(xy 24.410668 -100.263795) (xy 24.453478 -100.218498) (xy 24.501503 -100.178773) (xy 24.52751 -100.161598)
			(xy 24.547163 -100.148411) (xy 24.581627 -100.115982) (xy 24.609494 -100.077735) (xy 24.6298 -100.034991)
			(xy 24.641844 -99.989226) (xy 24.645209 -99.942024) (xy 24.639779 -99.895014) (xy 24.625743 -99.849821)
			(xy 24.603584 -99.808007) (xy 24.574069 -99.771017) (xy 24.556466 -99.755198) (xy 24.532147 -99.733576)
			(xy 24.488655 -99.685173) (xy 24.451693 -99.631617) (xy 24.421866 -99.573783) (xy 24.399661 -99.512616)
			(xy 24.385441 -99.449116) (xy 24.379438 -99.38432) (xy 24.381751 -99.319289) (xy 24.392342 -99.255083)
			(xy 24.411037 -99.192754) (xy 24.437532 -99.133319) (xy 24.471392 -99.07775) (xy 24.512066 -99.026955)
			(xy 24.558887 -98.981764) (xy 24.611091 -98.942916) (xy 24.667825 -98.911045) (xy 24.728161 -98.886672)
			(xy 24.791114 -98.870197) (xy 24.855654 -98.861887) (xy 24.88819 -98.861372) (xy 25.455372 -98.861372)
			(xy 25.472028 -98.860881) (xy 25.504206 -98.852264) (xy 25.533055 -98.83561) (xy 25.55661 -98.812055)
			(xy 25.573264 -98.783206) (xy 25.581881 -98.751028) (xy 25.582372 -98.734372) (xy 25.582372 -98.686112)
			(xy 25.518618 -98.61423) (xy 25.470612 -98.608388) (xy 25.43048 -98.601784) (xy 25.418034 -98.599244)
			(xy 24.363172 -98.599244) (xy 24.346531 -98.599769) (xy 24.314398 -98.608444) (xy 24.285607 -98.625142)
			(xy 24.27351 -98.636582) (xy 23.630128 -99.279964) (xy 23.630128 -104.332532) (xy 22.884638 -105.078022)
			(xy 22.873243 -105.090152) (xy 22.856563 -105.118935) (xy 22.847886 -105.151052) (xy 22.8473 -105.167684)
			(xy 22.8473 -106.099363) (xy 23.29671 -106.099363) (xy 23.301447 -106.04468) (xy 23.313974 -105.99124)
			(xy 23.334031 -105.940148) (xy 23.361205 -105.892458) (xy 23.394935 -105.849156) (xy 23.434523 -105.811136)
			(xy 23.479152 -105.779183) (xy 23.5279 -105.753958) (xy 23.553674 -105.744518) (xy 23.581106 -105.734866)
			(xy 23.956772 -105.3592) (xy 29.532326 -105.3592) (xy 29.594302 -105.31983) (xy 29.61005 -105.28681)
			(xy 29.628919 -105.248144) (xy 29.672748 -105.174098) (xy 29.723157 -105.104366) (xy 29.779726 -105.039531)
			(xy 29.841981 -104.980134) (xy 29.909401 -104.926672) (xy 29.981424 -104.879593) (xy 30.057446 -104.839291)
			(xy 30.136831 -104.806101) (xy 30.218917 -104.780302) (xy 30.303016 -104.76211) (xy 30.388426 -104.751676)
			(xy 30.474431 -104.749088) (xy 30.560314 -104.754367) (xy 30.645355 -104.76747) (xy 30.728843 -104.788287)
			(xy 30.810081 -104.816643) (xy 30.888389 -104.852302) (xy 30.963112 -104.894965) (xy 31.033625 -104.944276)
			(xy 31.099338 -104.999822) (xy 31.159703 -105.061139) (xy 31.214214 -105.127714) (xy 31.262415 -105.19899)
			(xy 31.303904 -105.274371) (xy 31.338333 -105.353227) (xy 31.365415 -105.434899) (xy 31.384922 -105.518703)
			(xy 31.396693 -105.603938) (xy 31.400628 -105.689893) (xy 31.396694 -105.775847) (xy 31.384925 -105.861083)
			(xy 31.365419 -105.944887) (xy 31.338338 -106.026559) (xy 31.303911 -106.105416) (xy 31.262423 -106.180798)
			(xy 31.214223 -106.252075) (xy 31.159713 -106.31865) (xy 31.099349 -106.379968) (xy 31.033636 -106.435515)
			(xy 30.963124 -106.484827) (xy 30.888402 -106.527492) (xy 30.810094 -106.563152) (xy 30.728857 -106.591509)
			(xy 30.645369 -106.612327) (xy 30.560328 -106.625431) (xy 30.474446 -106.630712) (xy 30.38844 -106.628125)
			(xy 30.303031 -106.617693) (xy 30.218931 -106.599502) (xy 30.136845 -106.573704) (xy 30.057459 -106.540516)
			(xy 29.981436 -106.500214) (xy 29.909413 -106.453136) (xy 29.841992 -106.399676) (xy 29.779736 -106.34028)
			(xy 29.723166 -106.275445) (xy 29.672756 -106.205714) (xy 29.628926 -106.131669) (xy 29.61005 -106.093006)
			(xy 29.594302 -106.059986) (xy 29.532326 -106.020616) (xy 28.87345 -106.020616) (xy 28.85055 -106.021078)
			(xy 28.805495 -106.029311) (xy 28.762645 -106.045485) (xy 28.723387 -106.069074) (xy 28.688991 -106.099317)
			(xy 28.66057 -106.135233) (xy 28.639045 -106.175661) (xy 28.625113 -106.219291) (xy 28.619224 -106.264712)
			(xy 28.621569 -106.310452) (xy 28.632073 -106.355032) (xy 28.640786 -106.376216) (xy 28.653183 -106.405888)
			(xy 28.670917 -106.4677) (xy 28.680295 -106.531319) (xy 28.681152 -106.595619) (xy 28.673472 -106.659465)
			(xy 28.657392 -106.721728) (xy 28.633195 -106.781308) (xy 28.601309 -106.837152) (xy 28.562297 -106.888273)
			(xy 28.539948 -106.911394) (xy 28.162758 -107.28833) (xy 28.146765 -107.304919) (xy 28.120588 -107.342838)
			(xy 28.101675 -107.384856) (xy 28.090647 -107.429594) (xy 28.087864 -107.475588) (xy 28.093418 -107.521329)
			(xy 28.107128 -107.56532) (xy 28.128543 -107.606119) (xy 28.156962 -107.642389) (xy 28.191454 -107.672942)
			(xy 28.230888 -107.696776) (xy 28.273973 -107.71311) (xy 28.319297 -107.721411) (xy 28.342336 -107.721908)
			(xy 28.523184 -107.721908) (xy 28.527502 -107.717844) (xy 29.221684 -107.717844) (xy 29.225494 -107.7214)
			(xy 29.602176 -107.7214) (xy 29.617018 -107.721038) (xy 29.645907 -107.714226) (xy 29.672427 -107.700899)
			(xy 29.695133 -107.681782) (xy 29.704284 -107.670092) (xy 29.730635 -107.635347) (xy 29.788824 -107.570389)
			(xy 29.852779 -107.511098) (xy 29.921949 -107.457985) (xy 29.99574 -107.411505) (xy 30.073518 -107.372058)
			(xy 30.154615 -107.339983) (xy 30.238334 -107.315555) (xy 30.323955 -107.298985) (xy 30.410742 -107.290415)
			(xy 30.49795 -107.289918) (xy 30.58483 -107.297499) (xy 30.670634 -107.313092) (xy 30.754626 -107.336564)
			(xy 30.836083 -107.367713) (xy 30.914306 -107.406272) (xy 30.988622 -107.451908) (xy 31.058392 -107.50423)
			(xy 31.123018 -107.562788) (xy 31.181944 -107.627078) (xy 31.234663 -107.69655) (xy 31.280722 -107.770604)
			(xy 31.319726 -107.848606) (xy 31.351339 -107.929884) (xy 31.37529 -108.01374) (xy 31.391372 -108.099454)
			(xy 31.399449 -108.186289) (xy 31.399449 -108.273498) (xy 31.391374 -108.360333) (xy 31.375293 -108.446048)
			(xy 31.351343 -108.529904) (xy 31.319731 -108.611183) (xy 31.280728 -108.689185) (xy 31.23467 -108.76324)
			(xy 31.181952 -108.832712) (xy 31.123027 -108.897003) (xy 31.058402 -108.955562) (xy 30.988632 -109.007885)
			(xy 30.914317 -109.053522) (xy 30.836095 -109.092081) (xy 30.754638 -109.123232) (xy 30.670647 -109.146705)
			(xy 30.584843 -109.1623) (xy 30.497963 -109.169882) (xy 30.410755 -109.169386) (xy 30.323967 -109.160817)
			(xy 30.238346 -109.144248) (xy 30.154627 -109.119821) (xy 30.07353 -109.087747) (xy 29.995751 -109.048301)
			(xy 29.921959 -109.001823) (xy 29.852788 -108.94871) (xy 29.788833 -108.889421) (xy 29.730643 -108.824463)
			(xy 29.704284 -108.789724) (xy 29.695101 -108.778072) (xy 29.672373 -108.759013) (xy 29.645866 -108.745702)
			(xy 29.617006 -108.738853) (xy 29.602176 -108.738416) (xy 28.944824 -108.738416) (xy 28.944316 -108.738924)
			(xy 28.083764 -108.738924) (xy 28.060857 -108.739461) (xy 28.015781 -108.747646) (xy 27.972904 -108.763782)
			(xy 27.933614 -108.787344) (xy 27.899187 -108.81757) (xy 27.870737 -108.853479) (xy 27.849187 -108.893908)
			(xy 27.835236 -108.937545) (xy 27.829336 -108.982976) (xy 27.830018 -109.005878) (xy 27.83078 -109.030516)
			(xy 27.83078 -109.765592) (xy 28.14828 -110.083092) (xy 28.170282 -110.105825) (xy 28.208795 -110.156017)
			(xy 28.240428 -110.210806) (xy 28.264639 -110.269256) (xy 28.281013 -110.330365) (xy 28.289271 -110.393089)
			(xy 28.289271 -110.456355) (xy 28.281013 -110.519079) (xy 28.264639 -110.580188) (xy 28.240428 -110.638638)
			(xy 28.208795 -110.693427) (xy 28.170282 -110.743619) (xy 28.125547 -110.788354) (xy 28.092961 -110.813358)
			(xy 29.519874 -110.813358) (xy 29.519874 -110.726458) (xy 29.527892 -110.639929) (xy 29.54386 -110.554509)
			(xy 29.567641 -110.470927) (xy 29.599033 -110.389895) (xy 29.637767 -110.312106) (xy 29.683514 -110.238222)
			(xy 29.735883 -110.168875) (xy 29.794427 -110.104655) (xy 29.858647 -110.046111) (xy 29.927994 -109.993742)
			(xy 30.001878 -109.947995) (xy 30.079667 -109.909261) (xy 30.160699 -109.877869) (xy 30.244281 -109.854088)
			(xy 30.329701 -109.83812) (xy 30.41623 -109.830102) (xy 30.50313 -109.830102) (xy 30.589659 -109.83812)
			(xy 30.675079 -109.854088) (xy 30.758661 -109.877869) (xy 30.839693 -109.909261) (xy 30.917482 -109.947995)
			(xy 30.991366 -109.993742) (xy 31.060713 -110.046111) (xy 31.124933 -110.104655) (xy 31.183477 -110.168875)
			(xy 31.235846 -110.238222) (xy 31.281593 -110.312106) (xy 31.320327 -110.389895) (xy 31.351719 -110.470927)
			(xy 31.3755 -110.554509) (xy 31.391468 -110.639929) (xy 31.399486 -110.726458) (xy 31.399988 -110.769893)
			(xy 34.599047 -110.769893) (xy 34.603036 -110.683372) (xy 34.614965 -110.597584) (xy 34.634735 -110.513257)
			(xy 34.662178 -110.431105) (xy 34.69706 -110.351827) (xy 34.739087 -110.276092) (xy 34.787902 -110.204545)
			(xy 34.84309 -110.137791) (xy 34.904185 -110.076396) (xy 34.970668 -110.020881) (xy 35.041976 -109.971716)
			(xy 35.117503 -109.929319) (xy 35.19661 -109.894048) (xy 35.278626 -109.866204) (xy 35.362855 -109.846021)
			(xy 35.448584 -109.833671) (xy 35.535085 -109.829259) (xy 35.621625 -109.832822) (xy 35.707471 -109.84433)
			(xy 35.791894 -109.863685) (xy 35.874179 -109.890724) (xy 35.953628 -109.925216) (xy 36.029568 -109.96687)
			(xy 36.101354 -110.015333) (xy 36.168379 -110.070193) (xy 36.230073 -110.130985) (xy 36.285914 -110.197195)
			(xy 36.311078 -110.232444) (xy 36.320211 -110.244749) (xy 36.343219 -110.264975) (xy 36.37039 -110.279124)
			(xy 36.400154 -110.286374) (xy 36.415472 -110.2868) (xy 38.723824 -110.2868) (xy 38.747123 -110.286238)
			(xy 38.792943 -110.277756) (xy 38.836448 -110.261061) (xy 38.87618 -110.236714) (xy 38.910807 -110.205531)
			(xy 38.939168 -110.168557) (xy 38.960312 -110.127032) (xy 38.97353 -110.082347) (xy 38.97838 -110.036002)
			(xy 38.977062 -110.012734) (xy 38.975003 -109.980664) (xy 38.978392 -109.91649) (xy 38.990268 -109.853333)
			(xy 39.010422 -109.792311) (xy 39.038495 -109.734504) (xy 39.055802 -109.707426) (xy 39.076884 -109.675422)
			(xy 39.076884 -109.618018) (xy 39.129208 -109.618018) (xy 39.163498 -109.591602) (xy 39.188935 -109.572629)
			(xy 39.243848 -109.540821) (xy 39.302454 -109.516482) (xy 39.363745 -109.500033) (xy 39.426662 -109.491756)
			(xy 39.458392 -109.491272) (xy 40.336978 -109.491272) (xy 40.368596 -109.491713) (xy 40.431292 -109.499965)
			(xy 40.492374 -109.516329) (xy 40.550797 -109.540526) (xy 40.605563 -109.572143) (xy 40.655732 -109.610637)
			(xy 40.700448 -109.655351) (xy 40.738945 -109.705519) (xy 40.770564 -109.760283) (xy 40.794764 -109.818705)
			(xy 40.811131 -109.879787) (xy 40.819385 -109.942482) (xy 40.819385 -110.005718) (xy 40.811131 -110.068413)
			(xy 40.794764 -110.129495) (xy 40.770564 -110.187917) (xy 40.738945 -110.242681) (xy 40.700448 -110.292849)
			(xy 40.655732 -110.337563) (xy 40.605563 -110.376057) (xy 40.550797 -110.407674) (xy 40.492374 -110.431871)
			(xy 40.431292 -110.448235) (xy 40.368596 -110.456487) (xy 40.336978 -110.45698) (xy 40.192706 -110.45698)
			(xy 40.169313 -110.457525) (xy 40.123321 -110.466104) (xy 40.079675 -110.482956) (xy 40.039851 -110.50751)
			(xy 40.005193 -110.538939) (xy 39.976872 -110.576179) (xy 39.955845 -110.617974) (xy 39.942822 -110.662911)
			(xy 39.938243 -110.709472) (xy 39.939722 -110.732824) (xy 39.941263 -110.753433) (xy 39.941264 -110.794765)
			(xy 39.939722 -110.815374) (xy 39.938197 -110.838715) (xy 39.942792 -110.885259) (xy 39.95583 -110.930176)
			(xy 39.97687 -110.971947) (xy 40.005201 -111.009161) (xy 40.039866 -111.040559) (xy 40.079693 -111.065081)
			(xy 40.123336 -111.081898) (xy 40.16932 -111.090441) (xy 40.192706 -111.090964) (xy 40.390826 -111.090964)
			(xy 40.422454 -111.091539) (xy 40.485168 -111.099798) (xy 40.546267 -111.116173) (xy 40.604707 -111.140382)
			(xy 40.659486 -111.172012) (xy 40.709669 -111.210521) (xy 40.754396 -111.25525) (xy 40.792903 -111.305435)
			(xy 40.82453 -111.360217) (xy 40.848736 -111.418657) (xy 40.865107 -111.479758) (xy 40.873363 -111.542472)
			(xy 40.873363 -111.605728) (xy 40.865107 -111.668442) (xy 40.848736 -111.729543) (xy 40.82453 -111.787983)
			(xy 40.792903 -111.842765) (xy 40.754396 -111.89295) (xy 40.709669 -111.937679) (xy 40.659486 -111.976188)
			(xy 40.604707 -112.007818) (xy 40.546267 -112.032027) (xy 40.485168 -112.048402) (xy 40.422454 -112.056661)
			(xy 40.390826 -112.05718) (xy 39.459154 -112.05718) (xy 39.427416 -112.05666) (xy 39.36449 -112.048336)
			(xy 39.303196 -112.031836) (xy 39.244594 -112.007447) (xy 39.189693 -111.975587) (xy 39.16426 -111.956596)
			(xy 39.12997 -111.93018) (xy 39.077646 -111.93018) (xy 39.077646 -111.872776) (xy 39.056564 -111.840772)
			(xy 39.038963 -111.813241) (xy 39.010523 -111.754411) (xy 38.990273 -111.692285) (xy 38.978582 -111.627995)
			(xy 38.975663 -111.562717) (xy 38.978078 -111.53013) (xy 38.979728 -111.506726) (xy 38.975338 -111.460016)
			(xy 38.962452 -111.414905) (xy 38.941508 -111.372924) (xy 38.913218 -111.335498) (xy 38.878542 -111.303897)
			(xy 38.838656 -111.279195) (xy 38.794916 -111.26223) (xy 38.748805 -111.253577) (xy 38.725348 -111.253016)
			(xy 36.415472 -111.253016) (xy 36.400156 -111.253447) (xy 36.370398 -111.260709) (xy 36.343229 -111.274857)
			(xy 36.320217 -111.295073) (xy 36.311078 -111.307372) (xy 36.285906 -111.342616) (xy 36.230064 -111.408824)
			(xy 36.168369 -111.469616) (xy 36.101344 -111.524475) (xy 36.029557 -111.572936) (xy 35.953616 -111.61459)
			(xy 35.874167 -111.649081) (xy 35.791881 -111.676118) (xy 35.707458 -111.695473) (xy 35.621612 -111.706979)
			(xy 35.535072 -111.710541) (xy 35.44857 -111.706128) (xy 35.362842 -111.693777) (xy 35.278613 -111.673593)
			(xy 35.196598 -111.645747) (xy 35.117491 -111.610475) (xy 35.041964 -111.568077) (xy 34.970658 -111.518911)
			(xy 34.904176 -111.463395) (xy 34.843082 -111.402) (xy 34.787894 -111.335245) (xy 34.73908 -111.263696)
			(xy 34.697054 -111.187962) (xy 34.662173 -111.108682) (xy 34.634732 -111.026531) (xy 34.614963 -110.942203)
			(xy 34.603035 -110.856415) (xy 34.599047 -110.769893) (xy 31.399988 -110.769893) (xy 31.399988 -110.769908)
			(xy 31.399486 -110.813358) (xy 31.391468 -110.899887) (xy 31.3755 -110.985307) (xy 31.351719 -111.068889)
			(xy 31.320327 -111.149921) (xy 31.281593 -111.22771) (xy 31.235846 -111.301594) (xy 31.183477 -111.370941)
			(xy 31.124933 -111.435161) (xy 31.060713 -111.493705) (xy 30.991366 -111.546074) (xy 30.917482 -111.591821)
			(xy 30.839693 -111.630555) (xy 30.758661 -111.661947) (xy 30.675079 -111.685728) (xy 30.589659 -111.701696)
			(xy 30.50313 -111.709714) (xy 30.41623 -111.709714) (xy 30.329701 -111.701696) (xy 30.244281 -111.685728)
			(xy 30.160699 -111.661947) (xy 30.079667 -111.630555) (xy 30.001878 -111.591821) (xy 29.927994 -111.546074)
			(xy 29.858647 -111.493705) (xy 29.794427 -111.435161) (xy 29.735883 -111.370941) (xy 29.683514 -111.301594)
			(xy 29.637767 -111.22771) (xy 29.599033 -111.149921) (xy 29.567641 -111.068889) (xy 29.54386 -110.985307)
			(xy 29.527892 -110.899887) (xy 29.519874 -110.813358) (xy 28.092961 -110.813358) (xy 28.075355 -110.826867)
			(xy 28.020566 -110.8585) (xy 27.962116 -110.882711) (xy 27.901007 -110.899085) (xy 27.838283 -110.907343)
			(xy 27.775017 -110.907343) (xy 27.712293 -110.899085) (xy 27.651184 -110.882711) (xy 27.592734 -110.8585)
			(xy 27.537945 -110.826867) (xy 27.487753 -110.788354) (xy 27.46502 -110.766352) (xy 26.864564 -110.165896)
			(xy 26.864564 -109.030516) (xy 26.866596 -108.987082) (xy 26.868128 -108.964902) (xy 26.864315 -108.920608)
			(xy 26.852854 -108.877654) (xy 26.834093 -108.837349) (xy 26.808606 -108.800923) (xy 26.777169 -108.769487)
			(xy 26.740742 -108.744001) (xy 26.700436 -108.725242) (xy 26.657481 -108.713783) (xy 26.613187 -108.709972)
			(xy 26.591006 -108.711492) (xy 26.547572 -108.713524) (xy 25.90546 -108.713524) (xy 25.873829 -108.713015)
			(xy 25.811108 -108.704758) (xy 25.750002 -108.688384) (xy 25.691556 -108.664175) (xy 25.636769 -108.632544)
			(xy 25.58658 -108.594033) (xy 25.541847 -108.5493) (xy 25.503336 -108.499111) (xy 25.471705 -108.444324)
			(xy 25.447496 -108.385878) (xy 25.431122 -108.324772) (xy 25.422865 -108.262051) (xy 25.422865 -108.198789)
			(xy 25.431122 -108.136068) (xy 25.447496 -108.074962) (xy 25.471705 -108.016516) (xy 25.503336 -107.961729)
			(xy 25.541847 -107.91154) (xy 25.58658 -107.866807) (xy 25.636769 -107.828296) (xy 25.691556 -107.796665)
			(xy 25.750002 -107.772456) (xy 25.811108 -107.756082) (xy 25.873829 -107.747825) (xy 25.90546 -107.747308)
			(xy 26.547572 -107.747308) (xy 26.591006 -107.74934) (xy 26.613185 -107.750921) (xy 26.657485 -107.747109)
			(xy 26.700445 -107.735647) (xy 26.740756 -107.716883) (xy 26.777185 -107.69139) (xy 26.808622 -107.659946)
			(xy 26.834108 -107.623511) (xy 26.852864 -107.583198) (xy 26.864318 -107.540235) (xy 26.868121 -107.495934)
			(xy 26.866596 -107.47375) (xy 26.864564 -107.430316) (xy 26.864564 -107.220258) (xy 26.94686 -107.138216)
			(xy 26.966164 -107.091734) (xy 26.966164 -107.074208) (xy 27.010868 -107.074208) (xy 27.630882 -106.454194)
			(xy 27.646822 -106.437558) (xy 27.672994 -106.399645) (xy 27.691903 -106.357635) (xy 27.702929 -106.312905)
			(xy 27.705712 -106.266919) (xy 27.70016 -106.221186) (xy 27.686456 -106.177202) (xy 27.665047 -106.136409)
			(xy 27.636636 -106.100144) (xy 27.602153 -106.069593) (xy 27.562729 -106.045759) (xy 27.519653 -106.029422)
			(xy 27.474339 -106.021117) (xy 27.451304 -106.020616) (xy 24.230584 -106.020616) (xy 24.04872 -106.20248)
			(xy 24.039068 -106.229912) (xy 24.029106 -106.257044) (xy 24.002199 -106.308194) (xy 23.985474 -106.331766)
			(xy 23.972027 -106.350969) (xy 23.951534 -106.393123) (xy 23.939123 -106.43832) (xy 23.935214 -106.485028)
			(xy 23.93994 -106.53166) (xy 23.953141 -106.576633) (xy 23.974369 -106.618421) (xy 24.002903 -106.655606)
			(xy 24.037775 -106.686924) (xy 24.077801 -106.711313) (xy 24.09952 -106.720132) (xy 24.125536 -106.730475)
			(xy 24.174412 -106.757783) (xy 24.218772 -106.79194) (xy 24.257665 -106.832213) (xy 24.290255 -106.877738)
			(xy 24.315843 -106.927535) (xy 24.333879 -106.980538) (xy 24.343976 -107.035607) (xy 24.345918 -107.09156)
			(xy 24.339663 -107.147197) (xy 24.325344 -107.201322) (xy 24.30327 -107.252774) (xy 24.273914 -107.300448)
			(xy 24.237907 -107.34332) (xy 24.196021 -107.38047) (xy 24.149156 -107.411101) (xy 24.098318 -107.434555)
			(xy 24.044599 -107.450328) (xy 23.989151 -107.458081) (xy 23.933166 -107.457649) (xy 23.877844 -107.44904)
			(xy 23.824375 -107.43244) (xy 23.773905 -107.408204) (xy 23.727519 -107.376854) (xy 23.686212 -107.339061)
			(xy 23.65087 -107.295638) (xy 23.622254 -107.247517) (xy 23.600977 -107.19573) (xy 23.587495 -107.141391)
			(xy 23.5821 -107.085664) (xy 23.584905 -107.029747) (xy 23.595851 -106.974841) (xy 23.614703 -106.922123)
			(xy 23.641057 -106.872726) (xy 23.657306 -106.849926) (xy 23.670771 -106.830734) (xy 23.691266 -106.788579)
			(xy 23.703678 -106.743378) (xy 23.707587 -106.696668) (xy 23.702859 -106.650034) (xy 23.689656 -106.605058)
			(xy 23.668425 -106.563268) (xy 23.639887 -106.526083) (xy 23.605011 -106.494765) (xy 23.564981 -106.470378)
			(xy 23.54326 -106.46156) (xy 23.51779 -106.451326) (xy 23.469793 -106.424698) (xy 23.426109 -106.391465)
			(xy 23.38764 -106.352313) (xy 23.35518 -106.308052) (xy 23.3294 -106.259594) (xy 23.310832 -106.207942)
			(xy 23.29986 -106.154161) (xy 23.29671 -106.099363) (xy 22.8473 -106.099363) (xy 22.8473 -107.967272)
			(xy 27.89936 -113.019332) (xy 27.89936 -113.353358) (xy 29.519874 -113.353358) (xy 29.519874 -113.266458)
			(xy 29.527892 -113.179929) (xy 29.54386 -113.094509) (xy 29.567641 -113.010927) (xy 29.599033 -112.929895)
			(xy 29.637767 -112.852106) (xy 29.683514 -112.778222) (xy 29.735883 -112.708875) (xy 29.794427 -112.644655)
			(xy 29.858647 -112.586111) (xy 29.927994 -112.533742) (xy 30.001878 -112.487995) (xy 30.079667 -112.449261)
			(xy 30.160699 -112.417869) (xy 30.244281 -112.394088) (xy 30.329701 -112.37812) (xy 30.41623 -112.370102)
			(xy 30.50313 -112.370102) (xy 30.589659 -112.37812) (xy 30.675079 -112.394088) (xy 30.758661 -112.417869)
			(xy 30.839693 -112.449261) (xy 30.917482 -112.487995) (xy 30.991366 -112.533742) (xy 31.060713 -112.586111)
			(xy 31.124933 -112.644655) (xy 31.183477 -112.708875) (xy 31.235846 -112.778222) (xy 31.281593 -112.852106)
			(xy 31.320327 -112.929895) (xy 31.351719 -113.010927) (xy 31.3755 -113.094509) (xy 31.391468 -113.179929)
			(xy 31.399486 -113.266458) (xy 31.399988 -113.309908) (xy 31.399486 -113.353358) (xy 34.599874 -113.353358)
			(xy 34.599874 -113.266458) (xy 34.607892 -113.179929) (xy 34.62386 -113.094509) (xy 34.647641 -113.010927)
			(xy 34.679033 -112.929895) (xy 34.717767 -112.852106) (xy 34.763514 -112.778222) (xy 34.815883 -112.708875)
			(xy 34.874427 -112.644655) (xy 34.938647 -112.586111) (xy 35.007994 -112.533742) (xy 35.081878 -112.487995)
			(xy 35.159667 -112.449261) (xy 35.240699 -112.417869) (xy 35.324281 -112.394088) (xy 35.409701 -112.37812)
			(xy 35.49623 -112.370102) (xy 35.58313 -112.370102) (xy 35.669659 -112.37812) (xy 35.755079 -112.394088)
			(xy 35.838661 -112.417869) (xy 35.919693 -112.449261) (xy 35.997482 -112.487995) (xy 36.071366 -112.533742)
			(xy 36.140713 -112.586111) (xy 36.204933 -112.644655) (xy 36.263477 -112.708875) (xy 36.315846 -112.778222)
			(xy 36.361593 -112.852106) (xy 36.400327 -112.929895) (xy 36.431719 -113.010927) (xy 36.4555 -113.094509)
			(xy 36.471468 -113.179929) (xy 36.479486 -113.266458) (xy 36.479988 -113.309908) (xy 36.479486 -113.353358)
			(xy 36.471468 -113.439887) (xy 36.4555 -113.525307) (xy 36.431719 -113.608889) (xy 36.400327 -113.689921)
			(xy 36.361593 -113.76771) (xy 36.315846 -113.841594) (xy 36.263477 -113.910941) (xy 36.204933 -113.975161)
			(xy 36.140713 -114.033705) (xy 36.071366 -114.086074) (xy 35.997482 -114.131821) (xy 35.919693 -114.170555)
			(xy 35.838661 -114.201947) (xy 35.755079 -114.225728) (xy 35.669659 -114.241696) (xy 35.58313 -114.249714)
			(xy 35.49623 -114.249714) (xy 35.409701 -114.241696) (xy 35.324281 -114.225728) (xy 35.240699 -114.201947)
			(xy 35.159667 -114.170555) (xy 35.081878 -114.131821) (xy 35.007994 -114.086074) (xy 34.938647 -114.033705)
			(xy 34.874427 -113.975161) (xy 34.815883 -113.910941) (xy 34.763514 -113.841594) (xy 34.717767 -113.76771)
			(xy 34.679033 -113.689921) (xy 34.647641 -113.608889) (xy 34.62386 -113.525307) (xy 34.607892 -113.439887)
			(xy 34.599874 -113.353358) (xy 31.399486 -113.353358) (xy 31.391468 -113.439887) (xy 31.3755 -113.525307)
			(xy 31.351719 -113.608889) (xy 31.320327 -113.689921) (xy 31.281593 -113.76771) (xy 31.235846 -113.841594)
			(xy 31.183477 -113.910941) (xy 31.124933 -113.975161) (xy 31.060713 -114.033705) (xy 30.991366 -114.086074)
			(xy 30.917482 -114.131821) (xy 30.839693 -114.170555) (xy 30.758661 -114.201947) (xy 30.675079 -114.225728)
			(xy 30.589659 -114.241696) (xy 30.50313 -114.249714) (xy 30.41623 -114.249714) (xy 30.329701 -114.241696)
			(xy 30.244281 -114.225728) (xy 30.160699 -114.201947) (xy 30.079667 -114.170555) (xy 30.001878 -114.131821)
			(xy 29.927994 -114.086074) (xy 29.858647 -114.033705) (xy 29.794427 -113.975161) (xy 29.735883 -113.910941)
			(xy 29.683514 -113.841594) (xy 29.637767 -113.76771) (xy 29.599033 -113.689921) (xy 29.567641 -113.608889)
			(xy 29.54386 -113.525307) (xy 29.527892 -113.439887) (xy 29.519874 -113.353358) (xy 27.89936 -113.353358)
			(xy 27.89936 -115.893358) (xy 29.519874 -115.893358) (xy 29.519874 -115.806458) (xy 29.527892 -115.719929)
			(xy 29.54386 -115.634509) (xy 29.567641 -115.550927) (xy 29.599033 -115.469895) (xy 29.637767 -115.392106)
			(xy 29.683514 -115.318222) (xy 29.735883 -115.248875) (xy 29.794427 -115.184655) (xy 29.858647 -115.126111)
			(xy 29.927994 -115.073742) (xy 30.001878 -115.027995) (xy 30.079667 -114.989261) (xy 30.160699 -114.957869)
			(xy 30.244281 -114.934088) (xy 30.329701 -114.91812) (xy 30.41623 -114.910102) (xy 30.50313 -114.910102)
			(xy 30.589659 -114.91812) (xy 30.675079 -114.934088) (xy 30.758661 -114.957869) (xy 30.839693 -114.989261)
			(xy 30.917482 -115.027995) (xy 30.991366 -115.073742) (xy 31.060713 -115.126111) (xy 31.124933 -115.184655)
			(xy 31.183477 -115.248875) (xy 31.235846 -115.318222) (xy 31.281593 -115.392106) (xy 31.320327 -115.469895)
			(xy 31.351719 -115.550927) (xy 31.3755 -115.634509) (xy 31.391468 -115.719929) (xy 31.399486 -115.806458)
			(xy 31.399988 -115.849908) (xy 31.399486 -115.893358) (xy 34.599874 -115.893358) (xy 34.599874 -115.806458)
			(xy 34.607892 -115.719929) (xy 34.62386 -115.634509) (xy 34.647641 -115.550927) (xy 34.679033 -115.469895)
			(xy 34.717767 -115.392106) (xy 34.763514 -115.318222) (xy 34.815883 -115.248875) (xy 34.874427 -115.184655)
			(xy 34.938647 -115.126111) (xy 35.007994 -115.073742) (xy 35.081878 -115.027995) (xy 35.159667 -114.989261)
			(xy 35.240699 -114.957869) (xy 35.324281 -114.934088) (xy 35.409701 -114.91812) (xy 35.49623 -114.910102)
			(xy 35.58313 -114.910102) (xy 35.669659 -114.91812) (xy 35.755079 -114.934088) (xy 35.838661 -114.957869)
			(xy 35.919693 -114.989261) (xy 35.997482 -115.027995) (xy 36.071366 -115.073742) (xy 36.140713 -115.126111)
			(xy 36.204933 -115.184655) (xy 36.263477 -115.248875) (xy 36.315846 -115.318222) (xy 36.361593 -115.392106)
			(xy 36.400327 -115.469895) (xy 36.431719 -115.550927) (xy 36.4555 -115.634509) (xy 36.471468 -115.719929)
			(xy 36.479486 -115.806458) (xy 36.479988 -115.849908) (xy 36.479486 -115.893358) (xy 36.471468 -115.979887)
			(xy 36.4555 -116.065307) (xy 36.431719 -116.148889) (xy 36.400327 -116.229921) (xy 36.361593 -116.30771)
			(xy 36.315846 -116.381594) (xy 36.263477 -116.450941) (xy 36.204933 -116.515161) (xy 36.140713 -116.573705)
			(xy 36.071366 -116.626074) (xy 35.997482 -116.671821) (xy 35.919693 -116.710555) (xy 35.838661 -116.741947)
			(xy 35.755079 -116.765728) (xy 35.669659 -116.781696) (xy 35.58313 -116.789714) (xy 35.49623 -116.789714)
			(xy 35.409701 -116.781696) (xy 35.324281 -116.765728) (xy 35.240699 -116.741947) (xy 35.159667 -116.710555)
			(xy 35.081878 -116.671821) (xy 35.007994 -116.626074) (xy 34.938647 -116.573705) (xy 34.874427 -116.515161)
			(xy 34.815883 -116.450941) (xy 34.763514 -116.381594) (xy 34.717767 -116.30771) (xy 34.679033 -116.229921)
			(xy 34.647641 -116.148889) (xy 34.62386 -116.065307) (xy 34.607892 -115.979887) (xy 34.599874 -115.893358)
			(xy 31.399486 -115.893358) (xy 31.391468 -115.979887) (xy 31.3755 -116.065307) (xy 31.351719 -116.148889)
			(xy 31.320327 -116.229921) (xy 31.281593 -116.30771) (xy 31.235846 -116.381594) (xy 31.183477 -116.450941)
			(xy 31.124933 -116.515161) (xy 31.060713 -116.573705) (xy 30.991366 -116.626074) (xy 30.917482 -116.671821)
			(xy 30.839693 -116.710555) (xy 30.758661 -116.741947) (xy 30.675079 -116.765728) (xy 30.589659 -116.781696)
			(xy 30.50313 -116.789714) (xy 30.41623 -116.789714) (xy 30.329701 -116.781696) (xy 30.244281 -116.765728)
			(xy 30.160699 -116.741947) (xy 30.079667 -116.710555) (xy 30.001878 -116.671821) (xy 29.927994 -116.626074)
			(xy 29.858647 -116.573705) (xy 29.794427 -116.515161) (xy 29.735883 -116.450941) (xy 29.683514 -116.381594)
			(xy 29.637767 -116.30771) (xy 29.599033 -116.229921) (xy 29.567641 -116.148889) (xy 29.54386 -116.065307)
			(xy 29.527892 -115.979887) (xy 29.519874 -115.893358) (xy 27.89936 -115.893358) (xy 27.89936 -117.311017)
			(xy 39.098212 -117.311017) (xy 39.098212 -117.239695) (xy 39.106198 -117.168821) (xy 39.122068 -117.099286)
			(xy 39.145625 -117.031966) (xy 39.17657 -116.967707) (xy 39.214516 -116.907316) (xy 39.258985 -116.851554)
			(xy 39.309418 -116.801121) (xy 39.36518 -116.756652) (xy 39.425571 -116.718706) (xy 39.48983 -116.687761)
			(xy 39.55715 -116.664204) (xy 39.626685 -116.648334) (xy 39.697559 -116.640348) (xy 39.768881 -116.640348)
			(xy 39.839755 -116.648334) (xy 39.90929 -116.664204) (xy 39.97661 -116.687761) (xy 40.040869 -116.718706)
			(xy 40.10126 -116.756652) (xy 40.157022 -116.801121) (xy 40.207455 -116.851554) (xy 40.251924 -116.907316)
			(xy 40.28987 -116.967707) (xy 40.320815 -117.031966) (xy 40.344372 -117.099286) (xy 40.356116 -117.150743)
			(xy 58.432184 -117.150743) (xy 58.432184 -117.079421) (xy 58.44017 -117.008547) (xy 58.45604 -116.939012)
			(xy 58.479597 -116.871692) (xy 58.510542 -116.807433) (xy 58.548488 -116.747042) (xy 58.592957 -116.69128)
			(xy 58.64339 -116.640847) (xy 58.699152 -116.596378) (xy 58.759543 -116.558432) (xy 58.823802 -116.527487)
			(xy 58.891122 -116.50393) (xy 58.960657 -116.48806) (xy 59.031531 -116.480074) (xy 59.102853 -116.480074)
			(xy 59.173727 -116.48806) (xy 59.243262 -116.50393) (xy 59.310582 -116.527487) (xy 59.374841 -116.558432)
			(xy 59.435232 -116.596378) (xy 59.490994 -116.640847) (xy 59.541427 -116.69128) (xy 59.585896 -116.747042)
			(xy 59.623842 -116.807433) (xy 59.654787 -116.871692) (xy 59.678344 -116.939012) (xy 59.694214 -117.008547)
			(xy 59.7022 -117.079421) (xy 59.7027 -117.115082) (xy 59.7022 -117.150743) (xy 59.694214 -117.221617)
			(xy 59.678344 -117.291152) (xy 59.654787 -117.358472) (xy 59.623842 -117.422731) (xy 59.585896 -117.483122)
			(xy 59.541427 -117.538884) (xy 59.490994 -117.589317) (xy 59.435232 -117.633786) (xy 59.39426 -117.65953)
			(xy 67.010817 -117.65953) (xy 67.010817 -117.59627) (xy 67.019074 -117.533552) (xy 67.035446 -117.472448)
			(xy 67.059654 -117.414004) (xy 67.091283 -117.35922) (xy 67.129793 -117.309032) (xy 67.174523 -117.264301)
			(xy 67.22471 -117.22579) (xy 67.279493 -117.19416) (xy 67.337937 -117.16995) (xy 67.39904 -117.153576)
			(xy 67.461758 -117.145318) (xy 67.493388 -117.1448) (xy 68.291964 -117.1448) (xy 68.32263 -117.143785)
			(xy 68.383805 -117.148515) (xy 68.443889 -117.16095) (xy 68.501915 -117.180891) (xy 68.556951 -117.208016)
			(xy 68.582794 -117.224556) (xy 68.614798 -117.245638) (xy 68.81749 -117.245638) (xy 68.849494 -117.224556)
			(xy 68.873282 -117.209294) (xy 68.923737 -117.183819) (xy 68.976817 -117.164399) (xy 69.031799 -117.151299)
			(xy 69.087934 -117.144698) (xy 69.116194 -117.144292) (xy 69.847714 -117.144292) (xy 69.87933 -117.144718)
			(xy 69.942022 -117.152973) (xy 70.0031 -117.16934) (xy 70.061519 -117.19354) (xy 70.11628 -117.225157)
			(xy 70.166445 -117.263652) (xy 70.211157 -117.308365) (xy 70.24965 -117.358532) (xy 70.281266 -117.413293)
			(xy 70.305464 -117.471713) (xy 70.32183 -117.532792) (xy 70.330083 -117.595484) (xy 70.330083 -117.658716)
			(xy 70.32183 -117.721408) (xy 70.305464 -117.782487) (xy 70.281266 -117.840907) (xy 70.24965 -117.895668)
			(xy 70.211157 -117.945835) (xy 70.166445 -117.990548) (xy 70.11628 -118.029043) (xy 70.061519 -118.06066)
			(xy 70.0031 -118.08486) (xy 69.942022 -118.101227) (xy 69.87933 -118.109482) (xy 69.847714 -118.11)
			(xy 69.116194 -118.11) (xy 69.087931 -118.109621) (xy 69.031789 -118.103046) (xy 68.9768 -118.089953)
			(xy 68.92372 -118.070519) (xy 68.873275 -118.045014) (xy 68.849494 -118.029736) (xy 68.81749 -118.008654)
			(xy 68.67017 -118.008654) (xy 68.65349 -118.009195) (xy 68.621271 -118.017843) (xy 68.592391 -118.034539)
			(xy 68.580254 -118.045992) (xy 68.515484 -118.111016) (xy 67.493388 -118.111016) (xy 67.461758 -118.110482)
			(xy 67.39904 -118.102224) (xy 67.337937 -118.08585) (xy 67.279493 -118.06164) (xy 67.22471 -118.03001)
			(xy 67.174523 -117.991499) (xy 67.129793 -117.946768) (xy 67.091283 -117.89658) (xy 67.059654 -117.841796)
			(xy 67.035446 -117.783352) (xy 67.019074 -117.722248) (xy 67.010817 -117.65953) (xy 59.39426 -117.65953)
			(xy 59.374841 -117.671732) (xy 59.310582 -117.702677) (xy 59.243262 -117.726234) (xy 59.173727 -117.742104)
			(xy 59.102853 -117.75009) (xy 59.031531 -117.75009) (xy 58.960657 -117.742104) (xy 58.891122 -117.726234)
			(xy 58.823802 -117.702677) (xy 58.759543 -117.671732) (xy 58.699152 -117.633786) (xy 58.64339 -117.589317)
			(xy 58.592957 -117.538884) (xy 58.548488 -117.483122) (xy 58.510542 -117.422731) (xy 58.479597 -117.358472)
			(xy 58.45604 -117.291152) (xy 58.44017 -117.221617) (xy 58.432184 -117.150743) (xy 40.356116 -117.150743)
			(xy 40.360242 -117.168821) (xy 40.368228 -117.239695) (xy 40.368728 -117.275356) (xy 40.368228 -117.311017)
			(xy 40.360242 -117.381891) (xy 40.344372 -117.451426) (xy 40.320815 -117.518746) (xy 40.28987 -117.583005)
			(xy 40.251924 -117.643396) (xy 40.207455 -117.699158) (xy 40.157022 -117.749591) (xy 40.10126 -117.79406)
			(xy 40.040869 -117.832006) (xy 39.97661 -117.862951) (xy 39.90929 -117.886508) (xy 39.839755 -117.902378)
			(xy 39.768881 -117.910364) (xy 39.697559 -117.910364) (xy 39.626685 -117.902378) (xy 39.55715 -117.886508)
			(xy 39.48983 -117.862951) (xy 39.425571 -117.832006) (xy 39.36518 -117.79406) (xy 39.309418 -117.749591)
			(xy 39.258985 -117.699158) (xy 39.214516 -117.643396) (xy 39.17657 -117.583005) (xy 39.145625 -117.518746)
			(xy 39.122068 -117.451426) (xy 39.106198 -117.381891) (xy 39.098212 -117.311017) (xy 27.89936 -117.311017)
			(xy 27.89936 -118.433358) (xy 29.519874 -118.433358) (xy 29.519874 -118.346458) (xy 29.527892 -118.259929)
			(xy 29.54386 -118.174509) (xy 29.567641 -118.090927) (xy 29.599033 -118.009895) (xy 29.637767 -117.932106)
			(xy 29.683514 -117.858222) (xy 29.735883 -117.788875) (xy 29.794427 -117.724655) (xy 29.858647 -117.666111)
			(xy 29.927994 -117.613742) (xy 30.001878 -117.567995) (xy 30.079667 -117.529261) (xy 30.160699 -117.497869)
			(xy 30.244281 -117.474088) (xy 30.329701 -117.45812) (xy 30.41623 -117.450102) (xy 30.50313 -117.450102)
			(xy 30.589659 -117.45812) (xy 30.675079 -117.474088) (xy 30.758661 -117.497869) (xy 30.839693 -117.529261)
			(xy 30.917482 -117.567995) (xy 30.991366 -117.613742) (xy 31.060713 -117.666111) (xy 31.124933 -117.724655)
			(xy 31.183477 -117.788875) (xy 31.235846 -117.858222) (xy 31.281593 -117.932106) (xy 31.320327 -118.009895)
			(xy 31.351719 -118.090927) (xy 31.3755 -118.174509) (xy 31.391468 -118.259929) (xy 31.399486 -118.346458)
			(xy 31.399988 -118.389908) (xy 31.399486 -118.433358) (xy 34.599874 -118.433358) (xy 34.599874 -118.346458)
			(xy 34.607892 -118.259929) (xy 34.62386 -118.174509) (xy 34.647641 -118.090927) (xy 34.679033 -118.009895)
			(xy 34.717767 -117.932106) (xy 34.763514 -117.858222) (xy 34.815883 -117.788875) (xy 34.874427 -117.724655)
			(xy 34.938647 -117.666111) (xy 35.007994 -117.613742) (xy 35.081878 -117.567995) (xy 35.159667 -117.529261)
			(xy 35.240699 -117.497869) (xy 35.324281 -117.474088) (xy 35.409701 -117.45812) (xy 35.49623 -117.450102)
			(xy 35.58313 -117.450102) (xy 35.669659 -117.45812) (xy 35.755079 -117.474088) (xy 35.838661 -117.497869)
			(xy 35.919693 -117.529261) (xy 35.997482 -117.567995) (xy 36.071366 -117.613742) (xy 36.140713 -117.666111)
			(xy 36.204933 -117.724655) (xy 36.263477 -117.788875) (xy 36.315846 -117.858222) (xy 36.361593 -117.932106)
			(xy 36.400327 -118.009895) (xy 36.431719 -118.090927) (xy 36.4555 -118.174509) (xy 36.471468 -118.259929)
			(xy 36.479486 -118.346458) (xy 36.479988 -118.389908) (xy 36.479486 -118.433358) (xy 36.471468 -118.519887)
			(xy 36.4555 -118.605307) (xy 36.431719 -118.688889) (xy 36.400327 -118.769921) (xy 36.361593 -118.84771)
			(xy 36.315846 -118.921594) (xy 36.263477 -118.990941) (xy 36.204933 -119.055161) (xy 36.140713 -119.113705)
			(xy 36.099745 -119.144643) (xy 39.098212 -119.144643) (xy 39.098212 -119.073321) (xy 39.106198 -119.002447)
			(xy 39.122068 -118.932912) (xy 39.145625 -118.865592) (xy 39.17657 -118.801333) (xy 39.214516 -118.740942)
			(xy 39.258985 -118.68518) (xy 39.309418 -118.634747) (xy 39.36518 -118.590278) (xy 39.425571 -118.552332)
			(xy 39.48983 -118.521387) (xy 39.55715 -118.49783) (xy 39.626685 -118.48196) (xy 39.697559 -118.473974)
			(xy 39.768881 -118.473974) (xy 39.839755 -118.48196) (xy 39.90929 -118.49783) (xy 39.97661 -118.521387)
			(xy 40.040869 -118.552332) (xy 40.10126 -118.590278) (xy 40.157022 -118.634747) (xy 40.207455 -118.68518)
			(xy 40.251924 -118.740942) (xy 40.28987 -118.801333) (xy 40.320815 -118.865592) (xy 40.344372 -118.932912)
			(xy 40.356116 -118.984369) (xy 58.432184 -118.984369) (xy 58.432184 -118.913047) (xy 58.44017 -118.842173)
			(xy 58.45604 -118.772638) (xy 58.479597 -118.705318) (xy 58.510542 -118.641059) (xy 58.548488 -118.580668)
			(xy 58.592957 -118.524906) (xy 58.64339 -118.474473) (xy 58.699152 -118.430004) (xy 58.759543 -118.392058)
			(xy 58.823802 -118.361113) (xy 58.891122 -118.337556) (xy 58.960657 -118.321686) (xy 59.031531 -118.3137)
			(xy 59.102853 -118.3137) (xy 59.173727 -118.321686) (xy 59.243262 -118.337556) (xy 59.310582 -118.361113)
			(xy 59.374841 -118.392058) (xy 59.435232 -118.430004) (xy 59.490994 -118.474473) (xy 59.541427 -118.524906)
			(xy 59.585896 -118.580668) (xy 59.623842 -118.641059) (xy 59.654787 -118.705318) (xy 59.678344 -118.772638)
			(xy 59.694214 -118.842173) (xy 59.7022 -118.913047) (xy 59.7027 -118.948708) (xy 59.7022 -118.984369)
			(xy 60.673226 -118.984369) (xy 60.673226 -118.913047) (xy 60.681212 -118.842173) (xy 60.697082 -118.772638)
			(xy 60.720639 -118.705318) (xy 60.751584 -118.641059) (xy 60.78953 -118.580668) (xy 60.833999 -118.524906)
			(xy 60.884432 -118.474473) (xy 60.940194 -118.430004) (xy 61.000585 -118.392058) (xy 61.064844 -118.361113)
			(xy 61.132164 -118.337556) (xy 61.201699 -118.321686) (xy 61.272573 -118.3137) (xy 61.343895 -118.3137)
			(xy 61.414769 -118.321686) (xy 61.484304 -118.337556) (xy 61.551624 -118.361113) (xy 61.615883 -118.392058)
			(xy 61.676274 -118.430004) (xy 61.732036 -118.474473) (xy 61.782469 -118.524906) (xy 61.826938 -118.580668)
			(xy 61.864884 -118.641059) (xy 61.895829 -118.705318) (xy 61.919386 -118.772638) (xy 61.935256 -118.842173)
			(xy 61.943242 -118.913047) (xy 61.943742 -118.948708) (xy 61.943242 -118.984369) (xy 62.57721 -118.984369)
			(xy 62.57721 -118.913047) (xy 62.585196 -118.842173) (xy 62.601066 -118.772638) (xy 62.624623 -118.705318)
			(xy 62.655568 -118.641059) (xy 62.693514 -118.580668) (xy 62.737983 -118.524906) (xy 62.788416 -118.474473)
			(xy 62.844178 -118.430004) (xy 62.904569 -118.392058) (xy 62.968828 -118.361113) (xy 63.036148 -118.337556)
			(xy 63.105683 -118.321686) (xy 63.176557 -118.3137) (xy 63.247879 -118.3137) (xy 63.318753 -118.321686)
			(xy 63.388288 -118.337556) (xy 63.455608 -118.361113) (xy 63.519867 -118.392058) (xy 63.580258 -118.430004)
			(xy 63.63602 -118.474473) (xy 63.686453 -118.524906) (xy 63.730922 -118.580668) (xy 63.768868 -118.641059)
			(xy 63.799813 -118.705318) (xy 63.82337 -118.772638) (xy 63.83924 -118.842173) (xy 63.847226 -118.913047)
			(xy 63.847726 -118.948708) (xy 63.847226 -118.984369) (xy 63.83924 -119.055243) (xy 63.82337 -119.124778)
			(xy 63.799813 -119.192098) (xy 63.768868 -119.256357) (xy 63.730922 -119.316748) (xy 63.686453 -119.37251)
			(xy 63.63602 -119.422943) (xy 63.580258 -119.467412) (xy 63.519867 -119.505358) (xy 63.455608 -119.536303)
			(xy 63.388288 -119.55986) (xy 63.318753 -119.57573) (xy 63.247879 -119.583716) (xy 63.176557 -119.583716)
			(xy 63.105683 -119.57573) (xy 63.036148 -119.55986) (xy 62.968828 -119.536303) (xy 62.904569 -119.505358)
			(xy 62.844178 -119.467412) (xy 62.788416 -119.422943) (xy 62.737983 -119.37251) (xy 62.693514 -119.316748)
			(xy 62.655568 -119.256357) (xy 62.624623 -119.192098) (xy 62.601066 -119.124778) (xy 62.585196 -119.055243)
			(xy 62.57721 -118.984369) (xy 61.943242 -118.984369) (xy 61.935256 -119.055243) (xy 61.919386 -119.124778)
			(xy 61.895829 -119.192098) (xy 61.864884 -119.256357) (xy 61.826938 -119.316748) (xy 61.782469 -119.37251)
			(xy 61.732036 -119.422943) (xy 61.676274 -119.467412) (xy 61.615883 -119.505358) (xy 61.551624 -119.536303)
			(xy 61.484304 -119.55986) (xy 61.414769 -119.57573) (xy 61.343895 -119.583716) (xy 61.272573 -119.583716)
			(xy 61.201699 -119.57573) (xy 61.132164 -119.55986) (xy 61.064844 -119.536303) (xy 61.000585 -119.505358)
			(xy 60.940194 -119.467412) (xy 60.884432 -119.422943) (xy 60.833999 -119.37251) (xy 60.78953 -119.316748)
			(xy 60.751584 -119.256357) (xy 60.720639 -119.192098) (xy 60.697082 -119.124778) (xy 60.681212 -119.055243)
			(xy 60.673226 -118.984369) (xy 59.7022 -118.984369) (xy 59.694214 -119.055243) (xy 59.678344 -119.124778)
			(xy 59.654787 -119.192098) (xy 59.623842 -119.256357) (xy 59.585896 -119.316748) (xy 59.541427 -119.37251)
			(xy 59.490994 -119.422943) (xy 59.435232 -119.467412) (xy 59.374841 -119.505358) (xy 59.310582 -119.536303)
			(xy 59.243262 -119.55986) (xy 59.173727 -119.57573) (xy 59.102853 -119.583716) (xy 59.031531 -119.583716)
			(xy 58.960657 -119.57573) (xy 58.891122 -119.55986) (xy 58.823802 -119.536303) (xy 58.759543 -119.505358)
			(xy 58.699152 -119.467412) (xy 58.64339 -119.422943) (xy 58.592957 -119.37251) (xy 58.548488 -119.316748)
			(xy 58.510542 -119.256357) (xy 58.479597 -119.192098) (xy 58.45604 -119.124778) (xy 58.44017 -119.055243)
			(xy 58.432184 -118.984369) (xy 40.356116 -118.984369) (xy 40.360242 -119.002447) (xy 40.368228 -119.073321)
			(xy 40.368728 -119.108982) (xy 40.368228 -119.144643) (xy 40.360242 -119.215517) (xy 40.344372 -119.285052)
			(xy 40.320815 -119.352372) (xy 40.28987 -119.416631) (xy 40.251924 -119.477022) (xy 40.207455 -119.532784)
			(xy 40.157022 -119.583217) (xy 40.10126 -119.627686) (xy 40.040869 -119.665632) (xy 39.97661 -119.696577)
			(xy 39.90929 -119.720134) (xy 39.839755 -119.736004) (xy 39.768881 -119.74399) (xy 39.697559 -119.74399)
			(xy 39.626685 -119.736004) (xy 39.55715 -119.720134) (xy 39.48983 -119.696577) (xy 39.425571 -119.665632)
			(xy 39.36518 -119.627686) (xy 39.309418 -119.583217) (xy 39.258985 -119.532784) (xy 39.214516 -119.477022)
			(xy 39.17657 -119.416631) (xy 39.145625 -119.352372) (xy 39.122068 -119.285052) (xy 39.106198 -119.215517)
			(xy 39.098212 -119.144643) (xy 36.099745 -119.144643) (xy 36.071366 -119.166074) (xy 35.997482 -119.211821)
			(xy 35.919693 -119.250555) (xy 35.838661 -119.281947) (xy 35.755079 -119.305728) (xy 35.669659 -119.321696)
			(xy 35.58313 -119.329714) (xy 35.49623 -119.329714) (xy 35.409701 -119.321696) (xy 35.324281 -119.305728)
			(xy 35.240699 -119.281947) (xy 35.159667 -119.250555) (xy 35.081878 -119.211821) (xy 35.007994 -119.166074)
			(xy 34.938647 -119.113705) (xy 34.874427 -119.055161) (xy 34.815883 -118.990941) (xy 34.763514 -118.921594)
			(xy 34.717767 -118.84771) (xy 34.679033 -118.769921) (xy 34.647641 -118.688889) (xy 34.62386 -118.605307)
			(xy 34.607892 -118.519887) (xy 34.599874 -118.433358) (xy 31.399486 -118.433358) (xy 31.391468 -118.519887)
			(xy 31.3755 -118.605307) (xy 31.351719 -118.688889) (xy 31.320327 -118.769921) (xy 31.281593 -118.84771)
			(xy 31.235846 -118.921594) (xy 31.183477 -118.990941) (xy 31.124933 -119.055161) (xy 31.060713 -119.113705)
			(xy 30.991366 -119.166074) (xy 30.917482 -119.211821) (xy 30.839693 -119.250555) (xy 30.758661 -119.281947)
			(xy 30.675079 -119.305728) (xy 30.589659 -119.321696) (xy 30.50313 -119.329714) (xy 30.41623 -119.329714)
			(xy 30.329701 -119.321696) (xy 30.244281 -119.305728) (xy 30.160699 -119.281947) (xy 30.079667 -119.250555)
			(xy 30.001878 -119.211821) (xy 29.927994 -119.166074) (xy 29.858647 -119.113705) (xy 29.794427 -119.055161)
			(xy 29.735883 -118.990941) (xy 29.683514 -118.921594) (xy 29.637767 -118.84771) (xy 29.599033 -118.769921)
			(xy 29.567641 -118.688889) (xy 29.54386 -118.605307) (xy 29.527892 -118.519887) (xy 29.519874 -118.433358)
			(xy 27.89936 -118.433358) (xy 27.89936 -120.973358) (xy 29.519874 -120.973358) (xy 29.519874 -120.886458)
			(xy 29.527892 -120.799929) (xy 29.54386 -120.714509) (xy 29.567641 -120.630927) (xy 29.599033 -120.549895)
			(xy 29.637767 -120.472106) (xy 29.683514 -120.398222) (xy 29.735883 -120.328875) (xy 29.794427 -120.264655)
			(xy 29.858647 -120.206111) (xy 29.927994 -120.153742) (xy 30.001878 -120.107995) (xy 30.079667 -120.069261)
			(xy 30.160699 -120.037869) (xy 30.244281 -120.014088) (xy 30.329701 -119.99812) (xy 30.41623 -119.990102)
			(xy 30.50313 -119.990102) (xy 30.589659 -119.99812) (xy 30.675079 -120.014088) (xy 30.758661 -120.037869)
			(xy 30.839693 -120.069261) (xy 30.917482 -120.107995) (xy 30.991366 -120.153742) (xy 31.060713 -120.206111)
			(xy 31.124933 -120.264655) (xy 31.183477 -120.328875) (xy 31.235846 -120.398222) (xy 31.281593 -120.472106)
			(xy 31.320327 -120.549895) (xy 31.351719 -120.630927) (xy 31.3755 -120.714509) (xy 31.391468 -120.799929)
			(xy 31.399486 -120.886458) (xy 31.399988 -120.929908) (xy 31.399486 -120.973358) (xy 34.599874 -120.973358)
			(xy 34.599874 -120.886458) (xy 34.607892 -120.799929) (xy 34.62386 -120.714509) (xy 34.647641 -120.630927)
			(xy 34.679033 -120.549895) (xy 34.717767 -120.472106) (xy 34.763514 -120.398222) (xy 34.815883 -120.328875)
			(xy 34.874427 -120.264655) (xy 34.938647 -120.206111) (xy 35.007994 -120.153742) (xy 35.081878 -120.107995)
			(xy 35.159667 -120.069261) (xy 35.240699 -120.037869) (xy 35.324281 -120.014088) (xy 35.409701 -119.99812)
			(xy 35.49623 -119.990102) (xy 35.58313 -119.990102) (xy 35.669659 -119.99812) (xy 35.755079 -120.014088)
			(xy 35.838661 -120.037869) (xy 35.919693 -120.069261) (xy 35.997482 -120.107995) (xy 36.071366 -120.153742)
			(xy 36.140713 -120.206111) (xy 36.204933 -120.264655) (xy 36.263477 -120.328875) (xy 36.315846 -120.398222)
			(xy 36.361593 -120.472106) (xy 36.400327 -120.549895) (xy 36.431719 -120.630927) (xy 36.4555 -120.714509)
			(xy 36.471468 -120.799929) (xy 36.479486 -120.886458) (xy 36.479988 -120.929908) (xy 36.479486 -120.973358)
			(xy 36.472794 -121.045579) (xy 39.098212 -121.045579) (xy 39.098212 -120.974257) (xy 39.106198 -120.903383)
			(xy 39.122068 -120.833848) (xy 39.145625 -120.766528) (xy 39.17657 -120.702269) (xy 39.214516 -120.641878)
			(xy 39.258985 -120.586116) (xy 39.309418 -120.535683) (xy 39.36518 -120.491214) (xy 39.425571 -120.453268)
			(xy 39.48983 -120.422323) (xy 39.55715 -120.398766) (xy 39.626685 -120.382896) (xy 39.697559 -120.37491)
			(xy 39.768881 -120.37491) (xy 39.839755 -120.382896) (xy 39.90929 -120.398766) (xy 39.97661 -120.422323)
			(xy 40.040869 -120.453268) (xy 40.10126 -120.491214) (xy 40.157022 -120.535683) (xy 40.207455 -120.586116)
			(xy 40.251924 -120.641878) (xy 40.28987 -120.702269) (xy 40.320815 -120.766528) (xy 40.344372 -120.833848)
			(xy 40.356116 -120.885305) (xy 58.432184 -120.885305) (xy 58.432184 -120.813983) (xy 58.44017 -120.743109)
			(xy 58.45604 -120.673574) (xy 58.479597 -120.606254) (xy 58.510542 -120.541995) (xy 58.548488 -120.481604)
			(xy 58.592957 -120.425842) (xy 58.64339 -120.375409) (xy 58.699152 -120.33094) (xy 58.759543 -120.292994)
			(xy 58.823802 -120.262049) (xy 58.891122 -120.238492) (xy 58.960657 -120.222622) (xy 59.031531 -120.214636)
			(xy 59.102853 -120.214636) (xy 59.173727 -120.222622) (xy 59.243262 -120.238492) (xy 59.310582 -120.262049)
			(xy 59.374841 -120.292994) (xy 59.435232 -120.33094) (xy 59.490994 -120.375409) (xy 59.541427 -120.425842)
			(xy 59.585896 -120.481604) (xy 59.623842 -120.541995) (xy 59.654787 -120.606254) (xy 59.678344 -120.673574)
			(xy 59.694214 -120.743109) (xy 59.7022 -120.813983) (xy 59.7027 -120.849644) (xy 59.7022 -120.885305)
			(xy 60.673226 -120.885305) (xy 60.673226 -120.813983) (xy 60.681212 -120.743109) (xy 60.697082 -120.673574)
			(xy 60.720639 -120.606254) (xy 60.751584 -120.541995) (xy 60.78953 -120.481604) (xy 60.833999 -120.425842)
			(xy 60.884432 -120.375409) (xy 60.940194 -120.33094) (xy 61.000585 -120.292994) (xy 61.064844 -120.262049)
			(xy 61.132164 -120.238492) (xy 61.201699 -120.222622) (xy 61.272573 -120.214636) (xy 61.343895 -120.214636)
			(xy 61.414769 -120.222622) (xy 61.484304 -120.238492) (xy 61.551624 -120.262049) (xy 61.615883 -120.292994)
			(xy 61.676274 -120.33094) (xy 61.732036 -120.375409) (xy 61.782469 -120.425842) (xy 61.826938 -120.481604)
			(xy 61.864884 -120.541995) (xy 61.895829 -120.606254) (xy 61.919386 -120.673574) (xy 61.935256 -120.743109)
			(xy 61.943242 -120.813983) (xy 61.943742 -120.849644) (xy 61.943242 -120.885305) (xy 62.57721 -120.885305)
			(xy 62.57721 -120.813983) (xy 62.585196 -120.743109) (xy 62.601066 -120.673574) (xy 62.624623 -120.606254)
			(xy 62.655568 -120.541995) (xy 62.693514 -120.481604) (xy 62.737983 -120.425842) (xy 62.788416 -120.375409)
			(xy 62.844178 -120.33094) (xy 62.904569 -120.292994) (xy 62.968828 -120.262049) (xy 63.036148 -120.238492)
			(xy 63.105683 -120.222622) (xy 63.176557 -120.214636) (xy 63.247879 -120.214636) (xy 63.318753 -120.222622)
			(xy 63.388288 -120.238492) (xy 63.455608 -120.262049) (xy 63.519867 -120.292994) (xy 63.580258 -120.33094)
			(xy 63.599555 -120.346329) (xy 67.014629 -120.346329) (xy 67.014629 -120.283071) (xy 67.022886 -120.220353)
			(xy 67.039258 -120.15925) (xy 67.063466 -120.100807) (xy 67.095095 -120.046023) (xy 67.133605 -119.995837)
			(xy 67.178335 -119.951106) (xy 67.228522 -119.912597) (xy 67.283305 -119.880967) (xy 67.341748 -119.856759)
			(xy 67.402851 -119.840386) (xy 67.465569 -119.832129) (xy 67.497198 -119.831612) (xy 68.273422 -119.831612)
			(xy 68.304113 -119.830548) (xy 68.365342 -119.83527) (xy 68.42548 -119.847708) (xy 68.483558 -119.867663)
			(xy 68.538642 -119.894812) (xy 68.564506 -119.911368) (xy 68.596256 -119.932704) (xy 68.65366 -119.932704)
			(xy 68.65366 -119.987568) (xy 68.673477 -120.009928) (xy 68.708112 -120.058612) (xy 68.736478 -120.111196)
			(xy 68.758141 -120.166877) (xy 68.772771 -120.224805) (xy 68.780144 -120.284096) (xy 68.780148 -120.343843)
			(xy 68.772782 -120.403134) (xy 68.75816 -120.461064) (xy 68.736504 -120.516748) (xy 68.708145 -120.569336)
			(xy 68.673516 -120.618024) (xy 68.65366 -120.640348) (xy 68.65366 -120.695212) (xy 68.651882 -120.695212)
			(xy 68.635197 -120.695686) (xy 68.602974 -120.70436) (xy 68.574097 -120.721084) (xy 68.561966 -120.73255)
			(xy 68.496942 -120.797828) (xy 67.497198 -120.797828) (xy 67.465569 -120.797271) (xy 67.402851 -120.789014)
			(xy 67.341748 -120.772641) (xy 67.283305 -120.748433) (xy 67.228522 -120.716803) (xy 67.178335 -120.678294)
			(xy 67.133605 -120.633563) (xy 67.095095 -120.583377) (xy 67.063466 -120.528593) (xy 67.039258 -120.47015)
			(xy 67.022886 -120.409047) (xy 67.014629 -120.346329) (xy 63.599555 -120.346329) (xy 63.63602 -120.375409)
			(xy 63.686453 -120.425842) (xy 63.730922 -120.481604) (xy 63.768868 -120.541995) (xy 63.799813 -120.606254)
			(xy 63.82337 -120.673574) (xy 63.83924 -120.743109) (xy 63.847226 -120.813983) (xy 63.847726 -120.849644)
			(xy 63.847226 -120.885305) (xy 63.83924 -120.956179) (xy 63.82337 -121.025714) (xy 63.799813 -121.093034)
			(xy 63.768868 -121.157293) (xy 63.74209 -121.19991) (xy 69.997584 -121.19991) (xy 70.001572 -120.94729)
			(xy 70.013533 -120.694922) (xy 70.033455 -120.443058) (xy 70.061319 -120.191948) (xy 70.097095 -119.941842)
			(xy 70.140749 -119.692991) (xy 70.192238 -119.445642) (xy 70.251509 -119.200041) (xy 70.318504 -118.956434)
			(xy 70.393155 -118.715064) (xy 70.47539 -118.47617) (xy 70.565124 -118.239992) (xy 70.66227 -118.006764)
			(xy 70.76673 -117.776718) (xy 70.878401 -117.550086) (xy 70.99717 -117.327091) (xy 71.122919 -117.107957)
			(xy 71.255524 -116.892902) (xy 71.394851 -116.68214) (xy 71.540763 -116.475882) (xy 71.693113 -116.274333)
			(xy 71.851749 -116.077693) (xy 72.016514 -115.88616) (xy 72.187244 -115.699923) (xy 72.363768 -115.519169)
			(xy 72.54591 -115.344078) (xy 72.733488 -115.174824) (xy 72.926316 -115.011575) (xy 73.124201 -114.854496)
			(xy 73.326947 -114.703741) (xy 73.534351 -114.559463) (xy 73.746206 -114.421803) (xy 73.962301 -114.2909)
			(xy 74.182421 -114.166884) (xy 74.406346 -114.049879) (xy 74.633853 -113.940001) (xy 74.864715 -113.83736)
			(xy 75.098703 -113.742058) (xy 75.335582 -113.654191) (xy 75.575118 -113.573844) (xy 75.81707 -113.5011)
			(xy 76.061198 -113.43603) (xy 76.307259 -113.3787) (xy 76.555007 -113.329166) (xy 76.804195 -113.287477)
			(xy 77.054575 -113.253676) (xy 77.305897 -113.227795) (xy 77.557911 -113.209862) (xy 77.810365 -113.199893)
			(xy 78.063009 -113.197899) (xy 78.315589 -113.203881) (xy 78.567855 -113.217834) (xy 78.819554 -113.239744)
			(xy 79.070437 -113.269588) (xy 79.320252 -113.307338) (xy 79.568751 -113.352955) (xy 79.815686 -113.406394)
			(xy 80.060811 -113.467602) (xy 80.303881 -113.536517) (xy 80.544655 -113.613072) (xy 80.782892 -113.697189)
			(xy 81.018355 -113.788786) (xy 81.250809 -113.88777) (xy 81.480023 -113.994042) (xy 81.705767 -114.107498)
			(xy 81.927817 -114.228023) (xy 82.145951 -114.355499) (xy 82.359953 -114.489797) (xy 82.569609 -114.630783)
			(xy 82.774709 -114.778318) (xy 82.975049 -114.932254) (xy 83.17043 -115.092438) (xy 83.360657 -115.25871)
			(xy 83.54554 -115.430905) (xy 83.724896 -115.608849) (xy 83.898544 -115.792368) (xy 84.066312 -115.981276)
			(xy 84.228033 -116.175387) (xy 84.383546 -116.374506) (xy 84.532695 -116.578435) (xy 84.675332 -116.786971)
			(xy 84.811315 -116.999906) (xy 84.940508 -117.217028) (xy 85.062783 -117.43812) (xy 85.178017 -117.662961)
			(xy 85.286096 -117.891329) (xy 85.386911 -118.122994) (xy 85.480363 -118.357727) (xy 85.566358 -118.595292)
			(xy 85.644811 -118.835454) (xy 85.715643 -119.077973) (xy 85.778784 -119.322608) (xy 85.834171 -119.569113)
			(xy 85.881748 -119.817244) (xy 85.921468 -120.066754) (xy 85.953292 -120.317393) (xy 85.977188 -120.568911)
			(xy 85.993132 -120.821059) (xy 86.001107 -121.073584) (xy 86.001606 -121.19991) (xy 86.001107 -121.326236)
			(xy 85.993132 -121.578761) (xy 85.977188 -121.830909) (xy 85.953292 -122.082427) (xy 85.921468 -122.333066)
			(xy 85.881748 -122.582576) (xy 85.834171 -122.830707) (xy 85.778784 -123.077212) (xy 85.715643 -123.321847)
			(xy 85.644811 -123.564366) (xy 85.566358 -123.804528) (xy 85.480363 -124.042093) (xy 85.386911 -124.276826)
			(xy 85.286096 -124.508491) (xy 85.178017 -124.736859) (xy 85.062783 -124.9617) (xy 84.940508 -125.182792)
			(xy 84.811315 -125.399914) (xy 84.675332 -125.612849) (xy 84.532695 -125.821385) (xy 84.383546 -126.025314)
			(xy 84.228033 -126.224433) (xy 84.066312 -126.418544) (xy 83.898544 -126.607452) (xy 83.724896 -126.790971)
			(xy 83.54554 -126.968915) (xy 83.360657 -127.14111) (xy 83.17043 -127.307382) (xy 82.975049 -127.467566)
			(xy 82.774709 -127.621502) (xy 82.569609 -127.769037) (xy 82.359953 -127.910023) (xy 82.145951 -128.044321)
			(xy 81.927817 -128.171797) (xy 81.705767 -128.292322) (xy 81.480023 -128.405778) (xy 81.250809 -128.51205)
			(xy 81.018355 -128.611034) (xy 80.782892 -128.702631) (xy 80.544655 -128.786748) (xy 80.303881 -128.863303)
			(xy 80.060811 -128.932218) (xy 79.815686 -128.993426) (xy 79.568751 -129.046865) (xy 79.320252 -129.092482)
			(xy 79.070437 -129.130232) (xy 78.819554 -129.160076) (xy 78.567855 -129.181986) (xy 78.315589 -129.195939)
			(xy 78.063009 -129.201921) (xy 77.810365 -129.199927) (xy 77.557911 -129.189958) (xy 77.305897 -129.172025)
			(xy 77.054575 -129.146144) (xy 76.804195 -129.112343) (xy 76.555007 -129.070654) (xy 76.307259 -129.02112)
			(xy 76.061198 -128.96379) (xy 75.81707 -128.89872) (xy 75.575118 -128.825976) (xy 75.335582 -128.745629)
			(xy 75.098703 -128.657762) (xy 74.864715 -128.56246) (xy 74.633853 -128.459819) (xy 74.406346 -128.349941)
			(xy 74.182421 -128.232936) (xy 73.962301 -128.10892) (xy 73.746206 -127.978017) (xy 73.534351 -127.840357)
			(xy 73.326947 -127.696079) (xy 73.124201 -127.545324) (xy 72.926316 -127.388245) (xy 72.733488 -127.224996)
			(xy 72.54591 -127.055742) (xy 72.363768 -126.880651) (xy 72.187244 -126.699897) (xy 72.016514 -126.51366)
			(xy 71.851749 -126.322127) (xy 71.693113 -126.125487) (xy 71.540763 -125.923938) (xy 71.394851 -125.71768)
			(xy 71.255524 -125.506918) (xy 71.122919 -125.291863) (xy 70.99717 -125.072729) (xy 70.878401 -124.849734)
			(xy 70.76673 -124.623102) (xy 70.66227 -124.393056) (xy 70.565124 -124.159828) (xy 70.47539 -123.92365)
			(xy 70.393155 -123.684756) (xy 70.318504 -123.443386) (xy 70.251509 -123.199779) (xy 70.192238 -122.954178)
			(xy 70.140749 -122.706829) (xy 70.097095 -122.457978) (xy 70.061319 -122.207872) (xy 70.033455 -121.956762)
			(xy 70.013533 -121.704898) (xy 70.001572 -121.45253) (xy 69.997584 -121.19991) (xy 63.74209 -121.19991)
			(xy 63.730922 -121.217684) (xy 63.686453 -121.273446) (xy 63.63602 -121.323879) (xy 63.580258 -121.368348)
			(xy 63.519867 -121.406294) (xy 63.455608 -121.437239) (xy 63.388288 -121.460796) (xy 63.318753 -121.476666)
			(xy 63.247879 -121.484652) (xy 63.176557 -121.484652) (xy 63.105683 -121.476666) (xy 63.036148 -121.460796)
			(xy 62.968828 -121.437239) (xy 62.904569 -121.406294) (xy 62.844178 -121.368348) (xy 62.788416 -121.323879)
			(xy 62.737983 -121.273446) (xy 62.693514 -121.217684) (xy 62.655568 -121.157293) (xy 62.624623 -121.093034)
			(xy 62.601066 -121.025714) (xy 62.585196 -120.956179) (xy 62.57721 -120.885305) (xy 61.943242 -120.885305)
			(xy 61.935256 -120.956179) (xy 61.919386 -121.025714) (xy 61.895829 -121.093034) (xy 61.864884 -121.157293)
			(xy 61.826938 -121.217684) (xy 61.782469 -121.273446) (xy 61.732036 -121.323879) (xy 61.676274 -121.368348)
			(xy 61.615883 -121.406294) (xy 61.551624 -121.437239) (xy 61.484304 -121.460796) (xy 61.414769 -121.476666)
			(xy 61.343895 -121.484652) (xy 61.272573 -121.484652) (xy 61.201699 -121.476666) (xy 61.132164 -121.460796)
			(xy 61.064844 -121.437239) (xy 61.000585 -121.406294) (xy 60.940194 -121.368348) (xy 60.884432 -121.323879)
			(xy 60.833999 -121.273446) (xy 60.78953 -121.217684) (xy 60.751584 -121.157293) (xy 60.720639 -121.093034)
			(xy 60.697082 -121.025714) (xy 60.681212 -120.956179) (xy 60.673226 -120.885305) (xy 59.7022 -120.885305)
			(xy 59.694214 -120.956179) (xy 59.678344 -121.025714) (xy 59.654787 -121.093034) (xy 59.623842 -121.157293)
			(xy 59.585896 -121.217684) (xy 59.541427 -121.273446) (xy 59.490994 -121.323879) (xy 59.435232 -121.368348)
			(xy 59.374841 -121.406294) (xy 59.310582 -121.437239) (xy 59.243262 -121.460796) (xy 59.173727 -121.476666)
			(xy 59.102853 -121.484652) (xy 59.031531 -121.484652) (xy 58.960657 -121.476666) (xy 58.891122 -121.460796)
			(xy 58.823802 -121.437239) (xy 58.759543 -121.406294) (xy 58.699152 -121.368348) (xy 58.64339 -121.323879)
			(xy 58.592957 -121.273446) (xy 58.548488 -121.217684) (xy 58.510542 -121.157293) (xy 58.479597 -121.093034)
			(xy 58.45604 -121.025714) (xy 58.44017 -120.956179) (xy 58.432184 -120.885305) (xy 40.356116 -120.885305)
			(xy 40.360242 -120.903383) (xy 40.368228 -120.974257) (xy 40.368728 -121.009918) (xy 40.368228 -121.045579)
			(xy 40.360242 -121.116453) (xy 40.344372 -121.185988) (xy 40.320815 -121.253308) (xy 40.28987 -121.317567)
			(xy 40.251924 -121.377958) (xy 40.207455 -121.43372) (xy 40.157022 -121.484153) (xy 40.10126 -121.528622)
			(xy 40.040869 -121.566568) (xy 39.97661 -121.597513) (xy 39.90929 -121.62107) (xy 39.839755 -121.63694)
			(xy 39.768881 -121.644926) (xy 39.697559 -121.644926) (xy 39.626685 -121.63694) (xy 39.55715 -121.62107)
			(xy 39.48983 -121.597513) (xy 39.425571 -121.566568) (xy 39.36518 -121.528622) (xy 39.309418 -121.484153)
			(xy 39.258985 -121.43372) (xy 39.214516 -121.377958) (xy 39.17657 -121.317567) (xy 39.145625 -121.253308)
			(xy 39.122068 -121.185988) (xy 39.106198 -121.116453) (xy 39.098212 -121.045579) (xy 36.472794 -121.045579)
			(xy 36.471468 -121.059887) (xy 36.4555 -121.145307) (xy 36.431719 -121.228889) (xy 36.400327 -121.309921)
			(xy 36.361593 -121.38771) (xy 36.315846 -121.461594) (xy 36.263477 -121.530941) (xy 36.204933 -121.595161)
			(xy 36.140713 -121.653705) (xy 36.071366 -121.706074) (xy 35.997482 -121.751821) (xy 35.919693 -121.790555)
			(xy 35.838661 -121.821947) (xy 35.755079 -121.845728) (xy 35.669659 -121.861696) (xy 35.58313 -121.869714)
			(xy 35.49623 -121.869714) (xy 35.409701 -121.861696) (xy 35.324281 -121.845728) (xy 35.240699 -121.821947)
			(xy 35.159667 -121.790555) (xy 35.081878 -121.751821) (xy 35.007994 -121.706074) (xy 34.938647 -121.653705)
			(xy 34.874427 -121.595161) (xy 34.815883 -121.530941) (xy 34.763514 -121.461594) (xy 34.717767 -121.38771)
			(xy 34.679033 -121.309921) (xy 34.647641 -121.228889) (xy 34.62386 -121.145307) (xy 34.607892 -121.059887)
			(xy 34.599874 -120.973358) (xy 31.399486 -120.973358) (xy 31.391468 -121.059887) (xy 31.3755 -121.145307)
			(xy 31.351719 -121.228889) (xy 31.320327 -121.309921) (xy 31.281593 -121.38771) (xy 31.235846 -121.461594)
			(xy 31.183477 -121.530941) (xy 31.124933 -121.595161) (xy 31.060713 -121.653705) (xy 30.991366 -121.706074)
			(xy 30.917482 -121.751821) (xy 30.839693 -121.790555) (xy 30.758661 -121.821947) (xy 30.675079 -121.845728)
			(xy 30.589659 -121.861696) (xy 30.50313 -121.869714) (xy 30.41623 -121.869714) (xy 30.329701 -121.861696)
			(xy 30.244281 -121.845728) (xy 30.160699 -121.821947) (xy 30.079667 -121.790555) (xy 30.001878 -121.751821)
			(xy 29.927994 -121.706074) (xy 29.858647 -121.653705) (xy 29.794427 -121.595161) (xy 29.735883 -121.530941)
			(xy 29.683514 -121.461594) (xy 29.637767 -121.38771) (xy 29.599033 -121.309921) (xy 29.567641 -121.228889)
			(xy 29.54386 -121.145307) (xy 29.527892 -121.059887) (xy 29.519874 -120.973358) (xy 27.89936 -120.973358)
			(xy 27.89936 -123.513358) (xy 29.519874 -123.513358) (xy 29.519874 -123.426458) (xy 29.527892 -123.339929)
			(xy 29.54386 -123.254509) (xy 29.567641 -123.170927) (xy 29.599033 -123.089895) (xy 29.637767 -123.012106)
			(xy 29.683514 -122.938222) (xy 29.735883 -122.868875) (xy 29.794427 -122.804655) (xy 29.858647 -122.746111)
			(xy 29.927994 -122.693742) (xy 30.001878 -122.647995) (xy 30.079667 -122.609261) (xy 30.160699 -122.577869)
			(xy 30.244281 -122.554088) (xy 30.329701 -122.53812) (xy 30.41623 -122.530102) (xy 30.50313 -122.530102)
			(xy 30.589659 -122.53812) (xy 30.675079 -122.554088) (xy 30.758661 -122.577869) (xy 30.839693 -122.609261)
			(xy 30.917482 -122.647995) (xy 30.991366 -122.693742) (xy 31.060713 -122.746111) (xy 31.124933 -122.804655)
			(xy 31.183477 -122.868875) (xy 31.235846 -122.938222) (xy 31.281593 -123.012106) (xy 31.320327 -123.089895)
			(xy 31.351719 -123.170927) (xy 31.3755 -123.254509) (xy 31.391468 -123.339929) (xy 31.399486 -123.426458)
			(xy 31.399988 -123.469908) (xy 31.399486 -123.513358) (xy 34.599874 -123.513358) (xy 34.599874 -123.426458)
			(xy 34.607892 -123.339929) (xy 34.62386 -123.254509) (xy 34.647641 -123.170927) (xy 34.679033 -123.089895)
			(xy 34.717767 -123.012106) (xy 34.763514 -122.938222) (xy 34.815883 -122.868875) (xy 34.874427 -122.804655)
			(xy 34.938647 -122.746111) (xy 35.007994 -122.693742) (xy 35.081878 -122.647995) (xy 35.159667 -122.609261)
			(xy 35.240699 -122.577869) (xy 35.324281 -122.554088) (xy 35.409701 -122.53812) (xy 35.49623 -122.530102)
			(xy 35.58313 -122.530102) (xy 35.669659 -122.53812) (xy 35.755079 -122.554088) (xy 35.838661 -122.577869)
			(xy 35.919693 -122.609261) (xy 35.997482 -122.647995) (xy 36.071366 -122.693742) (xy 36.107076 -122.720709)
			(xy 39.098212 -122.720709) (xy 39.098212 -122.649387) (xy 39.106198 -122.578513) (xy 39.122068 -122.508978)
			(xy 39.145625 -122.441658) (xy 39.17657 -122.377399) (xy 39.214516 -122.317008) (xy 39.258985 -122.261246)
			(xy 39.309418 -122.210813) (xy 39.36518 -122.166344) (xy 39.425571 -122.128398) (xy 39.48983 -122.097453)
			(xy 39.55715 -122.073896) (xy 39.626685 -122.058026) (xy 39.697559 -122.05004) (xy 39.768881 -122.05004)
			(xy 39.839755 -122.058026) (xy 39.90929 -122.073896) (xy 39.97661 -122.097453) (xy 40.040869 -122.128398)
			(xy 40.10126 -122.166344) (xy 40.157022 -122.210813) (xy 40.207455 -122.261246) (xy 40.251924 -122.317008)
			(xy 40.28987 -122.377399) (xy 40.320815 -122.441658) (xy 40.344372 -122.508978) (xy 40.356116 -122.560435)
			(xy 58.432184 -122.560435) (xy 58.432184 -122.489113) (xy 58.44017 -122.418239) (xy 58.45604 -122.348704)
			(xy 58.479597 -122.281384) (xy 58.510542 -122.217125) (xy 58.548488 -122.156734) (xy 58.592957 -122.100972)
			(xy 58.64339 -122.050539) (xy 58.699152 -122.00607) (xy 58.759543 -121.968124) (xy 58.823802 -121.937179)
			(xy 58.891122 -121.913622) (xy 58.960657 -121.897752) (xy 59.031531 -121.889766) (xy 59.102853 -121.889766)
			(xy 59.173727 -121.897752) (xy 59.243262 -121.913622) (xy 59.310582 -121.937179) (xy 59.374841 -121.968124)
			(xy 59.435232 -122.00607) (xy 59.490994 -122.050539) (xy 59.541427 -122.100972) (xy 59.585896 -122.156734)
			(xy 59.623842 -122.217125) (xy 59.654787 -122.281384) (xy 59.678344 -122.348704) (xy 59.694214 -122.418239)
			(xy 59.7022 -122.489113) (xy 59.7027 -122.524774) (xy 59.7022 -122.560435) (xy 60.673226 -122.560435)
			(xy 60.673226 -122.489113) (xy 60.681212 -122.418239) (xy 60.697082 -122.348704) (xy 60.720639 -122.281384)
			(xy 60.751584 -122.217125) (xy 60.78953 -122.156734) (xy 60.833999 -122.100972) (xy 60.884432 -122.050539)
			(xy 60.940194 -122.00607) (xy 61.000585 -121.968124) (xy 61.064844 -121.937179) (xy 61.132164 -121.913622)
			(xy 61.201699 -121.897752) (xy 61.272573 -121.889766) (xy 61.343895 -121.889766) (xy 61.414769 -121.897752)
			(xy 61.484304 -121.913622) (xy 61.551624 -121.937179) (xy 61.615883 -121.968124) (xy 61.676274 -122.00607)
			(xy 61.732036 -122.050539) (xy 61.782469 -122.100972) (xy 61.826938 -122.156734) (xy 61.864884 -122.217125)
			(xy 61.895829 -122.281384) (xy 61.919386 -122.348704) (xy 61.935256 -122.418239) (xy 61.943242 -122.489113)
			(xy 61.943742 -122.524774) (xy 61.943242 -122.560435) (xy 62.57721 -122.560435) (xy 62.57721 -122.489113)
			(xy 62.585196 -122.418239) (xy 62.601066 -122.348704) (xy 62.624623 -122.281384) (xy 62.655568 -122.217125)
			(xy 62.693514 -122.156734) (xy 62.737983 -122.100972) (xy 62.788416 -122.050539) (xy 62.844178 -122.00607)
			(xy 62.904569 -121.968124) (xy 62.968828 -121.937179) (xy 63.036148 -121.913622) (xy 63.105683 -121.897752)
			(xy 63.176557 -121.889766) (xy 63.247879 -121.889766) (xy 63.318753 -121.897752) (xy 63.388288 -121.913622)
			(xy 63.455608 -121.937179) (xy 63.519867 -121.968124) (xy 63.580258 -122.00607) (xy 63.63602 -122.050539)
			(xy 63.686453 -122.100972) (xy 63.730922 -122.156734) (xy 63.768868 -122.217125) (xy 63.799813 -122.281384)
			(xy 63.82337 -122.348704) (xy 63.83924 -122.418239) (xy 63.847226 -122.489113) (xy 63.847726 -122.524774)
			(xy 63.847226 -122.560435) (xy 63.83924 -122.631309) (xy 63.82337 -122.700844) (xy 63.799813 -122.768164)
			(xy 63.768868 -122.832423) (xy 63.730922 -122.892814) (xy 63.686453 -122.948576) (xy 63.63602 -122.999009)
			(xy 63.580258 -123.043478) (xy 63.519867 -123.081424) (xy 63.455608 -123.112369) (xy 63.388288 -123.135926)
			(xy 63.318753 -123.151796) (xy 63.247879 -123.159782) (xy 63.176557 -123.159782) (xy 63.105683 -123.151796)
			(xy 63.036148 -123.135926) (xy 62.968828 -123.112369) (xy 62.904569 -123.081424) (xy 62.844178 -123.043478)
			(xy 62.788416 -122.999009) (xy 62.737983 -122.948576) (xy 62.693514 -122.892814) (xy 62.655568 -122.832423)
			(xy 62.624623 -122.768164) (xy 62.601066 -122.700844) (xy 62.585196 -122.631309) (xy 62.57721 -122.560435)
			(xy 61.943242 -122.560435) (xy 61.935256 -122.631309) (xy 61.919386 -122.700844) (xy 61.895829 -122.768164)
			(xy 61.864884 -122.832423) (xy 61.826938 -122.892814) (xy 61.782469 -122.948576) (xy 61.732036 -122.999009)
			(xy 61.676274 -123.043478) (xy 61.615883 -123.081424) (xy 61.551624 -123.112369) (xy 61.484304 -123.135926)
			(xy 61.414769 -123.151796) (xy 61.343895 -123.159782) (xy 61.272573 -123.159782) (xy 61.201699 -123.151796)
			(xy 61.132164 -123.135926) (xy 61.064844 -123.112369) (xy 61.000585 -123.081424) (xy 60.940194 -123.043478)
			(xy 60.884432 -122.999009) (xy 60.833999 -122.948576) (xy 60.78953 -122.892814) (xy 60.751584 -122.832423)
			(xy 60.720639 -122.768164) (xy 60.697082 -122.700844) (xy 60.681212 -122.631309) (xy 60.673226 -122.560435)
			(xy 59.7022 -122.560435) (xy 59.694214 -122.631309) (xy 59.678344 -122.700844) (xy 59.654787 -122.768164)
			(xy 59.623842 -122.832423) (xy 59.585896 -122.892814) (xy 59.541427 -122.948576) (xy 59.490994 -122.999009)
			(xy 59.435232 -123.043478) (xy 59.374841 -123.081424) (xy 59.310582 -123.112369) (xy 59.243262 -123.135926)
			(xy 59.173727 -123.151796) (xy 59.102853 -123.159782) (xy 59.031531 -123.159782) (xy 58.960657 -123.151796)
			(xy 58.891122 -123.135926) (xy 58.823802 -123.112369) (xy 58.759543 -123.081424) (xy 58.699152 -123.043478)
			(xy 58.64339 -122.999009) (xy 58.592957 -122.948576) (xy 58.548488 -122.892814) (xy 58.510542 -122.832423)
			(xy 58.479597 -122.768164) (xy 58.45604 -122.700844) (xy 58.44017 -122.631309) (xy 58.432184 -122.560435)
			(xy 40.356116 -122.560435) (xy 40.360242 -122.578513) (xy 40.368228 -122.649387) (xy 40.368728 -122.685048)
			(xy 40.368228 -122.720709) (xy 40.360242 -122.791583) (xy 40.344372 -122.861118) (xy 40.320815 -122.928438)
			(xy 40.28987 -122.992697) (xy 40.251924 -123.053088) (xy 40.207455 -123.10885) (xy 40.157022 -123.159283)
			(xy 40.10126 -123.203752) (xy 40.040869 -123.241698) (xy 39.97661 -123.272643) (xy 39.90929 -123.2962)
			(xy 39.839755 -123.31207) (xy 39.768881 -123.320056) (xy 39.697559 -123.320056) (xy 39.626685 -123.31207)
			(xy 39.55715 -123.2962) (xy 39.48983 -123.272643) (xy 39.425571 -123.241698) (xy 39.36518 -123.203752)
			(xy 39.309418 -123.159283) (xy 39.258985 -123.10885) (xy 39.214516 -123.053088) (xy 39.17657 -122.992697)
			(xy 39.145625 -122.928438) (xy 39.122068 -122.861118) (xy 39.106198 -122.791583) (xy 39.098212 -122.720709)
			(xy 36.107076 -122.720709) (xy 36.140713 -122.746111) (xy 36.204933 -122.804655) (xy 36.263477 -122.868875)
			(xy 36.315846 -122.938222) (xy 36.361593 -123.012106) (xy 36.400327 -123.089895) (xy 36.431719 -123.170927)
			(xy 36.4555 -123.254509) (xy 36.471468 -123.339929) (xy 36.479486 -123.426458) (xy 36.479988 -123.469908)
			(xy 36.479486 -123.513358) (xy 36.471468 -123.599887) (xy 36.4555 -123.685307) (xy 36.431719 -123.768889)
			(xy 36.400327 -123.849921) (xy 36.361593 -123.92771) (xy 36.315846 -124.001594) (xy 36.263477 -124.070941)
			(xy 36.204933 -124.135161) (xy 36.140713 -124.193705) (xy 36.071366 -124.246074) (xy 35.997482 -124.291821)
			(xy 35.919693 -124.330555) (xy 35.838661 -124.361947) (xy 35.755079 -124.385728) (xy 35.669659 -124.401696)
			(xy 35.58313 -124.409714) (xy 35.49623 -124.409714) (xy 35.409701 -124.401696) (xy 35.324281 -124.385728)
			(xy 35.240699 -124.361947) (xy 35.159667 -124.330555) (xy 35.081878 -124.291821) (xy 35.007994 -124.246074)
			(xy 34.938647 -124.193705) (xy 34.874427 -124.135161) (xy 34.815883 -124.070941) (xy 34.763514 -124.001594)
			(xy 34.717767 -123.92771) (xy 34.679033 -123.849921) (xy 34.647641 -123.768889) (xy 34.62386 -123.685307)
			(xy 34.607892 -123.599887) (xy 34.599874 -123.513358) (xy 31.399486 -123.513358) (xy 31.391468 -123.599887)
			(xy 31.3755 -123.685307) (xy 31.351719 -123.768889) (xy 31.320327 -123.849921) (xy 31.281593 -123.92771)
			(xy 31.235846 -124.001594) (xy 31.183477 -124.070941) (xy 31.124933 -124.135161) (xy 31.060713 -124.193705)
			(xy 30.991366 -124.246074) (xy 30.917482 -124.291821) (xy 30.839693 -124.330555) (xy 30.758661 -124.361947)
			(xy 30.675079 -124.385728) (xy 30.589659 -124.401696) (xy 30.50313 -124.409714) (xy 30.41623 -124.409714)
			(xy 30.329701 -124.401696) (xy 30.244281 -124.385728) (xy 30.160699 -124.361947) (xy 30.079667 -124.330555)
			(xy 30.001878 -124.291821) (xy 29.927994 -124.246074) (xy 29.858647 -124.193705) (xy 29.794427 -124.135161)
			(xy 29.735883 -124.070941) (xy 29.683514 -124.001594) (xy 29.637767 -123.92771) (xy 29.599033 -123.849921)
			(xy 29.567641 -123.768889) (xy 29.54386 -123.685307) (xy 29.527892 -123.599887) (xy 29.519874 -123.513358)
			(xy 27.89936 -123.513358) (xy 27.89936 -124.731881) (xy 39.054778 -124.731881) (xy 39.054778 -124.660559)
			(xy 39.062764 -124.589685) (xy 39.078634 -124.52015) (xy 39.102191 -124.45283) (xy 39.133136 -124.388571)
			(xy 39.171082 -124.32818) (xy 39.215551 -124.272418) (xy 39.265984 -124.221985) (xy 39.321746 -124.177516)
			(xy 39.382137 -124.13957) (xy 39.446396 -124.108625) (xy 39.513716 -124.085068) (xy 39.583251 -124.069198)
			(xy 39.654125 -124.061212) (xy 39.725447 -124.061212) (xy 39.796321 -124.069198) (xy 39.865856 -124.085068)
			(xy 39.933176 -124.108625) (xy 39.997435 -124.13957) (xy 40.057826 -124.177516) (xy 40.113588 -124.221985)
			(xy 40.164021 -124.272418) (xy 40.20849 -124.32818) (xy 40.246436 -124.388571) (xy 40.277381 -124.45283)
			(xy 40.300938 -124.52015) (xy 40.312682 -124.571607) (xy 58.38875 -124.571607) (xy 58.38875 -124.500285)
			(xy 58.396736 -124.429411) (xy 58.412606 -124.359876) (xy 58.436163 -124.292556) (xy 58.467108 -124.228297)
			(xy 58.505054 -124.167906) (xy 58.549523 -124.112144) (xy 58.599956 -124.061711) (xy 58.655718 -124.017242)
			(xy 58.716109 -123.979296) (xy 58.780368 -123.948351) (xy 58.847688 -123.924794) (xy 58.917223 -123.908924)
			(xy 58.988097 -123.900938) (xy 59.059419 -123.900938) (xy 59.130293 -123.908924) (xy 59.199828 -123.924794)
			(xy 59.267148 -123.948351) (xy 59.331407 -123.979296) (xy 59.391798 -124.017242) (xy 59.44756 -124.061711)
			(xy 59.497993 -124.112144) (xy 59.542462 -124.167906) (xy 59.580408 -124.228297) (xy 59.611353 -124.292556)
			(xy 59.63491 -124.359876) (xy 59.65078 -124.429411) (xy 59.658766 -124.500285) (xy 59.659266 -124.535946)
			(xy 59.658766 -124.571607) (xy 60.629792 -124.571607) (xy 60.629792 -124.500285) (xy 60.637778 -124.429411)
			(xy 60.653648 -124.359876) (xy 60.677205 -124.292556) (xy 60.70815 -124.228297) (xy 60.746096 -124.167906)
			(xy 60.790565 -124.112144) (xy 60.840998 -124.061711) (xy 60.89676 -124.017242) (xy 60.957151 -123.979296)
			(xy 61.02141 -123.948351) (xy 61.08873 -123.924794) (xy 61.158265 -123.908924) (xy 61.229139 -123.900938)
			(xy 61.300461 -123.900938) (xy 61.371335 -123.908924) (xy 61.44087 -123.924794) (xy 61.50819 -123.948351)
			(xy 61.572449 -123.979296) (xy 61.63284 -124.017242) (xy 61.688602 -124.061711) (xy 61.739035 -124.112144)
			(xy 61.783504 -124.167906) (xy 61.82145 -124.228297) (xy 61.852395 -124.292556) (xy 61.875952 -124.359876)
			(xy 61.891822 -124.429411) (xy 61.899808 -124.500285) (xy 61.900308 -124.535946) (xy 61.899808 -124.571607)
			(xy 62.533776 -124.571607) (xy 62.533776 -124.500285) (xy 62.541762 -124.429411) (xy 62.557632 -124.359876)
			(xy 62.581189 -124.292556) (xy 62.612134 -124.228297) (xy 62.65008 -124.167906) (xy 62.694549 -124.112144)
			(xy 62.744982 -124.061711) (xy 62.800744 -124.017242) (xy 62.861135 -123.979296) (xy 62.925394 -123.948351)
			(xy 62.992714 -123.924794) (xy 63.062249 -123.908924) (xy 63.133123 -123.900938) (xy 63.204445 -123.900938)
			(xy 63.275319 -123.908924) (xy 63.344854 -123.924794) (xy 63.412174 -123.948351) (xy 63.476433 -123.979296)
			(xy 63.536824 -124.017242) (xy 63.592586 -124.061711) (xy 63.643019 -124.112144) (xy 63.687488 -124.167906)
			(xy 63.725434 -124.228297) (xy 63.756379 -124.292556) (xy 63.779936 -124.359876) (xy 63.795806 -124.429411)
			(xy 63.803792 -124.500285) (xy 63.804292 -124.535946) (xy 63.803792 -124.571607) (xy 63.795806 -124.642481)
			(xy 63.779936 -124.712016) (xy 63.756379 -124.779336) (xy 63.725434 -124.843595) (xy 63.687488 -124.903986)
			(xy 63.643019 -124.959748) (xy 63.592586 -125.010181) (xy 63.536824 -125.05465) (xy 63.476433 -125.092596)
			(xy 63.412174 -125.123541) (xy 63.344854 -125.147098) (xy 63.275319 -125.162968) (xy 63.204445 -125.170954)
			(xy 63.133123 -125.170954) (xy 63.062249 -125.162968) (xy 62.992714 -125.147098) (xy 62.925394 -125.123541)
			(xy 62.861135 -125.092596) (xy 62.800744 -125.05465) (xy 62.744982 -125.010181) (xy 62.694549 -124.959748)
			(xy 62.65008 -124.903986) (xy 62.612134 -124.843595) (xy 62.581189 -124.779336) (xy 62.557632 -124.712016)
			(xy 62.541762 -124.642481) (xy 62.533776 -124.571607) (xy 61.899808 -124.571607) (xy 61.891822 -124.642481)
			(xy 61.875952 -124.712016) (xy 61.852395 -124.779336) (xy 61.82145 -124.843595) (xy 61.783504 -124.903986)
			(xy 61.739035 -124.959748) (xy 61.688602 -125.010181) (xy 61.63284 -125.05465) (xy 61.572449 -125.092596)
			(xy 61.50819 -125.123541) (xy 61.44087 -125.147098) (xy 61.371335 -125.162968) (xy 61.300461 -125.170954)
			(xy 61.229139 -125.170954) (xy 61.158265 -125.162968) (xy 61.08873 -125.147098) (xy 61.02141 -125.123541)
			(xy 60.957151 -125.092596) (xy 60.89676 -125.05465) (xy 60.840998 -125.010181) (xy 60.790565 -124.959748)
			(xy 60.746096 -124.903986) (xy 60.70815 -124.843595) (xy 60.677205 -124.779336) (xy 60.653648 -124.712016)
			(xy 60.637778 -124.642481) (xy 60.629792 -124.571607) (xy 59.658766 -124.571607) (xy 59.65078 -124.642481)
			(xy 59.63491 -124.712016) (xy 59.611353 -124.779336) (xy 59.580408 -124.843595) (xy 59.542462 -124.903986)
			(xy 59.497993 -124.959748) (xy 59.44756 -125.010181) (xy 59.391798 -125.05465) (xy 59.331407 -125.092596)
			(xy 59.267148 -125.123541) (xy 59.199828 -125.147098) (xy 59.130293 -125.162968) (xy 59.059419 -125.170954)
			(xy 58.988097 -125.170954) (xy 58.917223 -125.162968) (xy 58.847688 -125.147098) (xy 58.780368 -125.123541)
			(xy 58.716109 -125.092596) (xy 58.655718 -125.05465) (xy 58.599956 -125.010181) (xy 58.549523 -124.959748)
			(xy 58.505054 -124.903986) (xy 58.467108 -124.843595) (xy 58.436163 -124.779336) (xy 58.412606 -124.712016)
			(xy 58.396736 -124.642481) (xy 58.38875 -124.571607) (xy 40.312682 -124.571607) (xy 40.316808 -124.589685)
			(xy 40.324794 -124.660559) (xy 40.325294 -124.69622) (xy 40.324794 -124.731881) (xy 40.316808 -124.802755)
			(xy 40.300938 -124.87229) (xy 40.277381 -124.93961) (xy 40.246436 -125.003869) (xy 40.20849 -125.06426)
			(xy 40.164021 -125.120022) (xy 40.113588 -125.170455) (xy 40.057826 -125.214924) (xy 39.997435 -125.25287)
			(xy 39.933176 -125.283815) (xy 39.865856 -125.307372) (xy 39.796321 -125.323242) (xy 39.725447 -125.331228)
			(xy 39.654125 -125.331228) (xy 39.583251 -125.323242) (xy 39.513716 -125.307372) (xy 39.446396 -125.283815)
			(xy 39.382137 -125.25287) (xy 39.321746 -125.214924) (xy 39.265984 -125.170455) (xy 39.215551 -125.120022)
			(xy 39.171082 -125.06426) (xy 39.133136 -125.003869) (xy 39.102191 -124.93961) (xy 39.078634 -124.87229)
			(xy 39.062764 -124.802755) (xy 39.054778 -124.731881) (xy 27.89936 -124.731881) (xy 27.89936 -126.053358)
			(xy 29.519874 -126.053358) (xy 29.519874 -125.966458) (xy 29.527892 -125.879929) (xy 29.54386 -125.794509)
			(xy 29.567641 -125.710927) (xy 29.599033 -125.629895) (xy 29.637767 -125.552106) (xy 29.683514 -125.478222)
			(xy 29.735883 -125.408875) (xy 29.794427 -125.344655) (xy 29.858647 -125.286111) (xy 29.927994 -125.233742)
			(xy 30.001878 -125.187995) (xy 30.079667 -125.149261) (xy 30.160699 -125.117869) (xy 30.244281 -125.094088)
			(xy 30.329701 -125.07812) (xy 30.41623 -125.070102) (xy 30.50313 -125.070102) (xy 30.589659 -125.07812)
			(xy 30.675079 -125.094088) (xy 30.758661 -125.117869) (xy 30.839693 -125.149261) (xy 30.917482 -125.187995)
			(xy 30.991366 -125.233742) (xy 31.060713 -125.286111) (xy 31.124933 -125.344655) (xy 31.183477 -125.408875)
			(xy 31.235846 -125.478222) (xy 31.281593 -125.552106) (xy 31.320327 -125.629895) (xy 31.351719 -125.710927)
			(xy 31.3755 -125.794509) (xy 31.391468 -125.879929) (xy 31.399486 -125.966458) (xy 31.399988 -126.009908)
			(xy 31.399486 -126.053358) (xy 34.599874 -126.053358) (xy 34.599874 -125.966458) (xy 34.607892 -125.879929)
			(xy 34.62386 -125.794509) (xy 34.647641 -125.710927) (xy 34.679033 -125.629895) (xy 34.717767 -125.552106)
			(xy 34.763514 -125.478222) (xy 34.815883 -125.408875) (xy 34.874427 -125.344655) (xy 34.938647 -125.286111)
			(xy 35.007994 -125.233742) (xy 35.081878 -125.187995) (xy 35.159667 -125.149261) (xy 35.240699 -125.117869)
			(xy 35.324281 -125.094088) (xy 35.409701 -125.07812) (xy 35.49623 -125.070102) (xy 35.58313 -125.070102)
			(xy 35.669659 -125.07812) (xy 35.755079 -125.094088) (xy 35.838661 -125.117869) (xy 35.919693 -125.149261)
			(xy 35.997482 -125.187995) (xy 36.071366 -125.233742) (xy 36.140713 -125.286111) (xy 36.204933 -125.344655)
			(xy 36.263477 -125.408875) (xy 36.315846 -125.478222) (xy 36.361593 -125.552106) (xy 36.400327 -125.629895)
			(xy 36.431719 -125.710927) (xy 36.4555 -125.794509) (xy 36.471468 -125.879929) (xy 36.479486 -125.966458)
			(xy 36.479988 -126.009908) (xy 36.479486 -126.053358) (xy 36.471468 -126.139887) (xy 36.4555 -126.225307)
			(xy 36.431719 -126.308889) (xy 36.400327 -126.389921) (xy 36.361593 -126.46771) (xy 36.315846 -126.541594)
			(xy 36.263477 -126.610941) (xy 36.253028 -126.622403) (xy 39.054778 -126.622403) (xy 39.054778 -126.551081)
			(xy 39.062764 -126.480207) (xy 39.078634 -126.410672) (xy 39.102191 -126.343352) (xy 39.133136 -126.279093)
			(xy 39.171082 -126.218702) (xy 39.215551 -126.16294) (xy 39.265984 -126.112507) (xy 39.321746 -126.068038)
			(xy 39.382137 -126.030092) (xy 39.446396 -125.999147) (xy 39.513716 -125.97559) (xy 39.583251 -125.95972)
			(xy 39.654125 -125.951734) (xy 39.725447 -125.951734) (xy 39.796321 -125.95972) (xy 39.865856 -125.97559)
			(xy 39.933176 -125.999147) (xy 39.997435 -126.030092) (xy 40.057826 -126.068038) (xy 40.113588 -126.112507)
			(xy 40.164021 -126.16294) (xy 40.20849 -126.218702) (xy 40.246436 -126.279093) (xy 40.277381 -126.343352)
			(xy 40.300938 -126.410672) (xy 40.312682 -126.462129) (xy 58.38875 -126.462129) (xy 58.38875 -126.390807)
			(xy 58.396736 -126.319933) (xy 58.412606 -126.250398) (xy 58.436163 -126.183078) (xy 58.467108 -126.118819)
			(xy 58.505054 -126.058428) (xy 58.549523 -126.002666) (xy 58.599956 -125.952233) (xy 58.655718 -125.907764)
			(xy 58.716109 -125.869818) (xy 58.780368 -125.838873) (xy 58.847688 -125.815316) (xy 58.917223 -125.799446)
			(xy 58.988097 -125.79146) (xy 59.059419 -125.79146) (xy 59.130293 -125.799446) (xy 59.199828 -125.815316)
			(xy 59.267148 -125.838873) (xy 59.331407 -125.869818) (xy 59.391798 -125.907764) (xy 59.44756 -125.952233)
			(xy 59.497993 -126.002666) (xy 59.542462 -126.058428) (xy 59.580408 -126.118819) (xy 59.611353 -126.183078)
			(xy 59.63491 -126.250398) (xy 59.65078 -126.319933) (xy 59.658766 -126.390807) (xy 59.659266 -126.426468)
			(xy 59.658766 -126.462129) (xy 60.629792 -126.462129) (xy 60.629792 -126.390807) (xy 60.637778 -126.319933)
			(xy 60.653648 -126.250398) (xy 60.677205 -126.183078) (xy 60.70815 -126.118819) (xy 60.746096 -126.058428)
			(xy 60.790565 -126.002666) (xy 60.840998 -125.952233) (xy 60.89676 -125.907764) (xy 60.957151 -125.869818)
			(xy 61.02141 -125.838873) (xy 61.08873 -125.815316) (xy 61.158265 -125.799446) (xy 61.229139 -125.79146)
			(xy 61.300461 -125.79146) (xy 61.371335 -125.799446) (xy 61.44087 -125.815316) (xy 61.50819 -125.838873)
			(xy 61.572449 -125.869818) (xy 61.63284 -125.907764) (xy 61.688602 -125.952233) (xy 61.739035 -126.002666)
			(xy 61.783504 -126.058428) (xy 61.82145 -126.118819) (xy 61.852395 -126.183078) (xy 61.875952 -126.250398)
			(xy 61.891822 -126.319933) (xy 61.899808 -126.390807) (xy 61.900308 -126.426468) (xy 61.899808 -126.462129)
			(xy 62.533776 -126.462129) (xy 62.533776 -126.390807) (xy 62.541762 -126.319933) (xy 62.557632 -126.250398)
			(xy 62.581189 -126.183078) (xy 62.612134 -126.118819) (xy 62.65008 -126.058428) (xy 62.694549 -126.002666)
			(xy 62.744982 -125.952233) (xy 62.800744 -125.907764) (xy 62.861135 -125.869818) (xy 62.925394 -125.838873)
			(xy 62.992714 -125.815316) (xy 63.062249 -125.799446) (xy 63.133123 -125.79146) (xy 63.204445 -125.79146)
			(xy 63.275319 -125.799446) (xy 63.344854 -125.815316) (xy 63.412174 -125.838873) (xy 63.476433 -125.869818)
			(xy 63.536824 -125.907764) (xy 63.592586 -125.952233) (xy 63.643019 -126.002666) (xy 63.687488 -126.058428)
			(xy 63.725434 -126.118819) (xy 63.756379 -126.183078) (xy 63.779936 -126.250398) (xy 63.795806 -126.319933)
			(xy 63.803792 -126.390807) (xy 63.804292 -126.426468) (xy 63.803792 -126.462129) (xy 63.795806 -126.533003)
			(xy 63.779936 -126.602538) (xy 63.756379 -126.669858) (xy 63.725434 -126.734117) (xy 63.687488 -126.794508)
			(xy 63.643019 -126.85027) (xy 63.592586 -126.900703) (xy 63.536824 -126.945172) (xy 63.476433 -126.983118)
			(xy 63.412174 -127.014063) (xy 63.344854 -127.03762) (xy 63.275319 -127.05349) (xy 63.204445 -127.061476)
			(xy 63.133123 -127.061476) (xy 63.062249 -127.05349) (xy 62.992714 -127.03762) (xy 62.925394 -127.014063)
			(xy 62.861135 -126.983118) (xy 62.800744 -126.945172) (xy 62.744982 -126.900703) (xy 62.694549 -126.85027)
			(xy 62.65008 -126.794508) (xy 62.612134 -126.734117) (xy 62.581189 -126.669858) (xy 62.557632 -126.602538)
			(xy 62.541762 -126.533003) (xy 62.533776 -126.462129) (xy 61.899808 -126.462129) (xy 61.891822 -126.533003)
			(xy 61.875952 -126.602538) (xy 61.852395 -126.669858) (xy 61.82145 -126.734117) (xy 61.783504 -126.794508)
			(xy 61.739035 -126.85027) (xy 61.688602 -126.900703) (xy 61.63284 -126.945172) (xy 61.572449 -126.983118)
			(xy 61.50819 -127.014063) (xy 61.44087 -127.03762) (xy 61.371335 -127.05349) (xy 61.300461 -127.061476)
			(xy 61.229139 -127.061476) (xy 61.158265 -127.05349) (xy 61.08873 -127.03762) (xy 61.02141 -127.014063)
			(xy 60.957151 -126.983118) (xy 60.89676 -126.945172) (xy 60.840998 -126.900703) (xy 60.790565 -126.85027)
			(xy 60.746096 -126.794508) (xy 60.70815 -126.734117) (xy 60.677205 -126.669858) (xy 60.653648 -126.602538)
			(xy 60.637778 -126.533003) (xy 60.629792 -126.462129) (xy 59.658766 -126.462129) (xy 59.65078 -126.533003)
			(xy 59.63491 -126.602538) (xy 59.611353 -126.669858) (xy 59.580408 -126.734117) (xy 59.542462 -126.794508)
			(xy 59.497993 -126.85027) (xy 59.44756 -126.900703) (xy 59.391798 -126.945172) (xy 59.331407 -126.983118)
			(xy 59.267148 -127.014063) (xy 59.199828 -127.03762) (xy 59.130293 -127.05349) (xy 59.059419 -127.061476)
			(xy 58.988097 -127.061476) (xy 58.917223 -127.05349) (xy 58.847688 -127.03762) (xy 58.780368 -127.014063)
			(xy 58.716109 -126.983118) (xy 58.655718 -126.945172) (xy 58.599956 -126.900703) (xy 58.549523 -126.85027)
			(xy 58.505054 -126.794508) (xy 58.467108 -126.734117) (xy 58.436163 -126.669858) (xy 58.412606 -126.602538)
			(xy 58.396736 -126.533003) (xy 58.38875 -126.462129) (xy 40.312682 -126.462129) (xy 40.316808 -126.480207)
			(xy 40.324794 -126.551081) (xy 40.325294 -126.586742) (xy 40.324794 -126.622403) (xy 40.316808 -126.693277)
			(xy 40.300938 -126.762812) (xy 40.277381 -126.830132) (xy 40.246436 -126.894391) (xy 40.20849 -126.954782)
			(xy 40.164021 -127.010544) (xy 40.113588 -127.060977) (xy 40.057826 -127.105446) (xy 39.997435 -127.143392)
			(xy 39.933176 -127.174337) (xy 39.865856 -127.197894) (xy 39.796321 -127.213764) (xy 39.725447 -127.22175)
			(xy 39.654125 -127.22175) (xy 39.583251 -127.213764) (xy 39.513716 -127.197894) (xy 39.446396 -127.174337)
			(xy 39.382137 -127.143392) (xy 39.321746 -127.105446) (xy 39.265984 -127.060977) (xy 39.215551 -127.010544)
			(xy 39.171082 -126.954782) (xy 39.133136 -126.894391) (xy 39.102191 -126.830132) (xy 39.078634 -126.762812)
			(xy 39.062764 -126.693277) (xy 39.054778 -126.622403) (xy 36.253028 -126.622403) (xy 36.204933 -126.675161)
			(xy 36.140713 -126.733705) (xy 36.071366 -126.786074) (xy 35.997482 -126.831821) (xy 35.919693 -126.870555)
			(xy 35.838661 -126.901947) (xy 35.755079 -126.925728) (xy 35.669659 -126.941696) (xy 35.58313 -126.949714)
			(xy 35.49623 -126.949714) (xy 35.409701 -126.941696) (xy 35.324281 -126.925728) (xy 35.240699 -126.901947)
			(xy 35.159667 -126.870555) (xy 35.081878 -126.831821) (xy 35.007994 -126.786074) (xy 34.938647 -126.733705)
			(xy 34.874427 -126.675161) (xy 34.815883 -126.610941) (xy 34.763514 -126.541594) (xy 34.717767 -126.46771)
			(xy 34.679033 -126.389921) (xy 34.647641 -126.308889) (xy 34.62386 -126.225307) (xy 34.607892 -126.139887)
			(xy 34.599874 -126.053358) (xy 31.399486 -126.053358) (xy 31.391468 -126.139887) (xy 31.3755 -126.225307)
			(xy 31.351719 -126.308889) (xy 31.320327 -126.389921) (xy 31.281593 -126.46771) (xy 31.235846 -126.541594)
			(xy 31.183477 -126.610941) (xy 31.124933 -126.675161) (xy 31.060713 -126.733705) (xy 30.991366 -126.786074)
			(xy 30.917482 -126.831821) (xy 30.839693 -126.870555) (xy 30.758661 -126.901947) (xy 30.675079 -126.925728)
			(xy 30.589659 -126.941696) (xy 30.50313 -126.949714) (xy 30.41623 -126.949714) (xy 30.329701 -126.941696)
			(xy 30.244281 -126.925728) (xy 30.160699 -126.901947) (xy 30.079667 -126.870555) (xy 30.001878 -126.831821)
			(xy 29.927994 -126.786074) (xy 29.858647 -126.733705) (xy 29.794427 -126.675161) (xy 29.735883 -126.610941)
			(xy 29.683514 -126.541594) (xy 29.637767 -126.46771) (xy 29.599033 -126.389921) (xy 29.567641 -126.308889)
			(xy 29.54386 -126.225307) (xy 29.527892 -126.139887) (xy 29.519874 -126.053358) (xy 27.89936 -126.053358)
			(xy 27.89936 -128.593358) (xy 29.519874 -128.593358) (xy 29.519874 -128.506458) (xy 29.527892 -128.419929)
			(xy 29.54386 -128.334509) (xy 29.567641 -128.250927) (xy 29.599033 -128.169895) (xy 29.637767 -128.092106)
			(xy 29.683514 -128.018222) (xy 29.735883 -127.948875) (xy 29.794427 -127.884655) (xy 29.858647 -127.826111)
			(xy 29.927994 -127.773742) (xy 30.001878 -127.727995) (xy 30.079667 -127.689261) (xy 30.160699 -127.657869)
			(xy 30.244281 -127.634088) (xy 30.329701 -127.61812) (xy 30.41623 -127.610102) (xy 30.50313 -127.610102)
			(xy 30.589659 -127.61812) (xy 30.675079 -127.634088) (xy 30.758661 -127.657869) (xy 30.839693 -127.689261)
			(xy 30.917482 -127.727995) (xy 30.991366 -127.773742) (xy 31.060713 -127.826111) (xy 31.124933 -127.884655)
			(xy 31.183477 -127.948875) (xy 31.235846 -128.018222) (xy 31.281593 -128.092106) (xy 31.320327 -128.169895)
			(xy 31.351719 -128.250927) (xy 31.3755 -128.334509) (xy 31.391468 -128.419929) (xy 31.399486 -128.506458)
			(xy 31.399988 -128.549908) (xy 31.399486 -128.593358) (xy 34.599874 -128.593358) (xy 34.599874 -128.506458)
			(xy 34.607892 -128.419929) (xy 34.62386 -128.334509) (xy 34.647641 -128.250927) (xy 34.679033 -128.169895)
			(xy 34.717767 -128.092106) (xy 34.763514 -128.018222) (xy 34.815883 -127.948875) (xy 34.874427 -127.884655)
			(xy 34.938647 -127.826111) (xy 35.007994 -127.773742) (xy 35.081878 -127.727995) (xy 35.159667 -127.689261)
			(xy 35.240699 -127.657869) (xy 35.324281 -127.634088) (xy 35.409701 -127.61812) (xy 35.49623 -127.610102)
			(xy 35.58313 -127.610102) (xy 35.669659 -127.61812) (xy 35.755079 -127.634088) (xy 35.838661 -127.657869)
			(xy 35.919693 -127.689261) (xy 35.997482 -127.727995) (xy 36.071366 -127.773742) (xy 36.140713 -127.826111)
			(xy 36.204933 -127.884655) (xy 36.263477 -127.948875) (xy 36.315846 -128.018222) (xy 36.361593 -128.092106)
			(xy 36.400327 -128.169895) (xy 36.431719 -128.250927) (xy 36.4555 -128.334509) (xy 36.471468 -128.419929)
			(xy 36.479486 -128.506458) (xy 36.479988 -128.549908) (xy 36.479486 -128.593358) (xy 36.472982 -128.663547)
			(xy 39.054778 -128.663547) (xy 39.054778 -128.592225) (xy 39.062764 -128.521351) (xy 39.078634 -128.451816)
			(xy 39.102191 -128.384496) (xy 39.133136 -128.320237) (xy 39.171082 -128.259846) (xy 39.215551 -128.204084)
			(xy 39.265984 -128.153651) (xy 39.321746 -128.109182) (xy 39.382137 -128.071236) (xy 39.446396 -128.040291)
			(xy 39.513716 -128.016734) (xy 39.583251 -128.000864) (xy 39.654125 -127.992878) (xy 39.725447 -127.992878)
			(xy 39.796321 -128.000864) (xy 39.865856 -128.016734) (xy 39.933176 -128.040291) (xy 39.997435 -128.071236)
			(xy 40.057826 -128.109182) (xy 40.113588 -128.153651) (xy 40.164021 -128.204084) (xy 40.20849 -128.259846)
			(xy 40.246436 -128.320237) (xy 40.277381 -128.384496) (xy 40.300938 -128.451816) (xy 40.316808 -128.521351)
			(xy 40.324794 -128.592225) (xy 40.325294 -128.627886) (xy 40.324794 -128.663547) (xy 40.321152 -128.695873)
			(xy 47.574952 -128.695873) (xy 47.574952 -128.614763) (xy 47.582902 -128.534044) (xy 47.598725 -128.454493)
			(xy 47.62227 -128.376877) (xy 47.653309 -128.301941) (xy 47.691544 -128.230409) (xy 47.736606 -128.162969)
			(xy 47.788061 -128.10027) (xy 47.845414 -128.042917) (xy 47.908113 -127.991462) (xy 47.975553 -127.9464)
			(xy 48.047085 -127.908165) (xy 48.122021 -127.877126) (xy 48.199637 -127.853581) (xy 48.279188 -127.837758)
			(xy 48.359907 -127.829808) (xy 48.441017 -127.829808) (xy 48.521736 -127.837758) (xy 48.601287 -127.853581)
			(xy 48.678903 -127.877126) (xy 48.753839 -127.908165) (xy 48.825371 -127.9464) (xy 48.892811 -127.991462)
			(xy 48.95551 -128.042917) (xy 49.012863 -128.10027) (xy 49.064318 -128.162969) (xy 49.10938 -128.230409)
			(xy 49.147615 -128.301941) (xy 49.178654 -128.376877) (xy 49.202199 -128.454493) (xy 49.211902 -128.503273)
			(xy 58.38875 -128.503273) (xy 58.38875 -128.431951) (xy 58.396736 -128.361077) (xy 58.412606 -128.291542)
			(xy 58.436163 -128.224222) (xy 58.467108 -128.159963) (xy 58.505054 -128.099572) (xy 58.549523 -128.04381)
			(xy 58.599956 -127.993377) (xy 58.655718 -127.948908) (xy 58.716109 -127.910962) (xy 58.780368 -127.880017)
			(xy 58.847688 -127.85646) (xy 58.917223 -127.84059) (xy 58.988097 -127.832604) (xy 59.059419 -127.832604)
			(xy 59.130293 -127.84059) (xy 59.199828 -127.85646) (xy 59.267148 -127.880017) (xy 59.331407 -127.910962)
			(xy 59.391798 -127.948908) (xy 59.44756 -127.993377) (xy 59.497993 -128.04381) (xy 59.542462 -128.099572)
			(xy 59.580408 -128.159963) (xy 59.611353 -128.224222) (xy 59.63491 -128.291542) (xy 59.65078 -128.361077)
			(xy 59.658766 -128.431951) (xy 59.659266 -128.467612) (xy 59.658766 -128.503273) (xy 60.629792 -128.503273)
			(xy 60.629792 -128.431951) (xy 60.637778 -128.361077) (xy 60.653648 -128.291542) (xy 60.677205 -128.224222)
			(xy 60.70815 -128.159963) (xy 60.746096 -128.099572) (xy 60.790565 -128.04381) (xy 60.840998 -127.993377)
			(xy 60.89676 -127.948908) (xy 60.957151 -127.910962) (xy 61.02141 -127.880017) (xy 61.08873 -127.85646)
			(xy 61.158265 -127.84059) (xy 61.229139 -127.832604) (xy 61.300461 -127.832604) (xy 61.371335 -127.84059)
			(xy 61.44087 -127.85646) (xy 61.50819 -127.880017) (xy 61.572449 -127.910962) (xy 61.63284 -127.948908)
			(xy 61.688602 -127.993377) (xy 61.739035 -128.04381) (xy 61.783504 -128.099572) (xy 61.82145 -128.159963)
			(xy 61.852395 -128.224222) (xy 61.875952 -128.291542) (xy 61.891822 -128.361077) (xy 61.899808 -128.431951)
			(xy 61.900308 -128.467612) (xy 61.899808 -128.503273) (xy 62.533776 -128.503273) (xy 62.533776 -128.431951)
			(xy 62.541762 -128.361077) (xy 62.557632 -128.291542) (xy 62.581189 -128.224222) (xy 62.612134 -128.159963)
			(xy 62.65008 -128.099572) (xy 62.694549 -128.04381) (xy 62.744982 -127.993377) (xy 62.800744 -127.948908)
			(xy 62.861135 -127.910962) (xy 62.925394 -127.880017) (xy 62.992714 -127.85646) (xy 63.062249 -127.84059)
			(xy 63.133123 -127.832604) (xy 63.204445 -127.832604) (xy 63.275319 -127.84059) (xy 63.344854 -127.85646)
			(xy 63.412174 -127.880017) (xy 63.476433 -127.910962) (xy 63.536824 -127.948908) (xy 63.592586 -127.993377)
			(xy 63.643019 -128.04381) (xy 63.687488 -128.099572) (xy 63.725434 -128.159963) (xy 63.756379 -128.224222)
			(xy 63.779936 -128.291542) (xy 63.795806 -128.361077) (xy 63.803792 -128.431951) (xy 63.804292 -128.467612)
			(xy 63.803792 -128.503273) (xy 63.795806 -128.574147) (xy 63.779936 -128.643682) (xy 63.756379 -128.711002)
			(xy 63.725434 -128.775261) (xy 63.687488 -128.835652) (xy 63.643019 -128.891414) (xy 63.592586 -128.941847)
			(xy 63.536824 -128.986316) (xy 63.476433 -129.024262) (xy 63.412174 -129.055207) (xy 63.344854 -129.078764)
			(xy 63.275319 -129.094634) (xy 63.204445 -129.10262) (xy 63.133123 -129.10262) (xy 63.062249 -129.094634)
			(xy 62.992714 -129.078764) (xy 62.925394 -129.055207) (xy 62.861135 -129.024262) (xy 62.800744 -128.986316)
			(xy 62.744982 -128.941847) (xy 62.694549 -128.891414) (xy 62.65008 -128.835652) (xy 62.612134 -128.775261)
			(xy 62.581189 -128.711002) (xy 62.557632 -128.643682) (xy 62.541762 -128.574147) (xy 62.533776 -128.503273)
			(xy 61.899808 -128.503273) (xy 61.891822 -128.574147) (xy 61.875952 -128.643682) (xy 61.852395 -128.711002)
			(xy 61.82145 -128.775261) (xy 61.783504 -128.835652) (xy 61.739035 -128.891414) (xy 61.688602 -128.941847)
			(xy 61.63284 -128.986316) (xy 61.572449 -129.024262) (xy 61.50819 -129.055207) (xy 61.44087 -129.078764)
			(xy 61.371335 -129.094634) (xy 61.300461 -129.10262) (xy 61.229139 -129.10262) (xy 61.158265 -129.094634)
			(xy 61.08873 -129.078764) (xy 61.02141 -129.055207) (xy 60.957151 -129.024262) (xy 60.89676 -128.986316)
			(xy 60.840998 -128.941847) (xy 60.790565 -128.891414) (xy 60.746096 -128.835652) (xy 60.70815 -128.775261)
			(xy 60.677205 -128.711002) (xy 60.653648 -128.643682) (xy 60.637778 -128.574147) (xy 60.629792 -128.503273)
			(xy 59.658766 -128.503273) (xy 59.65078 -128.574147) (xy 59.63491 -128.643682) (xy 59.611353 -128.711002)
			(xy 59.580408 -128.775261) (xy 59.542462 -128.835652) (xy 59.497993 -128.891414) (xy 59.44756 -128.941847)
			(xy 59.391798 -128.986316) (xy 59.331407 -129.024262) (xy 59.267148 -129.055207) (xy 59.199828 -129.078764)
			(xy 59.130293 -129.094634) (xy 59.059419 -129.10262) (xy 58.988097 -129.10262) (xy 58.917223 -129.094634)
			(xy 58.847688 -129.078764) (xy 58.780368 -129.055207) (xy 58.716109 -129.024262) (xy 58.655718 -128.986316)
			(xy 58.599956 -128.941847) (xy 58.549523 -128.891414) (xy 58.505054 -128.835652) (xy 58.467108 -128.775261)
			(xy 58.436163 -128.711002) (xy 58.412606 -128.643682) (xy 58.396736 -128.574147) (xy 58.38875 -128.503273)
			(xy 49.211902 -128.503273) (xy 49.218022 -128.534044) (xy 49.225972 -128.614763) (xy 49.22647 -128.655318)
			(xy 49.225972 -128.695873) (xy 49.218022 -128.776592) (xy 49.202199 -128.856143) (xy 49.178654 -128.933759)
			(xy 49.147615 -129.008695) (xy 49.10938 -129.080227) (xy 49.064318 -129.147667) (xy 49.012863 -129.210366)
			(xy 48.95551 -129.267719) (xy 48.892811 -129.319174) (xy 48.825371 -129.364236) (xy 48.753839 -129.402471)
			(xy 48.678903 -129.43351) (xy 48.601287 -129.457055) (xy 48.521736 -129.472878) (xy 48.441017 -129.480828)
			(xy 48.359907 -129.480828) (xy 48.279188 -129.472878) (xy 48.199637 -129.457055) (xy 48.122021 -129.43351)
			(xy 48.047085 -129.402471) (xy 47.975553 -129.364236) (xy 47.908113 -129.319174) (xy 47.845414 -129.267719)
			(xy 47.788061 -129.210366) (xy 47.736606 -129.147667) (xy 47.691544 -129.080227) (xy 47.653309 -129.008695)
			(xy 47.62227 -128.933759) (xy 47.598725 -128.856143) (xy 47.582902 -128.776592) (xy 47.574952 -128.695873)
			(xy 40.321152 -128.695873) (xy 40.316808 -128.734421) (xy 40.300938 -128.803956) (xy 40.277381 -128.871276)
			(xy 40.246436 -128.935535) (xy 40.20849 -128.995926) (xy 40.164021 -129.051688) (xy 40.113588 -129.102121)
			(xy 40.057826 -129.14659) (xy 39.997435 -129.184536) (xy 39.933176 -129.215481) (xy 39.865856 -129.239038)
			(xy 39.796321 -129.254908) (xy 39.725447 -129.262894) (xy 39.654125 -129.262894) (xy 39.583251 -129.254908)
			(xy 39.513716 -129.239038) (xy 39.446396 -129.215481) (xy 39.382137 -129.184536) (xy 39.321746 -129.14659)
			(xy 39.265984 -129.102121) (xy 39.215551 -129.051688) (xy 39.171082 -128.995926) (xy 39.133136 -128.935535)
			(xy 39.102191 -128.871276) (xy 39.078634 -128.803956) (xy 39.062764 -128.734421) (xy 39.054778 -128.663547)
			(xy 36.472982 -128.663547) (xy 36.471468 -128.679887) (xy 36.4555 -128.765307) (xy 36.431719 -128.848889)
			(xy 36.400327 -128.929921) (xy 36.361593 -129.00771) (xy 36.315846 -129.081594) (xy 36.263477 -129.150941)
			(xy 36.204933 -129.215161) (xy 36.140713 -129.273705) (xy 36.071366 -129.326074) (xy 35.997482 -129.371821)
			(xy 35.919693 -129.410555) (xy 35.838661 -129.441947) (xy 35.755079 -129.465728) (xy 35.669659 -129.481696)
			(xy 35.58313 -129.489714) (xy 35.49623 -129.489714) (xy 35.409701 -129.481696) (xy 35.324281 -129.465728)
			(xy 35.240699 -129.441947) (xy 35.159667 -129.410555) (xy 35.081878 -129.371821) (xy 35.007994 -129.326074)
			(xy 34.938647 -129.273705) (xy 34.874427 -129.215161) (xy 34.815883 -129.150941) (xy 34.763514 -129.081594)
			(xy 34.717767 -129.00771) (xy 34.679033 -128.929921) (xy 34.647641 -128.848889) (xy 34.62386 -128.765307)
			(xy 34.607892 -128.679887) (xy 34.599874 -128.593358) (xy 31.399486 -128.593358) (xy 31.391468 -128.679887)
			(xy 31.3755 -128.765307) (xy 31.351719 -128.848889) (xy 31.320327 -128.929921) (xy 31.281593 -129.00771)
			(xy 31.235846 -129.081594) (xy 31.183477 -129.150941) (xy 31.124933 -129.215161) (xy 31.060713 -129.273705)
			(xy 30.991366 -129.326074) (xy 30.917482 -129.371821) (xy 30.839693 -129.410555) (xy 30.758661 -129.441947)
			(xy 30.675079 -129.465728) (xy 30.589659 -129.481696) (xy 30.50313 -129.489714) (xy 30.41623 -129.489714)
			(xy 30.329701 -129.481696) (xy 30.244281 -129.465728) (xy 30.160699 -129.441947) (xy 30.079667 -129.410555)
			(xy 30.001878 -129.371821) (xy 29.927994 -129.326074) (xy 29.858647 -129.273705) (xy 29.794427 -129.215161)
			(xy 29.735883 -129.150941) (xy 29.683514 -129.081594) (xy 29.637767 -129.00771) (xy 29.599033 -128.929921)
			(xy 29.567641 -128.848889) (xy 29.54386 -128.765307) (xy 29.527892 -128.679887) (xy 29.519874 -128.593358)
			(xy 27.89936 -128.593358) (xy 27.89936 -131.133358) (xy 29.519874 -131.133358) (xy 29.519874 -131.046458)
			(xy 29.527892 -130.959929) (xy 29.54386 -130.874509) (xy 29.567641 -130.790927) (xy 29.599033 -130.709895)
			(xy 29.637767 -130.632106) (xy 29.683514 -130.558222) (xy 29.735883 -130.488875) (xy 29.794427 -130.424655)
			(xy 29.858647 -130.366111) (xy 29.927994 -130.313742) (xy 30.001878 -130.267995) (xy 30.079667 -130.229261)
			(xy 30.160699 -130.197869) (xy 30.244281 -130.174088) (xy 30.329701 -130.15812) (xy 30.41623 -130.150102)
			(xy 30.50313 -130.150102) (xy 30.589659 -130.15812) (xy 30.675079 -130.174088) (xy 30.758661 -130.197869)
			(xy 30.839693 -130.229261) (xy 30.917482 -130.267995) (xy 30.991366 -130.313742) (xy 31.060713 -130.366111)
			(xy 31.124933 -130.424655) (xy 31.183477 -130.488875) (xy 31.235846 -130.558222) (xy 31.281593 -130.632106)
			(xy 31.320327 -130.709895) (xy 31.351719 -130.790927) (xy 31.3755 -130.874509) (xy 31.391468 -130.959929)
			(xy 31.399486 -131.046458) (xy 31.399988 -131.089908) (xy 31.399486 -131.133358) (xy 34.599874 -131.133358)
			(xy 34.599874 -131.046458) (xy 34.607892 -130.959929) (xy 34.62386 -130.874509) (xy 34.647641 -130.790927)
			(xy 34.679033 -130.709895) (xy 34.717767 -130.632106) (xy 34.763514 -130.558222) (xy 34.815883 -130.488875)
			(xy 34.874427 -130.424655) (xy 34.938647 -130.366111) (xy 35.007994 -130.313742) (xy 35.081878 -130.267995)
			(xy 35.159667 -130.229261) (xy 35.240699 -130.197869) (xy 35.324281 -130.174088) (xy 35.409701 -130.15812)
			(xy 35.49623 -130.150102) (xy 35.58313 -130.150102) (xy 35.669659 -130.15812) (xy 35.755079 -130.174088)
			(xy 35.838661 -130.197869) (xy 35.919693 -130.229261) (xy 35.997482 -130.267995) (xy 36.071366 -130.313742)
			(xy 36.140713 -130.366111) (xy 36.204933 -130.424655) (xy 36.263477 -130.488875) (xy 36.315846 -130.558222)
			(xy 36.325227 -130.573373) (xy 39.054778 -130.573373) (xy 39.054778 -130.502051) (xy 39.062764 -130.431177)
			(xy 39.078634 -130.361642) (xy 39.102191 -130.294322) (xy 39.133136 -130.230063) (xy 39.171082 -130.169672)
			(xy 39.215551 -130.11391) (xy 39.265984 -130.063477) (xy 39.321746 -130.019008) (xy 39.382137 -129.981062)
			(xy 39.446396 -129.950117) (xy 39.513716 -129.92656) (xy 39.583251 -129.91069) (xy 39.654125 -129.902704)
			(xy 39.725447 -129.902704) (xy 39.796321 -129.91069) (xy 39.865856 -129.92656) (xy 39.933176 -129.950117)
			(xy 39.997435 -129.981062) (xy 40.057826 -130.019008) (xy 40.113588 -130.063477) (xy 40.164021 -130.11391)
			(xy 40.20849 -130.169672) (xy 40.246436 -130.230063) (xy 40.277381 -130.294322) (xy 40.300938 -130.361642)
			(xy 40.312682 -130.413099) (xy 58.38875 -130.413099) (xy 58.38875 -130.341777) (xy 58.396736 -130.270903)
			(xy 58.412606 -130.201368) (xy 58.436163 -130.134048) (xy 58.467108 -130.069789) (xy 58.505054 -130.009398)
			(xy 58.549523 -129.953636) (xy 58.599956 -129.903203) (xy 58.655718 -129.858734) (xy 58.716109 -129.820788)
			(xy 58.780368 -129.789843) (xy 58.847688 -129.766286) (xy 58.917223 -129.750416) (xy 58.988097 -129.74243)
			(xy 59.059419 -129.74243) (xy 59.130293 -129.750416) (xy 59.199828 -129.766286) (xy 59.267148 -129.789843)
			(xy 59.331407 -129.820788) (xy 59.391798 -129.858734) (xy 59.44756 -129.903203) (xy 59.497993 -129.953636)
			(xy 59.542462 -130.009398) (xy 59.580408 -130.069789) (xy 59.611353 -130.134048) (xy 59.63491 -130.201368)
			(xy 59.65078 -130.270903) (xy 59.658766 -130.341777) (xy 59.659266 -130.377438) (xy 59.658766 -130.413099)
			(xy 60.629792 -130.413099) (xy 60.629792 -130.341777) (xy 60.637778 -130.270903) (xy 60.653648 -130.201368)
			(xy 60.677205 -130.134048) (xy 60.70815 -130.069789) (xy 60.746096 -130.009398) (xy 60.790565 -129.953636)
			(xy 60.840998 -129.903203) (xy 60.89676 -129.858734) (xy 60.957151 -129.820788) (xy 61.02141 -129.789843)
			(xy 61.08873 -129.766286) (xy 61.158265 -129.750416) (xy 61.229139 -129.74243) (xy 61.300461 -129.74243)
			(xy 61.371335 -129.750416) (xy 61.44087 -129.766286) (xy 61.50819 -129.789843) (xy 61.572449 -129.820788)
			(xy 61.63284 -129.858734) (xy 61.688602 -129.903203) (xy 61.739035 -129.953636) (xy 61.783504 -130.009398)
			(xy 61.82145 -130.069789) (xy 61.852395 -130.134048) (xy 61.875952 -130.201368) (xy 61.891822 -130.270903)
			(xy 61.899808 -130.341777) (xy 61.900308 -130.377438) (xy 61.899808 -130.413099) (xy 62.533776 -130.413099)
			(xy 62.533776 -130.341777) (xy 62.541762 -130.270903) (xy 62.557632 -130.201368) (xy 62.581189 -130.134048)
			(xy 62.612134 -130.069789) (xy 62.65008 -130.009398) (xy 62.694549 -129.953636) (xy 62.744982 -129.903203)
			(xy 62.800744 -129.858734) (xy 62.861135 -129.820788) (xy 62.925394 -129.789843) (xy 62.992714 -129.766286)
			(xy 63.062249 -129.750416) (xy 63.133123 -129.74243) (xy 63.204445 -129.74243) (xy 63.275319 -129.750416)
			(xy 63.344854 -129.766286) (xy 63.412174 -129.789843) (xy 63.476433 -129.820788) (xy 63.536824 -129.858734)
			(xy 63.592586 -129.903203) (xy 63.643019 -129.953636) (xy 63.687488 -130.009398) (xy 63.725434 -130.069789)
			(xy 63.756379 -130.134048) (xy 63.779936 -130.201368) (xy 63.795806 -130.270903) (xy 63.803792 -130.341777)
			(xy 63.804292 -130.377438) (xy 63.803792 -130.413099) (xy 63.795806 -130.483973) (xy 63.779936 -130.553508)
			(xy 63.756379 -130.620828) (xy 63.725434 -130.685087) (xy 63.687488 -130.745478) (xy 63.643019 -130.80124)
			(xy 63.592586 -130.851673) (xy 63.536824 -130.896142) (xy 63.476433 -130.934088) (xy 63.412174 -130.965033)
			(xy 63.344854 -130.98859) (xy 63.275319 -131.00446) (xy 63.204445 -131.012446) (xy 63.133123 -131.012446)
			(xy 63.062249 -131.00446) (xy 62.992714 -130.98859) (xy 62.925394 -130.965033) (xy 62.861135 -130.934088)
			(xy 62.800744 -130.896142) (xy 62.744982 -130.851673) (xy 62.694549 -130.80124) (xy 62.65008 -130.745478)
			(xy 62.612134 -130.685087) (xy 62.581189 -130.620828) (xy 62.557632 -130.553508) (xy 62.541762 -130.483973)
			(xy 62.533776 -130.413099) (xy 61.899808 -130.413099) (xy 61.891822 -130.483973) (xy 61.875952 -130.553508)
			(xy 61.852395 -130.620828) (xy 61.82145 -130.685087) (xy 61.783504 -130.745478) (xy 61.739035 -130.80124)
			(xy 61.688602 -130.851673) (xy 61.63284 -130.896142) (xy 61.572449 -130.934088) (xy 61.50819 -130.965033)
			(xy 61.44087 -130.98859) (xy 61.371335 -131.00446) (xy 61.300461 -131.012446) (xy 61.229139 -131.012446)
			(xy 61.158265 -131.00446) (xy 61.08873 -130.98859) (xy 61.02141 -130.965033) (xy 60.957151 -130.934088)
			(xy 60.89676 -130.896142) (xy 60.840998 -130.851673) (xy 60.790565 -130.80124) (xy 60.746096 -130.745478)
			(xy 60.70815 -130.685087) (xy 60.677205 -130.620828) (xy 60.653648 -130.553508) (xy 60.637778 -130.483973)
			(xy 60.629792 -130.413099) (xy 59.658766 -130.413099) (xy 59.65078 -130.483973) (xy 59.63491 -130.553508)
			(xy 59.611353 -130.620828) (xy 59.580408 -130.685087) (xy 59.542462 -130.745478) (xy 59.497993 -130.80124)
			(xy 59.44756 -130.851673) (xy 59.391798 -130.896142) (xy 59.331407 -130.934088) (xy 59.267148 -130.965033)
			(xy 59.199828 -130.98859) (xy 59.130293 -131.00446) (xy 59.059419 -131.012446) (xy 58.988097 -131.012446)
			(xy 58.917223 -131.00446) (xy 58.847688 -130.98859) (xy 58.780368 -130.965033) (xy 58.716109 -130.934088)
			(xy 58.655718 -130.896142) (xy 58.599956 -130.851673) (xy 58.549523 -130.80124) (xy 58.505054 -130.745478)
			(xy 58.467108 -130.685087) (xy 58.436163 -130.620828) (xy 58.412606 -130.553508) (xy 58.396736 -130.483973)
			(xy 58.38875 -130.413099) (xy 40.312682 -130.413099) (xy 40.316808 -130.431177) (xy 40.324794 -130.502051)
			(xy 40.325294 -130.537712) (xy 40.324794 -130.573373) (xy 40.316808 -130.644247) (xy 40.300938 -130.713782)
			(xy 40.277381 -130.781102) (xy 40.246436 -130.845361) (xy 40.20849 -130.905752) (xy 40.164021 -130.961514)
			(xy 40.113588 -131.011947) (xy 40.074115 -131.043426) (xy 67.948556 -131.043426) (xy 67.948556 -130.134614)
			(xy 67.94901 -130.102509) (xy 67.957104 -130.038811) (xy 67.973154 -129.976639) (xy 67.996903 -129.916982)
			(xy 68.027974 -129.86079) (xy 68.065871 -129.808957) (xy 68.109993 -129.762307) (xy 68.159637 -129.721583)
			(xy 68.214013 -129.687433) (xy 68.272256 -129.660401) (xy 68.333438 -129.640916) (xy 68.396587 -129.629289)
			(xy 68.460697 -129.625704) (xy 68.524748 -129.63022) (xy 68.587721 -129.642763) (xy 68.648614 -129.663134)
			(xy 68.706458 -129.69101) (xy 68.760332 -129.725946) (xy 68.809379 -129.767387) (xy 68.83146 -129.790698)
			(xy 68.847672 -129.807583) (xy 68.885089 -129.8357) (xy 68.927022 -129.856491) (xy 68.972052 -129.869253)
			(xy 69.018658 -129.873556) (xy 69.065264 -129.869253) (xy 69.110294 -129.856491) (xy 69.152227 -129.8357)
			(xy 69.189644 -129.807583) (xy 69.205856 -129.790698) (xy 69.228304 -129.767051) (xy 69.278198 -129.725076)
			(xy 69.333049 -129.689825) (xy 69.391958 -129.661877) (xy 69.453956 -129.64169) (xy 69.518026 -129.629595)
			(xy 69.583117 -129.625791) (xy 69.64816 -129.630341) (xy 69.712087 -129.643169) (xy 69.77385 -129.664066)
			(xy 69.832434 -129.692688) (xy 69.886878 -129.728565) (xy 69.936287 -129.771109) (xy 69.958458 -129.795016)
			(xy 69.974701 -129.8123) (xy 70.012389 -129.841088) (xy 70.054758 -129.862394) (xy 70.100342 -129.87548)
			(xy 70.147561 -129.879893) (xy 70.19478 -129.87548) (xy 70.240364 -129.862394) (xy 70.282733 -129.841088)
			(xy 70.320421 -129.8123) (xy 70.336664 -129.795016) (xy 70.358666 -129.771282) (xy 70.407665 -129.729003)
			(xy 70.461634 -129.693285) (xy 70.519701 -129.664707) (xy 70.580925 -129.64373) (xy 70.644317 -129.630695)
			(xy 70.708851 -129.625812) (xy 70.773482 -129.629159) (xy 70.837166 -129.640684) (xy 70.898872 -129.660199)
			(xy 70.957601 -129.687389) (xy 71.012405 -129.721813) (xy 71.062395 -129.762916) (xy 71.084948 -129.786126)
			(xy 71.101113 -129.802559) (xy 71.138243 -129.829867) (xy 71.179686 -129.850038) (xy 71.224085 -129.862411)
			(xy 71.269987 -129.866581) (xy 71.315889 -129.862411) (xy 71.360288 -129.850038) (xy 71.401731 -129.829867)
			(xy 71.438861 -129.802559) (xy 71.455026 -129.786126) (xy 71.477219 -129.763147) (xy 71.526487 -129.722475)
			(xy 71.580463 -129.688297) (xy 71.638295 -129.66115) (xy 71.699073 -129.641463) (xy 71.761839 -129.629545)
			(xy 71.825603 -129.625586) (xy 71.889361 -129.629646) (xy 71.952107 -129.641663) (xy 72.012854 -129.661446)
			(xy 72.070643 -129.688684) (xy 72.124565 -129.722948) (xy 72.173769 -129.763698) (xy 72.217479 -129.810291)
			(xy 72.255008 -129.861994) (xy 72.285763 -129.917991) (xy 72.30926 -129.9774) (xy 72.325128 -130.039285)
			(xy 72.333118 -130.10267) (xy 72.333612 -130.134614) (xy 72.333612 -131.043426) (xy 72.333072 -131.07616)
			(xy 72.32464 -131.141084) (xy 72.307946 -131.204389) (xy 72.283264 -131.265027) (xy 72.251004 -131.321996)
			(xy 72.231758 -131.34848) (xy 72.206612 -131.382262) (xy 72.206612 -131.39928) (xy 72.191118 -131.39928)
			(xy 72.155304 -131.42976) (xy 72.130127 -131.450613) (xy 72.075395 -131.486364) (xy 72.01653 -131.514803)
			(xy 71.954505 -131.535458) (xy 71.890343 -131.547989) (xy 71.825104 -131.552189) (xy 71.759865 -131.547989)
			(xy 71.695703 -131.535458) (xy 71.633678 -131.514803) (xy 71.574813 -131.486364) (xy 71.520081 -131.450613)
			(xy 71.494904 -131.42976) (xy 71.45909 -131.39928) (xy 71.443596 -131.39928) (xy 71.443596 -131.382262)
			(xy 71.41845 -131.34848) (xy 71.408202 -131.334638) (xy 71.389389 -131.305784) (xy 71.380858 -131.290822)
			(xy 71.372198 -131.276303) (xy 71.348611 -131.252102) (xy 71.319489 -131.234955) (xy 71.286884 -131.226068)
			(xy 71.25309 -131.226068) (xy 71.220485 -131.234955) (xy 71.191363 -131.252102) (xy 71.167776 -131.276303)
			(xy 71.159116 -131.290822) (xy 71.15058 -131.305781) (xy 71.131767 -131.334634) (xy 71.121524 -131.34848)
			(xy 71.096124 -131.382262) (xy 71.096124 -131.39928) (xy 71.080884 -131.39928) (xy 71.04507 -131.42976)
			(xy 71.019893 -131.450613) (xy 70.965161 -131.486364) (xy 70.906296 -131.514803) (xy 70.844271 -131.535458)
			(xy 70.780109 -131.547989) (xy 70.71487 -131.552189) (xy 70.649631 -131.547989) (xy 70.585469 -131.535458)
			(xy 70.523444 -131.514803) (xy 70.464579 -131.486364) (xy 70.409847 -131.450613) (xy 70.38467 -131.42976)
			(xy 70.348856 -131.39928) (xy 70.333616 -131.39928) (xy 70.333616 -131.382262) (xy 70.308216 -131.34848)
			(xy 70.294959 -131.330365) (xy 70.2713 -131.292211) (xy 70.260972 -131.27228) (xy 70.25356 -131.258534)
			(xy 70.233186 -131.234878) (xy 70.207671 -131.216886) (xy 70.178546 -131.20564) (xy 70.147561 -131.201815)
			(xy 70.116576 -131.20564) (xy 70.087451 -131.216886) (xy 70.061936 -131.234878) (xy 70.041562 -131.258534)
			(xy 70.03415 -131.27228) (xy 70.023841 -131.292222) (xy 70.000185 -131.33038) (xy 69.986906 -131.34848)
			(xy 69.96176 -131.382262) (xy 69.96176 -131.39928) (xy 69.946266 -131.39928) (xy 69.910452 -131.42976)
			(xy 69.885275 -131.450613) (xy 69.830543 -131.486364) (xy 69.771678 -131.514803) (xy 69.709653 -131.535458)
			(xy 69.645491 -131.547989) (xy 69.580252 -131.552189) (xy 69.515013 -131.547989) (xy 69.450851 -131.535458)
			(xy 69.388826 -131.514803) (xy 69.329961 -131.486364) (xy 69.275229 -131.450613) (xy 69.250052 -131.42976)
			(xy 69.214238 -131.39928) (xy 69.198744 -131.39928) (xy 69.198744 -131.382262) (xy 69.173598 -131.34848)
			(xy 69.161792 -131.332401) (xy 69.140429 -131.298709) (xy 69.130926 -131.28117) (xy 69.123355 -131.267846)
			(xy 69.102976 -131.244972) (xy 69.077729 -131.227619) (xy 69.049072 -131.21679) (xy 69.018658 -131.21311)
			(xy 68.988244 -131.21679) (xy 68.959587 -131.227619) (xy 68.93434 -131.244972) (xy 68.913961 -131.267846)
			(xy 68.90639 -131.28117) (xy 68.896896 -131.298714) (xy 68.875536 -131.332409) (xy 68.863718 -131.34848)
			(xy 68.838572 -131.382262) (xy 68.838572 -131.39928) (xy 68.823078 -131.39928) (xy 68.787264 -131.42976)
			(xy 68.762087 -131.450613) (xy 68.707355 -131.486364) (xy 68.64849 -131.514803) (xy 68.586465 -131.535458)
			(xy 68.522303 -131.547989) (xy 68.457064 -131.552189) (xy 68.391825 -131.547989) (xy 68.327663 -131.535458)
			(xy 68.265638 -131.514803) (xy 68.206773 -131.486364) (xy 68.152041 -131.450613) (xy 68.126864 -131.42976)
			(xy 68.09105 -131.39928) (xy 68.075556 -131.39928) (xy 68.075556 -131.382262) (xy 68.05041 -131.34848)
			(xy 68.031145 -131.322009) (xy 67.998885 -131.265037) (xy 67.974204 -131.204395) (xy 67.95751 -131.141088)
			(xy 67.949079 -131.076162) (xy 67.948556 -131.043426) (xy 40.074115 -131.043426) (xy 40.057826 -131.056416)
			(xy 39.997435 -131.094362) (xy 39.933176 -131.125307) (xy 39.865856 -131.148864) (xy 39.796321 -131.164734)
			(xy 39.725447 -131.17272) (xy 39.654125 -131.17272) (xy 39.583251 -131.164734) (xy 39.513716 -131.148864)
			(xy 39.446396 -131.125307) (xy 39.382137 -131.094362) (xy 39.321746 -131.056416) (xy 39.265984 -131.011947)
			(xy 39.215551 -130.961514) (xy 39.171082 -130.905752) (xy 39.133136 -130.845361) (xy 39.102191 -130.781102)
			(xy 39.078634 -130.713782) (xy 39.062764 -130.644247) (xy 39.054778 -130.573373) (xy 36.325227 -130.573373)
			(xy 36.361593 -130.632106) (xy 36.400327 -130.709895) (xy 36.431719 -130.790927) (xy 36.4555 -130.874509)
			(xy 36.471468 -130.959929) (xy 36.479486 -131.046458) (xy 36.479988 -131.089908) (xy 36.479486 -131.133358)
			(xy 36.471468 -131.219887) (xy 36.4555 -131.305307) (xy 36.431719 -131.388889) (xy 36.400327 -131.469921)
			(xy 36.361593 -131.54771) (xy 36.315846 -131.621594) (xy 36.263477 -131.690941) (xy 36.204933 -131.755161)
			(xy 36.140713 -131.813705) (xy 36.071366 -131.866074) (xy 35.997482 -131.911821) (xy 35.919693 -131.950555)
			(xy 35.838661 -131.981947) (xy 35.755079 -132.005728) (xy 35.669659 -132.021696) (xy 35.58313 -132.029714)
			(xy 35.49623 -132.029714) (xy 35.409701 -132.021696) (xy 35.324281 -132.005728) (xy 35.240699 -131.981947)
			(xy 35.159667 -131.950555) (xy 35.081878 -131.911821) (xy 35.007994 -131.866074) (xy 34.938647 -131.813705)
			(xy 34.874427 -131.755161) (xy 34.815883 -131.690941) (xy 34.763514 -131.621594) (xy 34.717767 -131.54771)
			(xy 34.679033 -131.469921) (xy 34.647641 -131.388889) (xy 34.62386 -131.305307) (xy 34.607892 -131.219887)
			(xy 34.599874 -131.133358) (xy 31.399486 -131.133358) (xy 31.391468 -131.219887) (xy 31.3755 -131.305307)
			(xy 31.351719 -131.388889) (xy 31.320327 -131.469921) (xy 31.281593 -131.54771) (xy 31.235846 -131.621594)
			(xy 31.183477 -131.690941) (xy 31.124933 -131.755161) (xy 31.060713 -131.813705) (xy 30.991366 -131.866074)
			(xy 30.917482 -131.911821) (xy 30.839693 -131.950555) (xy 30.758661 -131.981947) (xy 30.675079 -132.005728)
			(xy 30.589659 -132.021696) (xy 30.50313 -132.029714) (xy 30.41623 -132.029714) (xy 30.329701 -132.021696)
			(xy 30.244281 -132.005728) (xy 30.160699 -131.981947) (xy 30.079667 -131.950555) (xy 30.001878 -131.911821)
			(xy 29.927994 -131.866074) (xy 29.858647 -131.813705) (xy 29.794427 -131.755161) (xy 29.735883 -131.690941)
			(xy 29.683514 -131.621594) (xy 29.637767 -131.54771) (xy 29.599033 -131.469921) (xy 29.567641 -131.388889)
			(xy 29.54386 -131.305307) (xy 29.527892 -131.219887) (xy 29.519874 -131.133358) (xy 27.89936 -131.133358)
			(xy 27.89936 -133.673358) (xy 29.519874 -133.673358) (xy 29.519874 -133.586458) (xy 29.527892 -133.499929)
			(xy 29.54386 -133.414509) (xy 29.567641 -133.330927) (xy 29.599033 -133.249895) (xy 29.637767 -133.172106)
			(xy 29.683514 -133.098222) (xy 29.735883 -133.028875) (xy 29.794427 -132.964655) (xy 29.858647 -132.906111)
			(xy 29.927994 -132.853742) (xy 30.001878 -132.807995) (xy 30.079667 -132.769261) (xy 30.160699 -132.737869)
			(xy 30.244281 -132.714088) (xy 30.329701 -132.69812) (xy 30.41623 -132.690102) (xy 30.50313 -132.690102)
			(xy 30.589659 -132.69812) (xy 30.675079 -132.714088) (xy 30.758661 -132.737869) (xy 30.839693 -132.769261)
			(xy 30.917482 -132.807995) (xy 30.991366 -132.853742) (xy 31.060713 -132.906111) (xy 31.124933 -132.964655)
			(xy 31.183477 -133.028875) (xy 31.235846 -133.098222) (xy 31.281593 -133.172106) (xy 31.320327 -133.249895)
			(xy 31.351719 -133.330927) (xy 31.3755 -133.414509) (xy 31.391468 -133.499929) (xy 31.399486 -133.586458)
			(xy 31.399988 -133.629908) (xy 31.399486 -133.673358) (xy 34.599874 -133.673358) (xy 34.599874 -133.586458)
			(xy 34.607892 -133.499929) (xy 34.62386 -133.414509) (xy 34.647641 -133.330927) (xy 34.679033 -133.249895)
			(xy 34.717767 -133.172106) (xy 34.763514 -133.098222) (xy 34.815883 -133.028875) (xy 34.874427 -132.964655)
			(xy 34.938647 -132.906111) (xy 35.007994 -132.853742) (xy 35.081878 -132.807995) (xy 35.159667 -132.769261)
			(xy 35.240699 -132.737869) (xy 35.324281 -132.714088) (xy 35.409701 -132.69812) (xy 35.49623 -132.690102)
			(xy 35.58313 -132.690102) (xy 35.669659 -132.69812) (xy 35.755079 -132.714088) (xy 35.838661 -132.737869)
			(xy 35.919693 -132.769261) (xy 35.997482 -132.807995) (xy 36.071366 -132.853742) (xy 36.140713 -132.906111)
			(xy 36.204933 -132.964655) (xy 36.263477 -133.028875) (xy 36.315846 -133.098222) (xy 36.361593 -133.172106)
			(xy 36.400327 -133.249895) (xy 36.431719 -133.330927) (xy 36.4555 -133.414509) (xy 36.471468 -133.499929)
			(xy 36.479486 -133.586458) (xy 36.479988 -133.629908) (xy 36.479486 -133.673358) (xy 36.471468 -133.759887)
			(xy 36.4555 -133.845307) (xy 36.431719 -133.928889) (xy 36.400327 -134.009921) (xy 36.361593 -134.08771)
			(xy 36.315846 -134.161594) (xy 36.263477 -134.230941) (xy 36.204933 -134.295161) (xy 36.140713 -134.353705)
			(xy 36.071366 -134.406074) (xy 35.997482 -134.451821) (xy 35.919693 -134.490555) (xy 35.838661 -134.521947)
			(xy 35.755079 -134.545728) (xy 35.669659 -134.561696) (xy 35.58313 -134.569714) (xy 35.49623 -134.569714)
			(xy 35.409701 -134.561696) (xy 35.324281 -134.545728) (xy 35.240699 -134.521947) (xy 35.159667 -134.490555)
			(xy 35.081878 -134.451821) (xy 35.007994 -134.406074) (xy 34.938647 -134.353705) (xy 34.874427 -134.295161)
			(xy 34.815883 -134.230941) (xy 34.763514 -134.161594) (xy 34.717767 -134.08771) (xy 34.679033 -134.009921)
			(xy 34.647641 -133.928889) (xy 34.62386 -133.845307) (xy 34.607892 -133.759887) (xy 34.599874 -133.673358)
			(xy 31.399486 -133.673358) (xy 31.391468 -133.759887) (xy 31.3755 -133.845307) (xy 31.351719 -133.928889)
			(xy 31.320327 -134.009921) (xy 31.281593 -134.08771) (xy 31.235846 -134.161594) (xy 31.183477 -134.230941)
			(xy 31.124933 -134.295161) (xy 31.060713 -134.353705) (xy 30.991366 -134.406074) (xy 30.917482 -134.451821)
			(xy 30.839693 -134.490555) (xy 30.758661 -134.521947) (xy 30.675079 -134.545728) (xy 30.589659 -134.561696)
			(xy 30.50313 -134.569714) (xy 30.41623 -134.569714) (xy 30.329701 -134.561696) (xy 30.244281 -134.545728)
			(xy 30.160699 -134.521947) (xy 30.079667 -134.490555) (xy 30.001878 -134.451821) (xy 29.927994 -134.406074)
			(xy 29.858647 -134.353705) (xy 29.794427 -134.295161) (xy 29.735883 -134.230941) (xy 29.683514 -134.161594)
			(xy 29.637767 -134.08771) (xy 29.599033 -134.009921) (xy 29.567641 -133.928889) (xy 29.54386 -133.845307)
			(xy 29.527892 -133.759887) (xy 29.519874 -133.673358) (xy 27.89936 -133.673358) (xy 27.89936 -136.213358)
			(xy 29.519874 -136.213358) (xy 29.519874 -136.126458) (xy 29.527892 -136.039929) (xy 29.54386 -135.954509)
			(xy 29.567641 -135.870927) (xy 29.599033 -135.789895) (xy 29.637767 -135.712106) (xy 29.683514 -135.638222)
			(xy 29.735883 -135.568875) (xy 29.794427 -135.504655) (xy 29.858647 -135.446111) (xy 29.927994 -135.393742)
			(xy 30.001878 -135.347995) (xy 30.079667 -135.309261) (xy 30.160699 -135.277869) (xy 30.244281 -135.254088)
			(xy 30.329701 -135.23812) (xy 30.41623 -135.230102) (xy 30.50313 -135.230102) (xy 30.589659 -135.23812)
			(xy 30.675079 -135.254088) (xy 30.758661 -135.277869) (xy 30.839693 -135.309261) (xy 30.917482 -135.347995)
			(xy 30.991366 -135.393742) (xy 31.060713 -135.446111) (xy 31.124933 -135.504655) (xy 31.183477 -135.568875)
			(xy 31.235846 -135.638222) (xy 31.281593 -135.712106) (xy 31.320327 -135.789895) (xy 31.351719 -135.870927)
			(xy 31.3755 -135.954509) (xy 31.391468 -136.039929) (xy 31.399486 -136.126458) (xy 31.399988 -136.169908)
			(xy 31.399486 -136.213358) (xy 34.599874 -136.213358) (xy 34.599874 -136.126458) (xy 34.607892 -136.039929)
			(xy 34.62386 -135.954509) (xy 34.647641 -135.870927) (xy 34.679033 -135.789895) (xy 34.717767 -135.712106)
			(xy 34.763514 -135.638222) (xy 34.815883 -135.568875) (xy 34.874427 -135.504655) (xy 34.938647 -135.446111)
			(xy 35.007994 -135.393742) (xy 35.081878 -135.347995) (xy 35.159667 -135.309261) (xy 35.240699 -135.277869)
			(xy 35.324281 -135.254088) (xy 35.409701 -135.23812) (xy 35.49623 -135.230102) (xy 35.58313 -135.230102)
			(xy 35.669659 -135.23812) (xy 35.755079 -135.254088) (xy 35.838661 -135.277869) (xy 35.919693 -135.309261)
			(xy 35.997482 -135.347995) (xy 36.071366 -135.393742) (xy 36.140713 -135.446111) (xy 36.204933 -135.504655)
			(xy 36.263477 -135.568875) (xy 36.315846 -135.638222) (xy 36.361593 -135.712106) (xy 36.400327 -135.789895)
			(xy 36.431719 -135.870927) (xy 36.4555 -135.954509) (xy 36.471468 -136.039929) (xy 36.479486 -136.126458)
			(xy 36.479988 -136.169908) (xy 36.479486 -136.213358) (xy 36.471468 -136.299887) (xy 36.4555 -136.385307)
			(xy 36.431719 -136.468889) (xy 36.400327 -136.549921) (xy 36.361593 -136.62771) (xy 36.315846 -136.701594)
			(xy 36.263477 -136.770941) (xy 36.204933 -136.835161) (xy 36.140713 -136.893705) (xy 36.071366 -136.946074)
			(xy 35.997482 -136.991821) (xy 35.919693 -137.030555) (xy 35.838661 -137.061947) (xy 35.755079 -137.085728)
			(xy 35.669659 -137.101696) (xy 35.58313 -137.109714) (xy 35.49623 -137.109714) (xy 35.409701 -137.101696)
			(xy 35.324281 -137.085728) (xy 35.240699 -137.061947) (xy 35.159667 -137.030555) (xy 35.081878 -136.991821)
			(xy 35.007994 -136.946074) (xy 34.938647 -136.893705) (xy 34.874427 -136.835161) (xy 34.815883 -136.770941)
			(xy 34.763514 -136.701594) (xy 34.717767 -136.62771) (xy 34.679033 -136.549921) (xy 34.647641 -136.468889)
			(xy 34.62386 -136.385307) (xy 34.607892 -136.299887) (xy 34.599874 -136.213358) (xy 31.399486 -136.213358)
			(xy 31.391468 -136.299887) (xy 31.3755 -136.385307) (xy 31.351719 -136.468889) (xy 31.320327 -136.549921)
			(xy 31.281593 -136.62771) (xy 31.235846 -136.701594) (xy 31.183477 -136.770941) (xy 31.124933 -136.835161)
			(xy 31.060713 -136.893705) (xy 30.991366 -136.946074) (xy 30.917482 -136.991821) (xy 30.839693 -137.030555)
			(xy 30.758661 -137.061947) (xy 30.675079 -137.085728) (xy 30.589659 -137.101696) (xy 30.50313 -137.109714)
			(xy 30.41623 -137.109714) (xy 30.329701 -137.101696) (xy 30.244281 -137.085728) (xy 30.160699 -137.061947)
			(xy 30.079667 -137.030555) (xy 30.001878 -136.991821) (xy 29.927994 -136.946074) (xy 29.858647 -136.893705)
			(xy 29.794427 -136.835161) (xy 29.735883 -136.770941) (xy 29.683514 -136.701594) (xy 29.637767 -136.62771)
			(xy 29.599033 -136.549921) (xy 29.567641 -136.468889) (xy 29.54386 -136.385307) (xy 29.527892 -136.299887)
			(xy 29.519874 -136.213358) (xy 27.89936 -136.213358) (xy 27.89936 -138.753358) (xy 29.519874 -138.753358)
			(xy 29.519874 -138.666458) (xy 29.527892 -138.579929) (xy 29.54386 -138.494509) (xy 29.567641 -138.410927)
			(xy 29.599033 -138.329895) (xy 29.637767 -138.252106) (xy 29.683514 -138.178222) (xy 29.735883 -138.108875)
			(xy 29.794427 -138.044655) (xy 29.858647 -137.986111) (xy 29.927994 -137.933742) (xy 30.001878 -137.887995)
			(xy 30.079667 -137.849261) (xy 30.160699 -137.817869) (xy 30.244281 -137.794088) (xy 30.329701 -137.77812)
			(xy 30.41623 -137.770102) (xy 30.50313 -137.770102) (xy 30.589659 -137.77812) (xy 30.675079 -137.794088)
			(xy 30.758661 -137.817869) (xy 30.839693 -137.849261) (xy 30.917482 -137.887995) (xy 30.991366 -137.933742)
			(xy 31.060713 -137.986111) (xy 31.124933 -138.044655) (xy 31.183477 -138.108875) (xy 31.235846 -138.178222)
			(xy 31.281593 -138.252106) (xy 31.320327 -138.329895) (xy 31.351719 -138.410927) (xy 31.3755 -138.494509)
			(xy 31.391468 -138.579929) (xy 31.399486 -138.666458) (xy 31.399988 -138.709908) (xy 31.399486 -138.753358)
			(xy 34.599874 -138.753358) (xy 34.599874 -138.666458) (xy 34.607892 -138.579929) (xy 34.62386 -138.494509)
			(xy 34.647641 -138.410927) (xy 34.679033 -138.329895) (xy 34.717767 -138.252106) (xy 34.763514 -138.178222)
			(xy 34.815883 -138.108875) (xy 34.874427 -138.044655) (xy 34.938647 -137.986111) (xy 35.007994 -137.933742)
			(xy 35.081878 -137.887995) (xy 35.159667 -137.849261) (xy 35.240699 -137.817869) (xy 35.324281 -137.794088)
			(xy 35.409701 -137.77812) (xy 35.49623 -137.770102) (xy 35.58313 -137.770102) (xy 35.669659 -137.77812)
			(xy 35.755079 -137.794088) (xy 35.838661 -137.817869) (xy 35.919693 -137.849261) (xy 35.997482 -137.887995)
			(xy 36.071366 -137.933742) (xy 36.140713 -137.986111) (xy 36.204933 -138.044655) (xy 36.263477 -138.108875)
			(xy 36.315846 -138.178222) (xy 36.361593 -138.252106) (xy 36.400327 -138.329895) (xy 36.431719 -138.410927)
			(xy 36.4555 -138.494509) (xy 36.471468 -138.579929) (xy 36.479486 -138.666458) (xy 36.479988 -138.709908)
			(xy 36.479486 -138.753358) (xy 36.471468 -138.839887) (xy 36.4555 -138.925307) (xy 36.431719 -139.008889)
			(xy 36.400327 -139.089921) (xy 36.361593 -139.16771) (xy 36.315846 -139.241594) (xy 36.263477 -139.310941)
			(xy 36.204933 -139.375161) (xy 36.140713 -139.433705) (xy 36.071366 -139.486074) (xy 35.997482 -139.531821)
			(xy 35.919693 -139.570555) (xy 35.838661 -139.601947) (xy 35.755079 -139.625728) (xy 35.669659 -139.641696)
			(xy 35.58313 -139.649714) (xy 35.49623 -139.649714) (xy 35.409701 -139.641696) (xy 35.324281 -139.625728)
			(xy 35.240699 -139.601947) (xy 35.159667 -139.570555) (xy 35.081878 -139.531821) (xy 35.007994 -139.486074)
			(xy 34.938647 -139.433705) (xy 34.874427 -139.375161) (xy 34.815883 -139.310941) (xy 34.763514 -139.241594)
			(xy 34.717767 -139.16771) (xy 34.679033 -139.089921) (xy 34.647641 -139.008889) (xy 34.62386 -138.925307)
			(xy 34.607892 -138.839887) (xy 34.599874 -138.753358) (xy 31.399486 -138.753358) (xy 31.391468 -138.839887)
			(xy 31.3755 -138.925307) (xy 31.351719 -139.008889) (xy 31.320327 -139.089921) (xy 31.281593 -139.16771)
			(xy 31.235846 -139.241594) (xy 31.183477 -139.310941) (xy 31.124933 -139.375161) (xy 31.060713 -139.433705)
			(xy 30.991366 -139.486074) (xy 30.917482 -139.531821) (xy 30.839693 -139.570555) (xy 30.758661 -139.601947)
			(xy 30.675079 -139.625728) (xy 30.589659 -139.641696) (xy 30.50313 -139.649714) (xy 30.41623 -139.649714)
			(xy 30.329701 -139.641696) (xy 30.244281 -139.625728) (xy 30.160699 -139.601947) (xy 30.079667 -139.570555)
			(xy 30.001878 -139.531821) (xy 29.927994 -139.486074) (xy 29.858647 -139.433705) (xy 29.794427 -139.375161)
			(xy 29.735883 -139.310941) (xy 29.683514 -139.241594) (xy 29.637767 -139.16771) (xy 29.599033 -139.089921)
			(xy 29.567641 -139.008889) (xy 29.54386 -138.925307) (xy 29.527892 -138.839887) (xy 29.519874 -138.753358)
			(xy 27.89936 -138.753358) (xy 27.89936 -140.26007) (xy 39.818317 -140.26007) (xy 39.822324 -140.144046)
			(xy 39.834326 -140.028574) (xy 39.854266 -139.914206) (xy 39.882049 -139.801486) (xy 39.917543 -139.690952)
			(xy 39.960578 -139.583129) (xy 40.010949 -139.478532) (xy 40.068416 -139.37766) (xy 40.132706 -139.280993)
			(xy 40.203511 -139.188992) (xy 40.280495 -139.102095) (xy 40.363291 -139.020716) (xy 40.451504 -138.945243)
			(xy 40.544714 -138.876036) (xy 40.642477 -138.813424) (xy 40.744326 -138.757707) (xy 40.849776 -138.709149)
			(xy 40.958325 -138.667981) (xy 41.069456 -138.634401) (xy 41.182639 -138.608568) (xy 41.297334 -138.590605)
			(xy 41.412996 -138.580597) (xy 41.529072 -138.578594) (xy 41.64501 -138.584603) (xy 41.760257 -138.598596)
			(xy 41.874263 -138.620507) (xy 41.986487 -138.650232) (xy 42.096393 -138.687628) (xy 42.203456 -138.732517)
			(xy 42.307168 -138.784686) (xy 42.407033 -138.843886) (xy 42.502576 -138.909835) (xy 42.502858 -138.91006)
			(xy 43.327831 -138.91006) (xy 43.331866 -138.834356) (xy 43.343925 -138.759511) (xy 43.363871 -138.68637)
			(xy 43.391478 -138.615765) (xy 43.426434 -138.548494) (xy 43.468342 -138.485319) (xy 43.516728 -138.426957)
			(xy 43.571044 -138.374069) (xy 43.630673 -138.327254) (xy 43.694941 -138.287042) (xy 43.763118 -138.25389)
			(xy 43.834434 -138.228172) (xy 43.908079 -138.21018) (xy 43.983219 -138.200118) (xy 44.059003 -138.198099)
			(xy 44.134573 -138.204148) (xy 44.209071 -138.218195) (xy 44.281654 -138.240081) (xy 44.3515 -138.269558)
			(xy 44.417817 -138.306293) (xy 44.479853 -138.349868) (xy 44.536906 -138.39979) (xy 44.58833 -138.455494)
			(xy 44.633541 -138.516349) (xy 44.672028 -138.581664) (xy 44.703354 -138.6507) (xy 44.727164 -138.722675)
			(xy 44.743189 -138.796773) (xy 44.751248 -138.872154) (xy 44.751752 -138.91006) (xy 45.867831 -138.91006)
			(xy 45.871866 -138.834356) (xy 45.883925 -138.759511) (xy 45.903871 -138.68637) (xy 45.931478 -138.615765)
			(xy 45.966434 -138.548494) (xy 46.008342 -138.485319) (xy 46.056728 -138.426957) (xy 46.111044 -138.374069)
			(xy 46.170673 -138.327254) (xy 46.234941 -138.287042) (xy 46.303118 -138.25389) (xy 46.374434 -138.228172)
			(xy 46.448079 -138.21018) (xy 46.523219 -138.200118) (xy 46.599003 -138.198099) (xy 46.674573 -138.204148)
			(xy 46.749071 -138.218195) (xy 46.821654 -138.240081) (xy 46.8915 -138.269558) (xy 46.957817 -138.306293)
			(xy 47.019853 -138.349868) (xy 47.076906 -138.39979) (xy 47.12833 -138.455494) (xy 47.173541 -138.516349)
			(xy 47.212028 -138.581664) (xy 47.243354 -138.6507) (xy 47.267164 -138.722675) (xy 47.283189 -138.796773)
			(xy 47.291248 -138.872154) (xy 47.291752 -138.91006) (xy 48.407831 -138.91006) (xy 48.411866 -138.834356)
			(xy 48.423925 -138.759511) (xy 48.443871 -138.68637) (xy 48.471478 -138.615765) (xy 48.506434 -138.548494)
			(xy 48.548342 -138.485319) (xy 48.596728 -138.426957) (xy 48.651044 -138.374069) (xy 48.710673 -138.327254)
			(xy 48.774941 -138.287042) (xy 48.843118 -138.25389) (xy 48.914434 -138.228172) (xy 48.988079 -138.21018)
			(xy 49.063219 -138.200118) (xy 49.139003 -138.198099) (xy 49.214573 -138.204148) (xy 49.289071 -138.218195)
			(xy 49.361654 -138.240081) (xy 49.4315 -138.269558) (xy 49.497817 -138.306293) (xy 49.559853 -138.349868)
			(xy 49.616906 -138.39979) (xy 49.66833 -138.455494) (xy 49.713541 -138.516349) (xy 49.752028 -138.581664)
			(xy 49.783354 -138.6507) (xy 49.807164 -138.722675) (xy 49.823189 -138.796773) (xy 49.831248 -138.872154)
			(xy 49.831752 -138.91006) (xy 50.947831 -138.91006) (xy 50.951866 -138.834356) (xy 50.963925 -138.759511)
			(xy 50.983871 -138.68637) (xy 51.011478 -138.615765) (xy 51.046434 -138.548494) (xy 51.088342 -138.485319)
			(xy 51.136728 -138.426957) (xy 51.191044 -138.374069) (xy 51.250673 -138.327254) (xy 51.314941 -138.287042)
			(xy 51.383118 -138.25389) (xy 51.454434 -138.228172) (xy 51.528079 -138.21018) (xy 51.603219 -138.200118)
			(xy 51.679003 -138.198099) (xy 51.754573 -138.204148) (xy 51.829071 -138.218195) (xy 51.901654 -138.240081)
			(xy 51.9715 -138.269558) (xy 52.037817 -138.306293) (xy 52.099853 -138.349868) (xy 52.156906 -138.39979)
			(xy 52.20833 -138.455494) (xy 52.253541 -138.516349) (xy 52.292028 -138.581664) (xy 52.323354 -138.6507)
			(xy 52.347164 -138.722675) (xy 52.363189 -138.796773) (xy 52.371248 -138.872154) (xy 52.371752 -138.91006)
			(xy 53.487831 -138.91006) (xy 53.491866 -138.834356) (xy 53.503925 -138.759511) (xy 53.523871 -138.68637)
			(xy 53.551478 -138.615765) (xy 53.586434 -138.548494) (xy 53.628342 -138.485319) (xy 53.676728 -138.426957)
			(xy 53.731044 -138.374069) (xy 53.790673 -138.327254) (xy 53.854941 -138.287042) (xy 53.923118 -138.25389)
			(xy 53.994434 -138.228172) (xy 54.068079 -138.21018) (xy 54.143219 -138.200118) (xy 54.219003 -138.198099)
			(xy 54.294573 -138.204148) (xy 54.369071 -138.218195) (xy 54.441654 -138.240081) (xy 54.5115 -138.269558)
			(xy 54.577817 -138.306293) (xy 54.639853 -138.349868) (xy 54.696906 -138.39979) (xy 54.74833 -138.455494)
			(xy 54.793541 -138.516349) (xy 54.832028 -138.581664) (xy 54.863354 -138.6507) (xy 54.887164 -138.722675)
			(xy 54.903189 -138.796773) (xy 54.911248 -138.872154) (xy 54.911752 -138.91006) (xy 56.027831 -138.91006)
			(xy 56.031866 -138.834356) (xy 56.043925 -138.759511) (xy 56.063871 -138.68637) (xy 56.091478 -138.615765)
			(xy 56.126434 -138.548494) (xy 56.168342 -138.485319) (xy 56.216728 -138.426957) (xy 56.271044 -138.374069)
			(xy 56.330673 -138.327254) (xy 56.394941 -138.287042) (xy 56.463118 -138.25389) (xy 56.534434 -138.228172)
			(xy 56.608079 -138.21018) (xy 56.683219 -138.200118) (xy 56.759003 -138.198099) (xy 56.834573 -138.204148)
			(xy 56.909071 -138.218195) (xy 56.981654 -138.240081) (xy 57.0515 -138.269558) (xy 57.117817 -138.306293)
			(xy 57.179853 -138.349868) (xy 57.236906 -138.39979) (xy 57.28833 -138.455494) (xy 57.333541 -138.516349)
			(xy 57.372028 -138.581664) (xy 57.403354 -138.6507) (xy 57.427164 -138.722675) (xy 57.443189 -138.796773)
			(xy 57.451248 -138.872154) (xy 57.451752 -138.91006) (xy 58.567831 -138.91006) (xy 58.571866 -138.834356)
			(xy 58.583925 -138.759511) (xy 58.603871 -138.68637) (xy 58.631478 -138.615765) (xy 58.666434 -138.548494)
			(xy 58.708342 -138.485319) (xy 58.756728 -138.426957) (xy 58.811044 -138.374069) (xy 58.870673 -138.327254)
			(xy 58.934941 -138.287042) (xy 59.003118 -138.25389) (xy 59.074434 -138.228172) (xy 59.148079 -138.21018)
			(xy 59.223219 -138.200118) (xy 59.299003 -138.198099) (xy 59.374573 -138.204148) (xy 59.449071 -138.218195)
			(xy 59.521654 -138.240081) (xy 59.5915 -138.269558) (xy 59.657817 -138.306293) (xy 59.719853 -138.349868)
			(xy 59.776906 -138.39979) (xy 59.82833 -138.455494) (xy 59.873541 -138.516349) (xy 59.912028 -138.581664)
			(xy 59.943354 -138.6507) (xy 59.967164 -138.722675) (xy 59.983189 -138.796773) (xy 59.991248 -138.872154)
			(xy 59.991752 -138.91006) (xy 61.107831 -138.91006) (xy 61.111866 -138.834356) (xy 61.123925 -138.759511)
			(xy 61.143871 -138.68637) (xy 61.171478 -138.615765) (xy 61.206434 -138.548494) (xy 61.248342 -138.485319)
			(xy 61.296728 -138.426957) (xy 61.351044 -138.374069) (xy 61.410673 -138.327254) (xy 61.474941 -138.287042)
			(xy 61.543118 -138.25389) (xy 61.614434 -138.228172) (xy 61.688079 -138.21018) (xy 61.763219 -138.200118)
			(xy 61.839003 -138.198099) (xy 61.914573 -138.204148) (xy 61.989071 -138.218195) (xy 62.061654 -138.240081)
			(xy 62.1315 -138.269558) (xy 62.197817 -138.306293) (xy 62.259853 -138.349868) (xy 62.265798 -138.35507)
			(xy 86.197951 -138.35507) (xy 86.201986 -138.279366) (xy 86.214045 -138.204521) (xy 86.233991 -138.13138)
			(xy 86.261598 -138.060775) (xy 86.296554 -137.993504) (xy 86.338462 -137.930329) (xy 86.386848 -137.871967)
			(xy 86.441164 -137.819079) (xy 86.500793 -137.772264) (xy 86.565061 -137.732052) (xy 86.633238 -137.6989)
			(xy 86.704554 -137.673182) (xy 86.778199 -137.65519) (xy 86.853339 -137.645128) (xy 86.929123 -137.643109)
			(xy 87.004693 -137.649158) (xy 87.079191 -137.663205) (xy 87.151774 -137.685091) (xy 87.22162 -137.714568)
			(xy 87.287937 -137.751303) (xy 87.349973 -137.794878) (xy 87.407026 -137.8448) (xy 87.45845 -137.900504)
			(xy 87.503661 -137.961359) (xy 87.542148 -138.026674) (xy 87.573474 -138.09571) (xy 87.597284 -138.167685)
			(xy 87.613309 -138.241783) (xy 87.621368 -138.317164) (xy 87.621872 -138.35507) (xy 88.737951 -138.35507)
			(xy 88.741986 -138.279366) (xy 88.754045 -138.204521) (xy 88.773991 -138.13138) (xy 88.801598 -138.060775)
			(xy 88.836554 -137.993504) (xy 88.878462 -137.930329) (xy 88.926848 -137.871967) (xy 88.981164 -137.819079)
			(xy 89.040793 -137.772264) (xy 89.105061 -137.732052) (xy 89.173238 -137.6989) (xy 89.244554 -137.673182)
			(xy 89.318199 -137.65519) (xy 89.393339 -137.645128) (xy 89.469123 -137.643109) (xy 89.544693 -137.649158)
			(xy 89.619191 -137.663205) (xy 89.691774 -137.685091) (xy 89.76162 -137.714568) (xy 89.827937 -137.751303)
			(xy 89.889973 -137.794878) (xy 89.947026 -137.8448) (xy 89.99845 -137.900504) (xy 90.043661 -137.961359)
			(xy 90.082148 -138.026674) (xy 90.113474 -138.09571) (xy 90.137284 -138.167685) (xy 90.153309 -138.241783)
			(xy 90.161368 -138.317164) (xy 90.161872 -138.35507) (xy 91.277951 -138.35507) (xy 91.281986 -138.279366)
			(xy 91.294045 -138.204521) (xy 91.313991 -138.13138) (xy 91.341598 -138.060775) (xy 91.376554 -137.993504)
			(xy 91.418462 -137.930329) (xy 91.466848 -137.871967) (xy 91.521164 -137.819079) (xy 91.580793 -137.772264)
			(xy 91.645061 -137.732052) (xy 91.713238 -137.6989) (xy 91.784554 -137.673182) (xy 91.858199 -137.65519)
			(xy 91.933339 -137.645128) (xy 92.009123 -137.643109) (xy 92.084693 -137.649158) (xy 92.159191 -137.663205)
			(xy 92.231774 -137.685091) (xy 92.30162 -137.714568) (xy 92.367937 -137.751303) (xy 92.429973 -137.794878)
			(xy 92.487026 -137.8448) (xy 92.53845 -137.900504) (xy 92.583661 -137.961359) (xy 92.622148 -138.026674)
			(xy 92.653474 -138.09571) (xy 92.677284 -138.167685) (xy 92.693309 -138.241783) (xy 92.701368 -138.317164)
			(xy 92.701872 -138.35507) (xy 92.701368 -138.392976) (xy 92.693309 -138.468357) (xy 92.677284 -138.542455)
			(xy 92.653474 -138.61443) (xy 92.622148 -138.683466) (xy 92.583661 -138.748781) (xy 92.53845 -138.809636)
			(xy 92.487026 -138.86534) (xy 92.429973 -138.915262) (xy 92.367937 -138.958837) (xy 92.30162 -138.995572)
			(xy 92.231774 -139.025049) (xy 92.159191 -139.046935) (xy 92.084693 -139.060982) (xy 92.009123 -139.067031)
			(xy 91.933339 -139.065012) (xy 91.858199 -139.05495) (xy 91.784554 -139.036958) (xy 91.713238 -139.01124)
			(xy 91.645061 -138.978088) (xy 91.580793 -138.937876) (xy 91.521164 -138.891061) (xy 91.466848 -138.838173)
			(xy 91.418462 -138.779811) (xy 91.376554 -138.716636) (xy 91.341598 -138.649365) (xy 91.313991 -138.57876)
			(xy 91.294045 -138.505619) (xy 91.281986 -138.430774) (xy 91.277951 -138.35507) (xy 90.161872 -138.35507)
			(xy 90.161368 -138.392976) (xy 90.153309 -138.468357) (xy 90.137284 -138.542455) (xy 90.113474 -138.61443)
			(xy 90.082148 -138.683466) (xy 90.043661 -138.748781) (xy 89.99845 -138.809636) (xy 89.947026 -138.86534)
			(xy 89.889973 -138.915262) (xy 89.827937 -138.958837) (xy 89.76162 -138.995572) (xy 89.691774 -139.025049)
			(xy 89.619191 -139.046935) (xy 89.544693 -139.060982) (xy 89.469123 -139.067031) (xy 89.393339 -139.065012)
			(xy 89.318199 -139.05495) (xy 89.244554 -139.036958) (xy 89.173238 -139.01124) (xy 89.105061 -138.978088)
			(xy 89.040793 -138.937876) (xy 88.981164 -138.891061) (xy 88.926848 -138.838173) (xy 88.878462 -138.779811)
			(xy 88.836554 -138.716636) (xy 88.801598 -138.649365) (xy 88.773991 -138.57876) (xy 88.754045 -138.505619)
			(xy 88.741986 -138.430774) (xy 88.737951 -138.35507) (xy 87.621872 -138.35507) (xy 87.621368 -138.392976)
			(xy 87.613309 -138.468357) (xy 87.597284 -138.542455) (xy 87.573474 -138.61443) (xy 87.542148 -138.683466)
			(xy 87.503661 -138.748781) (xy 87.45845 -138.809636) (xy 87.407026 -138.86534) (xy 87.349973 -138.915262)
			(xy 87.287937 -138.958837) (xy 87.22162 -138.995572) (xy 87.151774 -139.025049) (xy 87.079191 -139.046935)
			(xy 87.004693 -139.060982) (xy 86.929123 -139.067031) (xy 86.853339 -139.065012) (xy 86.778199 -139.05495)
			(xy 86.704554 -139.036958) (xy 86.633238 -139.01124) (xy 86.565061 -138.978088) (xy 86.500793 -138.937876)
			(xy 86.441164 -138.891061) (xy 86.386848 -138.838173) (xy 86.338462 -138.779811) (xy 86.296554 -138.716636)
			(xy 86.261598 -138.649365) (xy 86.233991 -138.57876) (xy 86.214045 -138.505619) (xy 86.201986 -138.430774)
			(xy 86.197951 -138.35507) (xy 62.265798 -138.35507) (xy 62.316906 -138.39979) (xy 62.36833 -138.455494)
			(xy 62.413541 -138.516349) (xy 62.452028 -138.581664) (xy 62.483354 -138.6507) (xy 62.507164 -138.722675)
			(xy 62.523189 -138.796773) (xy 62.531248 -138.872154) (xy 62.531752 -138.91006) (xy 62.531248 -138.947966)
			(xy 62.523189 -139.023347) (xy 62.507164 -139.097445) (xy 62.483354 -139.16942) (xy 62.452028 -139.238456)
			(xy 62.413541 -139.303771) (xy 62.36833 -139.364626) (xy 62.316906 -139.42033) (xy 62.259853 -139.470252)
			(xy 62.197817 -139.513827) (xy 62.1315 -139.550562) (xy 62.061654 -139.580039) (xy 61.989071 -139.601925)
			(xy 61.914573 -139.615972) (xy 61.839003 -139.622021) (xy 61.763219 -139.620002) (xy 61.688079 -139.60994)
			(xy 61.614434 -139.591948) (xy 61.543118 -139.56623) (xy 61.474941 -139.533078) (xy 61.410673 -139.492866)
			(xy 61.351044 -139.446051) (xy 61.296728 -139.393163) (xy 61.248342 -139.334801) (xy 61.206434 -139.271626)
			(xy 61.171478 -139.204355) (xy 61.143871 -139.13375) (xy 61.123925 -139.060609) (xy 61.111866 -138.985764)
			(xy 61.107831 -138.91006) (xy 59.991752 -138.91006) (xy 59.991248 -138.947966) (xy 59.983189 -139.023347)
			(xy 59.967164 -139.097445) (xy 59.943354 -139.16942) (xy 59.912028 -139.238456) (xy 59.873541 -139.303771)
			(xy 59.82833 -139.364626) (xy 59.776906 -139.42033) (xy 59.719853 -139.470252) (xy 59.657817 -139.513827)
			(xy 59.5915 -139.550562) (xy 59.521654 -139.580039) (xy 59.449071 -139.601925) (xy 59.374573 -139.615972)
			(xy 59.299003 -139.622021) (xy 59.223219 -139.620002) (xy 59.148079 -139.60994) (xy 59.074434 -139.591948)
			(xy 59.003118 -139.56623) (xy 58.934941 -139.533078) (xy 58.870673 -139.492866) (xy 58.811044 -139.446051)
			(xy 58.756728 -139.393163) (xy 58.708342 -139.334801) (xy 58.666434 -139.271626) (xy 58.631478 -139.204355)
			(xy 58.603871 -139.13375) (xy 58.583925 -139.060609) (xy 58.571866 -138.985764) (xy 58.567831 -138.91006)
			(xy 57.451752 -138.91006) (xy 57.451248 -138.947966) (xy 57.443189 -139.023347) (xy 57.427164 -139.097445)
			(xy 57.403354 -139.16942) (xy 57.372028 -139.238456) (xy 57.333541 -139.303771) (xy 57.28833 -139.364626)
			(xy 57.236906 -139.42033) (xy 57.179853 -139.470252) (xy 57.117817 -139.513827) (xy 57.0515 -139.550562)
			(xy 56.981654 -139.580039) (xy 56.909071 -139.601925) (xy 56.834573 -139.615972) (xy 56.759003 -139.622021)
			(xy 56.683219 -139.620002) (xy 56.608079 -139.60994) (xy 56.534434 -139.591948) (xy 56.463118 -139.56623)
			(xy 56.394941 -139.533078) (xy 56.330673 -139.492866) (xy 56.271044 -139.446051) (xy 56.216728 -139.393163)
			(xy 56.168342 -139.334801) (xy 56.126434 -139.271626) (xy 56.091478 -139.204355) (xy 56.063871 -139.13375)
			(xy 56.043925 -139.060609) (xy 56.031866 -138.985764) (xy 56.027831 -138.91006) (xy 54.911752 -138.91006)
			(xy 54.911248 -138.947966) (xy 54.903189 -139.023347) (xy 54.887164 -139.097445) (xy 54.863354 -139.16942)
			(xy 54.832028 -139.238456) (xy 54.793541 -139.303771) (xy 54.74833 -139.364626) (xy 54.696906 -139.42033)
			(xy 54.639853 -139.470252) (xy 54.577817 -139.513827) (xy 54.5115 -139.550562) (xy 54.441654 -139.580039)
			(xy 54.369071 -139.601925) (xy 54.294573 -139.615972) (xy 54.219003 -139.622021) (xy 54.143219 -139.620002)
			(xy 54.068079 -139.60994) (xy 53.994434 -139.591948) (xy 53.923118 -139.56623) (xy 53.854941 -139.533078)
			(xy 53.790673 -139.492866) (xy 53.731044 -139.446051) (xy 53.676728 -139.393163) (xy 53.628342 -139.334801)
			(xy 53.586434 -139.271626) (xy 53.551478 -139.204355) (xy 53.523871 -139.13375) (xy 53.503925 -139.060609)
			(xy 53.491866 -138.985764) (xy 53.487831 -138.91006) (xy 52.371752 -138.91006) (xy 52.371248 -138.947966)
			(xy 52.363189 -139.023347) (xy 52.347164 -139.097445) (xy 52.323354 -139.16942) (xy 52.292028 -139.238456)
			(xy 52.253541 -139.303771) (xy 52.20833 -139.364626) (xy 52.156906 -139.42033) (xy 52.099853 -139.470252)
			(xy 52.037817 -139.513827) (xy 51.9715 -139.550562) (xy 51.901654 -139.580039) (xy 51.829071 -139.601925)
			(xy 51.754573 -139.615972) (xy 51.679003 -139.622021) (xy 51.603219 -139.620002) (xy 51.528079 -139.60994)
			(xy 51.454434 -139.591948) (xy 51.383118 -139.56623) (xy 51.314941 -139.533078) (xy 51.250673 -139.492866)
			(xy 51.191044 -139.446051) (xy 51.136728 -139.393163) (xy 51.088342 -139.334801) (xy 51.046434 -139.271626)
			(xy 51.011478 -139.204355) (xy 50.983871 -139.13375) (xy 50.963925 -139.060609) (xy 50.951866 -138.985764)
			(xy 50.947831 -138.91006) (xy 49.831752 -138.91006) (xy 49.831248 -138.947966) (xy 49.823189 -139.023347)
			(xy 49.807164 -139.097445) (xy 49.783354 -139.16942) (xy 49.752028 -139.238456) (xy 49.713541 -139.303771)
			(xy 49.66833 -139.364626) (xy 49.616906 -139.42033) (xy 49.559853 -139.470252) (xy 49.497817 -139.513827)
			(xy 49.4315 -139.550562) (xy 49.361654 -139.580039) (xy 49.289071 -139.601925) (xy 49.214573 -139.615972)
			(xy 49.139003 -139.622021) (xy 49.063219 -139.620002) (xy 48.988079 -139.60994) (xy 48.914434 -139.591948)
			(xy 48.843118 -139.56623) (xy 48.774941 -139.533078) (xy 48.710673 -139.492866) (xy 48.651044 -139.446051)
			(xy 48.596728 -139.393163) (xy 48.548342 -139.334801) (xy 48.506434 -139.271626) (xy 48.471478 -139.204355)
			(xy 48.443871 -139.13375) (xy 48.423925 -139.060609) (xy 48.411866 -138.985764) (xy 48.407831 -138.91006)
			(xy 47.291752 -138.91006) (xy 47.291248 -138.947966) (xy 47.283189 -139.023347) (xy 47.267164 -139.097445)
			(xy 47.243354 -139.16942) (xy 47.212028 -139.238456) (xy 47.173541 -139.303771) (xy 47.12833 -139.364626)
			(xy 47.076906 -139.42033) (xy 47.019853 -139.470252) (xy 46.957817 -139.513827) (xy 46.8915 -139.550562)
			(xy 46.821654 -139.580039) (xy 46.749071 -139.601925) (xy 46.674573 -139.615972) (xy 46.599003 -139.622021)
			(xy 46.523219 -139.620002) (xy 46.448079 -139.60994) (xy 46.374434 -139.591948) (xy 46.303118 -139.56623)
			(xy 46.234941 -139.533078) (xy 46.170673 -139.492866) (xy 46.111044 -139.446051) (xy 46.056728 -139.393163)
			(xy 46.008342 -139.334801) (xy 45.966434 -139.271626) (xy 45.931478 -139.204355) (xy 45.903871 -139.13375)
			(xy 45.883925 -139.060609) (xy 45.871866 -138.985764) (xy 45.867831 -138.91006) (xy 44.751752 -138.91006)
			(xy 44.751248 -138.947966) (xy 44.743189 -139.023347) (xy 44.727164 -139.097445) (xy 44.703354 -139.16942)
			(xy 44.672028 -139.238456) (xy 44.633541 -139.303771) (xy 44.58833 -139.364626) (xy 44.536906 -139.42033)
			(xy 44.479853 -139.470252) (xy 44.417817 -139.513827) (xy 44.3515 -139.550562) (xy 44.281654 -139.580039)
			(xy 44.209071 -139.601925) (xy 44.134573 -139.615972) (xy 44.059003 -139.622021) (xy 43.983219 -139.620002)
			(xy 43.908079 -139.60994) (xy 43.834434 -139.591948) (xy 43.763118 -139.56623) (xy 43.694941 -139.533078)
			(xy 43.630673 -139.492866) (xy 43.571044 -139.446051) (xy 43.516728 -139.393163) (xy 43.468342 -139.334801)
			(xy 43.426434 -139.271626) (xy 43.391478 -139.204355) (xy 43.363871 -139.13375) (xy 43.343925 -139.060609)
			(xy 43.331866 -138.985764) (xy 43.327831 -138.91006) (xy 42.502858 -138.91006) (xy 42.593342 -138.982218)
			(xy 42.678897 -139.060691) (xy 42.758835 -139.144879) (xy 42.832774 -139.234381) (xy 42.900362 -139.328772)
			(xy 42.961276 -139.4276) (xy 43.015228 -139.530396) (xy 43.056858 -139.62507) (xy 84.927951 -139.62507)
			(xy 84.931986 -139.549366) (xy 84.944045 -139.474521) (xy 84.963991 -139.40138) (xy 84.991598 -139.330775)
			(xy 85.026554 -139.263504) (xy 85.068462 -139.200329) (xy 85.116848 -139.141967) (xy 85.171164 -139.089079)
			(xy 85.230793 -139.042264) (xy 85.295061 -139.002052) (xy 85.363238 -138.9689) (xy 85.434554 -138.943182)
			(xy 85.508199 -138.92519) (xy 85.583339 -138.915128) (xy 85.659123 -138.913109) (xy 85.734693 -138.919158)
			(xy 85.809191 -138.933205) (xy 85.881774 -138.955091) (xy 85.95162 -138.984568) (xy 86.017937 -139.021303)
			(xy 86.079973 -139.064878) (xy 86.137026 -139.1148) (xy 86.18845 -139.170504) (xy 86.233661 -139.231359)
			(xy 86.272148 -139.296674) (xy 86.303474 -139.36571) (xy 86.327284 -139.437685) (xy 86.343309 -139.511783)
			(xy 86.351368 -139.587164) (xy 86.351872 -139.62507) (xy 87.467951 -139.62507) (xy 87.471986 -139.549366)
			(xy 87.484045 -139.474521) (xy 87.503991 -139.40138) (xy 87.531598 -139.330775) (xy 87.566554 -139.263504)
			(xy 87.608462 -139.200329) (xy 87.656848 -139.141967) (xy 87.711164 -139.089079) (xy 87.770793 -139.042264)
			(xy 87.835061 -139.002052) (xy 87.903238 -138.9689) (xy 87.974554 -138.943182) (xy 88.048199 -138.92519)
			(xy 88.123339 -138.915128) (xy 88.199123 -138.913109) (xy 88.274693 -138.919158) (xy 88.349191 -138.933205)
			(xy 88.421774 -138.955091) (xy 88.49162 -138.984568) (xy 88.557937 -139.021303) (xy 88.619973 -139.064878)
			(xy 88.677026 -139.1148) (xy 88.72845 -139.170504) (xy 88.773661 -139.231359) (xy 88.812148 -139.296674)
			(xy 88.843474 -139.36571) (xy 88.867284 -139.437685) (xy 88.883309 -139.511783) (xy 88.891368 -139.587164)
			(xy 88.891872 -139.62507) (xy 90.007951 -139.62507) (xy 90.011986 -139.549366) (xy 90.024045 -139.474521)
			(xy 90.043991 -139.40138) (xy 90.071598 -139.330775) (xy 90.106554 -139.263504) (xy 90.148462 -139.200329)
			(xy 90.196848 -139.141967) (xy 90.251164 -139.089079) (xy 90.310793 -139.042264) (xy 90.375061 -139.002052)
			(xy 90.443238 -138.9689) (xy 90.514554 -138.943182) (xy 90.588199 -138.92519) (xy 90.663339 -138.915128)
			(xy 90.739123 -138.913109) (xy 90.814693 -138.919158) (xy 90.889191 -138.933205) (xy 90.961774 -138.955091)
			(xy 91.03162 -138.984568) (xy 91.097937 -139.021303) (xy 91.159973 -139.064878) (xy 91.217026 -139.1148)
			(xy 91.26845 -139.170504) (xy 91.313661 -139.231359) (xy 91.352148 -139.296674) (xy 91.383474 -139.36571)
			(xy 91.407284 -139.437685) (xy 91.423309 -139.511783) (xy 91.431368 -139.587164) (xy 91.431872 -139.62507)
			(xy 91.431368 -139.662976) (xy 91.423309 -139.738357) (xy 91.407284 -139.812455) (xy 91.383474 -139.88443)
			(xy 91.352148 -139.953466) (xy 91.313661 -140.018781) (xy 91.26845 -140.079636) (xy 91.217026 -140.13534)
			(xy 91.159973 -140.185262) (xy 91.097937 -140.228837) (xy 91.03162 -140.265572) (xy 90.961774 -140.295049)
			(xy 90.889191 -140.316935) (xy 90.814693 -140.330982) (xy 90.739123 -140.337031) (xy 90.663339 -140.335012)
			(xy 90.588199 -140.32495) (xy 90.514554 -140.306958) (xy 90.443238 -140.28124) (xy 90.375061 -140.248088)
			(xy 90.310793 -140.207876) (xy 90.251164 -140.161061) (xy 90.196848 -140.108173) (xy 90.148462 -140.049811)
			(xy 90.106554 -139.986636) (xy 90.071598 -139.919365) (xy 90.043991 -139.84876) (xy 90.024045 -139.775619)
			(xy 90.011986 -139.700774) (xy 90.007951 -139.62507) (xy 88.891872 -139.62507) (xy 88.891368 -139.662976)
			(xy 88.883309 -139.738357) (xy 88.867284 -139.812455) (xy 88.843474 -139.88443) (xy 88.812148 -139.953466)
			(xy 88.773661 -140.018781) (xy 88.72845 -140.079636) (xy 88.677026 -140.13534) (xy 88.619973 -140.185262)
			(xy 88.557937 -140.228837) (xy 88.49162 -140.265572) (xy 88.421774 -140.295049) (xy 88.349191 -140.316935)
			(xy 88.274693 -140.330982) (xy 88.199123 -140.337031) (xy 88.123339 -140.335012) (xy 88.048199 -140.32495)
			(xy 87.974554 -140.306958) (xy 87.903238 -140.28124) (xy 87.835061 -140.248088) (xy 87.770793 -140.207876)
			(xy 87.711164 -140.161061) (xy 87.656848 -140.108173) (xy 87.608462 -140.049811) (xy 87.566554 -139.986636)
			(xy 87.531598 -139.919365) (xy 87.503991 -139.84876) (xy 87.484045 -139.775619) (xy 87.471986 -139.700774)
			(xy 87.467951 -139.62507) (xy 86.351872 -139.62507) (xy 86.351368 -139.662976) (xy 86.343309 -139.738357)
			(xy 86.327284 -139.812455) (xy 86.303474 -139.88443) (xy 86.272148 -139.953466) (xy 86.233661 -140.018781)
			(xy 86.18845 -140.079636) (xy 86.137026 -140.13534) (xy 86.079973 -140.185262) (xy 86.017937 -140.228837)
			(xy 85.95162 -140.265572) (xy 85.881774 -140.295049) (xy 85.809191 -140.316935) (xy 85.734693 -140.330982)
			(xy 85.659123 -140.337031) (xy 85.583339 -140.335012) (xy 85.508199 -140.32495) (xy 85.434554 -140.306958)
			(xy 85.363238 -140.28124) (xy 85.295061 -140.248088) (xy 85.230793 -140.207876) (xy 85.171164 -140.161061)
			(xy 85.116848 -140.108173) (xy 85.068462 -140.049811) (xy 85.026554 -139.986636) (xy 84.991598 -139.919365)
			(xy 84.963991 -139.84876) (xy 84.944045 -139.775619) (xy 84.931986 -139.700774) (xy 84.927951 -139.62507)
			(xy 43.056858 -139.62507) (xy 43.061958 -139.636669) (xy 43.101246 -139.745913) (xy 43.132903 -139.857606)
			(xy 43.156779 -139.971218) (xy 43.17276 -140.086206) (xy 43.180769 -140.202023) (xy 43.18127 -140.26007)
			(xy 43.180769 -140.318117) (xy 43.17276 -140.433934) (xy 43.156779 -140.548922) (xy 43.132903 -140.662534)
			(xy 43.101246 -140.774227) (xy 43.061958 -140.883471) (xy 43.056858 -140.89507) (xy 86.197951 -140.89507)
			(xy 86.201986 -140.819366) (xy 86.214045 -140.744521) (xy 86.233991 -140.67138) (xy 86.261598 -140.600775)
			(xy 86.296554 -140.533504) (xy 86.338462 -140.470329) (xy 86.386848 -140.411967) (xy 86.441164 -140.359079)
			(xy 86.500793 -140.312264) (xy 86.565061 -140.272052) (xy 86.633238 -140.2389) (xy 86.704554 -140.213182)
			(xy 86.778199 -140.19519) (xy 86.853339 -140.185128) (xy 86.929123 -140.183109) (xy 87.004693 -140.189158)
			(xy 87.079191 -140.203205) (xy 87.151774 -140.225091) (xy 87.22162 -140.254568) (xy 87.287937 -140.291303)
			(xy 87.349973 -140.334878) (xy 87.407026 -140.3848) (xy 87.45845 -140.440504) (xy 87.503661 -140.501359)
			(xy 87.542148 -140.566674) (xy 87.573474 -140.63571) (xy 87.597284 -140.707685) (xy 87.613309 -140.781783)
			(xy 87.621368 -140.857164) (xy 87.621872 -140.89507) (xy 88.737951 -140.89507) (xy 88.741986 -140.819366)
			(xy 88.754045 -140.744521) (xy 88.773991 -140.67138) (xy 88.801598 -140.600775) (xy 88.836554 -140.533504)
			(xy 88.878462 -140.470329) (xy 88.926848 -140.411967) (xy 88.981164 -140.359079) (xy 89.040793 -140.312264)
			(xy 89.105061 -140.272052) (xy 89.173238 -140.2389) (xy 89.244554 -140.213182) (xy 89.318199 -140.19519)
			(xy 89.393339 -140.185128) (xy 89.469123 -140.183109) (xy 89.544693 -140.189158) (xy 89.619191 -140.203205)
			(xy 89.691774 -140.225091) (xy 89.76162 -140.254568) (xy 89.827937 -140.291303) (xy 89.889973 -140.334878)
			(xy 89.947026 -140.3848) (xy 89.99845 -140.440504) (xy 90.043661 -140.501359) (xy 90.082148 -140.566674)
			(xy 90.113474 -140.63571) (xy 90.137284 -140.707685) (xy 90.153309 -140.781783) (xy 90.161368 -140.857164)
			(xy 90.161872 -140.89507) (xy 91.277951 -140.89507) (xy 91.281986 -140.819366) (xy 91.294045 -140.744521)
			(xy 91.313991 -140.67138) (xy 91.341598 -140.600775) (xy 91.376554 -140.533504) (xy 91.418462 -140.470329)
			(xy 91.466848 -140.411967) (xy 91.521164 -140.359079) (xy 91.580793 -140.312264) (xy 91.645061 -140.272052)
			(xy 91.713238 -140.2389) (xy 91.784554 -140.213182) (xy 91.858199 -140.19519) (xy 91.933339 -140.185128)
			(xy 92.009123 -140.183109) (xy 92.084693 -140.189158) (xy 92.159191 -140.203205) (xy 92.231774 -140.225091)
			(xy 92.30162 -140.254568) (xy 92.367937 -140.291303) (xy 92.429973 -140.334878) (xy 92.487026 -140.3848)
			(xy 92.53845 -140.440504) (xy 92.583661 -140.501359) (xy 92.622148 -140.566674) (xy 92.653474 -140.63571)
			(xy 92.677284 -140.707685) (xy 92.693309 -140.781783) (xy 92.701368 -140.857164) (xy 92.701872 -140.89507)
			(xy 92.701368 -140.932976) (xy 92.693309 -141.008357) (xy 92.677284 -141.082455) (xy 92.653474 -141.15443)
			(xy 92.622148 -141.223466) (xy 92.583661 -141.288781) (xy 92.53845 -141.349636) (xy 92.487026 -141.40534)
			(xy 92.429973 -141.455262) (xy 92.367937 -141.498837) (xy 92.30162 -141.535572) (xy 92.231774 -141.565049)
			(xy 92.159191 -141.586935) (xy 92.084693 -141.600982) (xy 92.009123 -141.607031) (xy 91.933339 -141.605012)
			(xy 91.858199 -141.59495) (xy 91.784554 -141.576958) (xy 91.713238 -141.55124) (xy 91.645061 -141.518088)
			(xy 91.580793 -141.477876) (xy 91.521164 -141.431061) (xy 91.466848 -141.378173) (xy 91.418462 -141.319811)
			(xy 91.376554 -141.256636) (xy 91.341598 -141.189365) (xy 91.313991 -141.11876) (xy 91.294045 -141.045619)
			(xy 91.281986 -140.970774) (xy 91.277951 -140.89507) (xy 90.161872 -140.89507) (xy 90.161368 -140.932976)
			(xy 90.153309 -141.008357) (xy 90.137284 -141.082455) (xy 90.113474 -141.15443) (xy 90.082148 -141.223466)
			(xy 90.043661 -141.288781) (xy 89.99845 -141.349636) (xy 89.947026 -141.40534) (xy 89.889973 -141.455262)
			(xy 89.827937 -141.498837) (xy 89.76162 -141.535572) (xy 89.691774 -141.565049) (xy 89.619191 -141.586935)
			(xy 89.544693 -141.600982) (xy 89.469123 -141.607031) (xy 89.393339 -141.605012) (xy 89.318199 -141.59495)
			(xy 89.244554 -141.576958) (xy 89.173238 -141.55124) (xy 89.105061 -141.518088) (xy 89.040793 -141.477876)
			(xy 88.981164 -141.431061) (xy 88.926848 -141.378173) (xy 88.878462 -141.319811) (xy 88.836554 -141.256636)
			(xy 88.801598 -141.189365) (xy 88.773991 -141.11876) (xy 88.754045 -141.045619) (xy 88.741986 -140.970774)
			(xy 88.737951 -140.89507) (xy 87.621872 -140.89507) (xy 87.621368 -140.932976) (xy 87.613309 -141.008357)
			(xy 87.597284 -141.082455) (xy 87.573474 -141.15443) (xy 87.542148 -141.223466) (xy 87.503661 -141.288781)
			(xy 87.45845 -141.349636) (xy 87.407026 -141.40534) (xy 87.349973 -141.455262) (xy 87.287937 -141.498837)
			(xy 87.22162 -141.535572) (xy 87.151774 -141.565049) (xy 87.079191 -141.586935) (xy 87.004693 -141.600982)
			(xy 86.929123 -141.607031) (xy 86.853339 -141.605012) (xy 86.778199 -141.59495) (xy 86.704554 -141.576958)
			(xy 86.633238 -141.55124) (xy 86.565061 -141.518088) (xy 86.500793 -141.477876) (xy 86.441164 -141.431061)
			(xy 86.386848 -141.378173) (xy 86.338462 -141.319811) (xy 86.296554 -141.256636) (xy 86.261598 -141.189365)
			(xy 86.233991 -141.11876) (xy 86.214045 -141.045619) (xy 86.201986 -140.970774) (xy 86.197951 -140.89507)
			(xy 43.056858 -140.89507) (xy 43.055406 -140.898372) (xy 43.328336 -140.898372) (xy 44.751752 -140.898372)
			(xy 44.751752 -141.61008) (xy 45.867831 -141.61008) (xy 45.871866 -141.534376) (xy 45.883925 -141.459531)
			(xy 45.903871 -141.38639) (xy 45.931478 -141.315785) (xy 45.966434 -141.248514) (xy 46.008342 -141.185339)
			(xy 46.056728 -141.126977) (xy 46.111044 -141.074089) (xy 46.170673 -141.027274) (xy 46.234941 -140.987062)
			(xy 46.303118 -140.95391) (xy 46.374434 -140.928192) (xy 46.448079 -140.9102) (xy 46.523219 -140.900138)
			(xy 46.599003 -140.898119) (xy 46.674573 -140.904168) (xy 46.749071 -140.918215) (xy 46.821654 -140.940101)
			(xy 46.8915 -140.969578) (xy 46.957817 -141.006313) (xy 47.019853 -141.049888) (xy 47.076906 -141.09981)
			(xy 47.12833 -141.155514) (xy 47.173541 -141.216369) (xy 47.212028 -141.281684) (xy 47.243354 -141.35072)
			(xy 47.267164 -141.422695) (xy 47.283189 -141.496793) (xy 47.291248 -141.572174) (xy 47.291752 -141.61008)
			(xy 48.407831 -141.61008) (xy 48.411866 -141.534376) (xy 48.423925 -141.459531) (xy 48.443871 -141.38639)
			(xy 48.471478 -141.315785) (xy 48.506434 -141.248514) (xy 48.548342 -141.185339) (xy 48.596728 -141.126977)
			(xy 48.651044 -141.074089) (xy 48.710673 -141.027274) (xy 48.774941 -140.987062) (xy 48.843118 -140.95391)
			(xy 48.914434 -140.928192) (xy 48.988079 -140.9102) (xy 49.063219 -140.900138) (xy 49.139003 -140.898119)
			(xy 49.214573 -140.904168) (xy 49.289071 -140.918215) (xy 49.361654 -140.940101) (xy 49.4315 -140.969578)
			(xy 49.497817 -141.006313) (xy 49.559853 -141.049888) (xy 49.616906 -141.09981) (xy 49.66833 -141.155514)
			(xy 49.713541 -141.216369) (xy 49.752028 -141.281684) (xy 49.783354 -141.35072) (xy 49.807164 -141.422695)
			(xy 49.823189 -141.496793) (xy 49.831248 -141.572174) (xy 49.831752 -141.61008) (xy 50.947831 -141.61008)
			(xy 50.951866 -141.534376) (xy 50.963925 -141.459531) (xy 50.983871 -141.38639) (xy 51.011478 -141.315785)
			(xy 51.046434 -141.248514) (xy 51.088342 -141.185339) (xy 51.136728 -141.126977) (xy 51.191044 -141.074089)
			(xy 51.250673 -141.027274) (xy 51.314941 -140.987062) (xy 51.383118 -140.95391) (xy 51.454434 -140.928192)
			(xy 51.528079 -140.9102) (xy 51.603219 -140.900138) (xy 51.679003 -140.898119) (xy 51.754573 -140.904168)
			(xy 51.829071 -140.918215) (xy 51.901654 -140.940101) (xy 51.9715 -140.969578) (xy 52.037817 -141.006313)
			(xy 52.099853 -141.049888) (xy 52.156906 -141.09981) (xy 52.20833 -141.155514) (xy 52.253541 -141.216369)
			(xy 52.292028 -141.281684) (xy 52.323354 -141.35072) (xy 52.347164 -141.422695) (xy 52.363189 -141.496793)
			(xy 52.371248 -141.572174) (xy 52.371752 -141.61008) (xy 53.487831 -141.61008) (xy 53.491866 -141.534376)
			(xy 53.503925 -141.459531) (xy 53.523871 -141.38639) (xy 53.551478 -141.315785) (xy 53.586434 -141.248514)
			(xy 53.628342 -141.185339) (xy 53.676728 -141.126977) (xy 53.731044 -141.074089) (xy 53.790673 -141.027274)
			(xy 53.854941 -140.987062) (xy 53.923118 -140.95391) (xy 53.994434 -140.928192) (xy 54.068079 -140.9102)
			(xy 54.143219 -140.900138) (xy 54.219003 -140.898119) (xy 54.294573 -140.904168) (xy 54.369071 -140.918215)
			(xy 54.441654 -140.940101) (xy 54.5115 -140.969578) (xy 54.577817 -141.006313) (xy 54.639853 -141.049888)
			(xy 54.696906 -141.09981) (xy 54.74833 -141.155514) (xy 54.793541 -141.216369) (xy 54.832028 -141.281684)
			(xy 54.863354 -141.35072) (xy 54.887164 -141.422695) (xy 54.903189 -141.496793) (xy 54.911248 -141.572174)
			(xy 54.911752 -141.61008) (xy 56.027831 -141.61008) (xy 56.031866 -141.534376) (xy 56.043925 -141.459531)
			(xy 56.063871 -141.38639) (xy 56.091478 -141.315785) (xy 56.126434 -141.248514) (xy 56.168342 -141.185339)
			(xy 56.216728 -141.126977) (xy 56.271044 -141.074089) (xy 56.330673 -141.027274) (xy 56.394941 -140.987062)
			(xy 56.463118 -140.95391) (xy 56.534434 -140.928192) (xy 56.608079 -140.9102) (xy 56.683219 -140.900138)
			(xy 56.759003 -140.898119) (xy 56.834573 -140.904168) (xy 56.909071 -140.918215) (xy 56.981654 -140.940101)
			(xy 57.0515 -140.969578) (xy 57.117817 -141.006313) (xy 57.179853 -141.049888) (xy 57.236906 -141.09981)
			(xy 57.28833 -141.155514) (xy 57.333541 -141.216369) (xy 57.372028 -141.281684) (xy 57.403354 -141.35072)
			(xy 57.427164 -141.422695) (xy 57.443189 -141.496793) (xy 57.451248 -141.572174) (xy 57.451752 -141.61008)
			(xy 58.567831 -141.61008) (xy 58.571866 -141.534376) (xy 58.583925 -141.459531) (xy 58.603871 -141.38639)
			(xy 58.631478 -141.315785) (xy 58.666434 -141.248514) (xy 58.708342 -141.185339) (xy 58.756728 -141.126977)
			(xy 58.811044 -141.074089) (xy 58.870673 -141.027274) (xy 58.934941 -140.987062) (xy 59.003118 -140.95391)
			(xy 59.074434 -140.928192) (xy 59.148079 -140.9102) (xy 59.223219 -140.900138) (xy 59.299003 -140.898119)
			(xy 59.374573 -140.904168) (xy 59.449071 -140.918215) (xy 59.521654 -140.940101) (xy 59.5915 -140.969578)
			(xy 59.657817 -141.006313) (xy 59.719853 -141.049888) (xy 59.776906 -141.09981) (xy 59.82833 -141.155514)
			(xy 59.873541 -141.216369) (xy 59.912028 -141.281684) (xy 59.943354 -141.35072) (xy 59.967164 -141.422695)
			(xy 59.983189 -141.496793) (xy 59.991248 -141.572174) (xy 59.991752 -141.61008) (xy 61.107831 -141.61008)
			(xy 61.111866 -141.534376) (xy 61.123925 -141.459531) (xy 61.143871 -141.38639) (xy 61.171478 -141.315785)
			(xy 61.206434 -141.248514) (xy 61.248342 -141.185339) (xy 61.296728 -141.126977) (xy 61.351044 -141.074089)
			(xy 61.410673 -141.027274) (xy 61.474941 -140.987062) (xy 61.543118 -140.95391) (xy 61.614434 -140.928192)
			(xy 61.688079 -140.9102) (xy 61.763219 -140.900138) (xy 61.839003 -140.898119) (xy 61.914573 -140.904168)
			(xy 61.989071 -140.918215) (xy 62.061654 -140.940101) (xy 62.1315 -140.969578) (xy 62.197817 -141.006313)
			(xy 62.259853 -141.049888) (xy 62.316906 -141.09981) (xy 62.36833 -141.155514) (xy 62.413541 -141.216369)
			(xy 62.452028 -141.281684) (xy 62.483354 -141.35072) (xy 62.507164 -141.422695) (xy 62.523189 -141.496793)
			(xy 62.531248 -141.572174) (xy 62.531752 -141.61008) (xy 62.531248 -141.647986) (xy 62.523189 -141.723367)
			(xy 62.507164 -141.797465) (xy 62.483354 -141.86944) (xy 62.452028 -141.938476) (xy 62.413541 -142.003791)
			(xy 62.36833 -142.064646) (xy 62.316906 -142.12035) (xy 62.265798 -142.16507) (xy 84.927951 -142.16507)
			(xy 84.931986 -142.089366) (xy 84.944045 -142.014521) (xy 84.963991 -141.94138) (xy 84.991598 -141.870775)
			(xy 85.026554 -141.803504) (xy 85.068462 -141.740329) (xy 85.116848 -141.681967) (xy 85.171164 -141.629079)
			(xy 85.230793 -141.582264) (xy 85.295061 -141.542052) (xy 85.363238 -141.5089) (xy 85.434554 -141.483182)
			(xy 85.508199 -141.46519) (xy 85.583339 -141.455128) (xy 85.659123 -141.453109) (xy 85.734693 -141.459158)
			(xy 85.809191 -141.473205) (xy 85.881774 -141.495091) (xy 85.95162 -141.524568) (xy 86.017937 -141.561303)
			(xy 86.079973 -141.604878) (xy 86.137026 -141.6548) (xy 86.18845 -141.710504) (xy 86.233661 -141.771359)
			(xy 86.272148 -141.836674) (xy 86.303474 -141.90571) (xy 86.327284 -141.977685) (xy 86.343309 -142.051783)
			(xy 86.351368 -142.127164) (xy 86.351872 -142.16507) (xy 87.467951 -142.16507) (xy 87.471986 -142.089366)
			(xy 87.484045 -142.014521) (xy 87.503991 -141.94138) (xy 87.531598 -141.870775) (xy 87.566554 -141.803504)
			(xy 87.608462 -141.740329) (xy 87.656848 -141.681967) (xy 87.711164 -141.629079) (xy 87.770793 -141.582264)
			(xy 87.835061 -141.542052) (xy 87.903238 -141.5089) (xy 87.974554 -141.483182) (xy 88.048199 -141.46519)
			(xy 88.123339 -141.455128) (xy 88.199123 -141.453109) (xy 88.274693 -141.459158) (xy 88.349191 -141.473205)
			(xy 88.421774 -141.495091) (xy 88.49162 -141.524568) (xy 88.557937 -141.561303) (xy 88.619973 -141.604878)
			(xy 88.677026 -141.6548) (xy 88.72845 -141.710504) (xy 88.773661 -141.771359) (xy 88.812148 -141.836674)
			(xy 88.843474 -141.90571) (xy 88.867284 -141.977685) (xy 88.883309 -142.051783) (xy 88.891368 -142.127164)
			(xy 88.891872 -142.16507) (xy 90.007951 -142.16507) (xy 90.011986 -142.089366) (xy 90.024045 -142.014521)
			(xy 90.043991 -141.94138) (xy 90.071598 -141.870775) (xy 90.106554 -141.803504) (xy 90.148462 -141.740329)
			(xy 90.196848 -141.681967) (xy 90.251164 -141.629079) (xy 90.310793 -141.582264) (xy 90.375061 -141.542052)
			(xy 90.443238 -141.5089) (xy 90.514554 -141.483182) (xy 90.588199 -141.46519) (xy 90.663339 -141.455128)
			(xy 90.739123 -141.453109) (xy 90.814693 -141.459158) (xy 90.889191 -141.473205) (xy 90.961774 -141.495091)
			(xy 91.03162 -141.524568) (xy 91.097937 -141.561303) (xy 91.159973 -141.604878) (xy 91.165918 -141.61008)
			(xy 93.15476 -141.61008) (xy 93.158776 -141.49381) (xy 93.170803 -141.378095) (xy 93.190785 -141.263485)
			(xy 93.218627 -141.150526) (xy 93.254196 -141.039758) (xy 93.297322 -140.931707) (xy 93.347799 -140.826889)
			(xy 93.405388 -140.725804) (xy 93.469814 -140.628932) (xy 93.540769 -140.536736) (xy 93.617916 -140.449655)
			(xy 93.700887 -140.368104) (xy 93.789287 -140.292472) (xy 93.882694 -140.223118) (xy 93.980663 -140.160375)
			(xy 94.082727 -140.104539) (xy 94.188401 -140.055878) (xy 94.29718 -140.014624) (xy 94.408545 -139.980973)
			(xy 94.521968 -139.955085) (xy 94.636905 -139.937084) (xy 94.752811 -139.927055) (xy 94.869133 -139.925047)
			(xy 94.985316 -139.931069) (xy 95.100807 -139.945092) (xy 95.215055 -139.96705) (xy 95.327516 -139.996837)
			(xy 95.437654 -140.034312) (xy 95.544944 -140.079297) (xy 95.648875 -140.131576) (xy 95.748951 -140.190901)
			(xy 95.844697 -140.256989) (xy 95.935654 -140.329525) (xy 96.02139 -140.408164) (xy 96.101497 -140.49253)
			(xy 96.175593 -140.582222) (xy 96.243323 -140.676812) (xy 96.304367 -140.77585) (xy 96.358432 -140.878863)
			(xy 96.405262 -140.98536) (xy 96.444633 -141.094835) (xy 96.476357 -141.206765) (xy 96.500283 -141.320617)
			(xy 96.516297 -141.435849) (xy 96.524324 -141.551911) (xy 96.524826 -141.61008) (xy 96.524324 -141.668249)
			(xy 96.516297 -141.784311) (xy 96.500283 -141.899543) (xy 96.476357 -142.013395) (xy 96.444633 -142.125325)
			(xy 96.405262 -142.2348) (xy 96.358432 -142.341297) (xy 96.304367 -142.44431) (xy 96.243323 -142.543348)
			(xy 96.175593 -142.637938) (xy 96.101497 -142.72763) (xy 96.02139 -142.811996) (xy 95.935654 -142.890635)
			(xy 95.844697 -142.963171) (xy 95.748951 -143.029259) (xy 95.648875 -143.088584) (xy 95.544944 -143.140863)
			(xy 95.437654 -143.185848) (xy 95.327516 -143.223323) (xy 95.215055 -143.25311) (xy 95.100807 -143.275068)
			(xy 94.985316 -143.289091) (xy 94.869133 -143.295113) (xy 94.752811 -143.293105) (xy 94.636905 -143.283076)
			(xy 94.521968 -143.265075) (xy 94.408545 -143.239187) (xy 94.29718 -143.205536) (xy 94.188401 -143.164282)
			(xy 94.082727 -143.115621) (xy 93.980663 -143.059785) (xy 93.882694 -142.997042) (xy 93.789287 -142.927688)
			(xy 93.700887 -142.852056) (xy 93.617916 -142.770505) (xy 93.540769 -142.683424) (xy 93.469814 -142.591228)
			(xy 93.405388 -142.494356) (xy 93.347799 -142.393271) (xy 93.297322 -142.288453) (xy 93.254196 -142.180402)
			(xy 93.218627 -142.069634) (xy 93.190785 -141.956675) (xy 93.170803 -141.842065) (xy 93.158776 -141.72635)
			(xy 93.15476 -141.61008) (xy 91.165918 -141.61008) (xy 91.217026 -141.6548) (xy 91.26845 -141.710504)
			(xy 91.313661 -141.771359) (xy 91.352148 -141.836674) (xy 91.383474 -141.90571) (xy 91.407284 -141.977685)
			(xy 91.423309 -142.051783) (xy 91.431368 -142.127164) (xy 91.431872 -142.16507) (xy 91.431368 -142.202976)
			(xy 91.423309 -142.278357) (xy 91.407284 -142.352455) (xy 91.383474 -142.42443) (xy 91.352148 -142.493466)
			(xy 91.313661 -142.558781) (xy 91.26845 -142.619636) (xy 91.217026 -142.67534) (xy 91.159973 -142.725262)
			(xy 91.097937 -142.768837) (xy 91.03162 -142.805572) (xy 90.961774 -142.835049) (xy 90.889191 -142.856935)
			(xy 90.814693 -142.870982) (xy 90.739123 -142.877031) (xy 90.663339 -142.875012) (xy 90.588199 -142.86495)
			(xy 90.514554 -142.846958) (xy 90.443238 -142.82124) (xy 90.375061 -142.788088) (xy 90.310793 -142.747876)
			(xy 90.251164 -142.701061) (xy 90.196848 -142.648173) (xy 90.148462 -142.589811) (xy 90.106554 -142.526636)
			(xy 90.071598 -142.459365) (xy 90.043991 -142.38876) (xy 90.024045 -142.315619) (xy 90.011986 -142.240774)
			(xy 90.007951 -142.16507) (xy 88.891872 -142.16507) (xy 88.891368 -142.202976) (xy 88.883309 -142.278357)
			(xy 88.867284 -142.352455) (xy 88.843474 -142.42443) (xy 88.812148 -142.493466) (xy 88.773661 -142.558781)
			(xy 88.72845 -142.619636) (xy 88.677026 -142.67534) (xy 88.619973 -142.725262) (xy 88.557937 -142.768837)
			(xy 88.49162 -142.805572) (xy 88.421774 -142.835049) (xy 88.349191 -142.856935) (xy 88.274693 -142.870982)
			(xy 88.199123 -142.877031) (xy 88.123339 -142.875012) (xy 88.048199 -142.86495) (xy 87.974554 -142.846958)
			(xy 87.903238 -142.82124) (xy 87.835061 -142.788088) (xy 87.770793 -142.747876) (xy 87.711164 -142.701061)
			(xy 87.656848 -142.648173) (xy 87.608462 -142.589811) (xy 87.566554 -142.526636) (xy 87.531598 -142.459365)
			(xy 87.503991 -142.38876) (xy 87.484045 -142.315619) (xy 87.471986 -142.240774) (xy 87.467951 -142.16507)
			(xy 86.351872 -142.16507) (xy 86.351368 -142.202976) (xy 86.343309 -142.278357) (xy 86.327284 -142.352455)
			(xy 86.303474 -142.42443) (xy 86.272148 -142.493466) (xy 86.233661 -142.558781) (xy 86.18845 -142.619636)
			(xy 86.137026 -142.67534) (xy 86.079973 -142.725262) (xy 86.017937 -142.768837) (xy 85.95162 -142.805572)
			(xy 85.881774 -142.835049) (xy 85.809191 -142.856935) (xy 85.734693 -142.870982) (xy 85.659123 -142.877031)
			(xy 85.583339 -142.875012) (xy 85.508199 -142.86495) (xy 85.434554 -142.846958) (xy 85.363238 -142.82124)
			(xy 85.295061 -142.788088) (xy 85.230793 -142.747876) (xy 85.171164 -142.701061) (xy 85.116848 -142.648173)
			(xy 85.068462 -142.589811) (xy 85.026554 -142.526636) (xy 84.991598 -142.459365) (xy 84.963991 -142.38876)
			(xy 84.944045 -142.315619) (xy 84.931986 -142.240774) (xy 84.927951 -142.16507) (xy 62.265798 -142.16507)
			(xy 62.259853 -142.170272) (xy 62.197817 -142.213847) (xy 62.1315 -142.250582) (xy 62.061654 -142.280059)
			(xy 61.989071 -142.301945) (xy 61.914573 -142.315992) (xy 61.839003 -142.322041) (xy 61.763219 -142.320022)
			(xy 61.688079 -142.30996) (xy 61.614434 -142.291968) (xy 61.543118 -142.26625) (xy 61.474941 -142.233098)
			(xy 61.410673 -142.192886) (xy 61.351044 -142.146071) (xy 61.296728 -142.093183) (xy 61.248342 -142.034821)
			(xy 61.206434 -141.971646) (xy 61.171478 -141.904375) (xy 61.143871 -141.83377) (xy 61.123925 -141.760629)
			(xy 61.111866 -141.685784) (xy 61.107831 -141.61008) (xy 59.991752 -141.61008) (xy 59.991248 -141.647986)
			(xy 59.983189 -141.723367) (xy 59.967164 -141.797465) (xy 59.943354 -141.86944) (xy 59.912028 -141.938476)
			(xy 59.873541 -142.003791) (xy 59.82833 -142.064646) (xy 59.776906 -142.12035) (xy 59.719853 -142.170272)
			(xy 59.657817 -142.213847) (xy 59.5915 -142.250582) (xy 59.521654 -142.280059) (xy 59.449071 -142.301945)
			(xy 59.374573 -142.315992) (xy 59.299003 -142.322041) (xy 59.223219 -142.320022) (xy 59.148079 -142.30996)
			(xy 59.074434 -142.291968) (xy 59.003118 -142.26625) (xy 58.934941 -142.233098) (xy 58.870673 -142.192886)
			(xy 58.811044 -142.146071) (xy 58.756728 -142.093183) (xy 58.708342 -142.034821) (xy 58.666434 -141.971646)
			(xy 58.631478 -141.904375) (xy 58.603871 -141.83377) (xy 58.583925 -141.760629) (xy 58.571866 -141.685784)
			(xy 58.567831 -141.61008) (xy 57.451752 -141.61008) (xy 57.451248 -141.647986) (xy 57.443189 -141.723367)
			(xy 57.427164 -141.797465) (xy 57.403354 -141.86944) (xy 57.372028 -141.938476) (xy 57.333541 -142.003791)
			(xy 57.28833 -142.064646) (xy 57.236906 -142.12035) (xy 57.179853 -142.170272) (xy 57.117817 -142.213847)
			(xy 57.0515 -142.250582) (xy 56.981654 -142.280059) (xy 56.909071 -142.301945) (xy 56.834573 -142.315992)
			(xy 56.759003 -142.322041) (xy 56.683219 -142.320022) (xy 56.608079 -142.30996) (xy 56.534434 -142.291968)
			(xy 56.463118 -142.26625) (xy 56.394941 -142.233098) (xy 56.330673 -142.192886) (xy 56.271044 -142.146071)
			(xy 56.216728 -142.093183) (xy 56.168342 -142.034821) (xy 56.126434 -141.971646) (xy 56.091478 -141.904375)
			(xy 56.063871 -141.83377) (xy 56.043925 -141.760629) (xy 56.031866 -141.685784) (xy 56.027831 -141.61008)
			(xy 54.911752 -141.61008) (xy 54.911248 -141.647986) (xy 54.903189 -141.723367) (xy 54.887164 -141.797465)
			(xy 54.863354 -141.86944) (xy 54.832028 -141.938476) (xy 54.793541 -142.003791) (xy 54.74833 -142.064646)
			(xy 54.696906 -142.12035) (xy 54.639853 -142.170272) (xy 54.577817 -142.213847) (xy 54.5115 -142.250582)
			(xy 54.441654 -142.280059) (xy 54.369071 -142.301945) (xy 54.294573 -142.315992) (xy 54.219003 -142.322041)
			(xy 54.143219 -142.320022) (xy 54.068079 -142.30996) (xy 53.994434 -142.291968) (xy 53.923118 -142.26625)
			(xy 53.854941 -142.233098) (xy 53.790673 -142.192886) (xy 53.731044 -142.146071) (xy 53.676728 -142.093183)
			(xy 53.628342 -142.034821) (xy 53.586434 -141.971646) (xy 53.551478 -141.904375) (xy 53.523871 -141.83377)
			(xy 53.503925 -141.760629) (xy 53.491866 -141.685784) (xy 53.487831 -141.61008) (xy 52.371752 -141.61008)
			(xy 52.371248 -141.647986) (xy 52.363189 -141.723367) (xy 52.347164 -141.797465) (xy 52.323354 -141.86944)
			(xy 52.292028 -141.938476) (xy 52.253541 -142.003791) (xy 52.20833 -142.064646) (xy 52.156906 -142.12035)
			(xy 52.099853 -142.170272) (xy 52.037817 -142.213847) (xy 51.9715 -142.250582) (xy 51.901654 -142.280059)
			(xy 51.829071 -142.301945) (xy 51.754573 -142.315992) (xy 51.679003 -142.322041) (xy 51.603219 -142.320022)
			(xy 51.528079 -142.30996) (xy 51.454434 -142.291968) (xy 51.383118 -142.26625) (xy 51.314941 -142.233098)
			(xy 51.250673 -142.192886) (xy 51.191044 -142.146071) (xy 51.136728 -142.093183) (xy 51.088342 -142.034821)
			(xy 51.046434 -141.971646) (xy 51.011478 -141.904375) (xy 50.983871 -141.83377) (xy 50.963925 -141.760629)
			(xy 50.951866 -141.685784) (xy 50.947831 -141.61008) (xy 49.831752 -141.61008) (xy 49.831248 -141.647986)
			(xy 49.823189 -141.723367) (xy 49.807164 -141.797465) (xy 49.783354 -141.86944) (xy 49.752028 -141.938476)
			(xy 49.713541 -142.003791) (xy 49.66833 -142.064646) (xy 49.616906 -142.12035) (xy 49.559853 -142.170272)
			(xy 49.497817 -142.213847) (xy 49.4315 -142.250582) (xy 49.361654 -142.280059) (xy 49.289071 -142.301945)
			(xy 49.214573 -142.315992) (xy 49.139003 -142.322041) (xy 49.063219 -142.320022) (xy 48.988079 -142.30996)
			(xy 48.914434 -142.291968) (xy 48.843118 -142.26625) (xy 48.774941 -142.233098) (xy 48.710673 -142.192886)
			(xy 48.651044 -142.146071) (xy 48.596728 -142.093183) (xy 48.548342 -142.034821) (xy 48.506434 -141.971646)
			(xy 48.471478 -141.904375) (xy 48.443871 -141.83377) (xy 48.423925 -141.760629) (xy 48.411866 -141.685784)
			(xy 48.407831 -141.61008) (xy 47.291752 -141.61008) (xy 47.291248 -141.647986) (xy 47.283189 -141.723367)
			(xy 47.267164 -141.797465) (xy 47.243354 -141.86944) (xy 47.212028 -141.938476) (xy 47.173541 -142.003791)
			(xy 47.12833 -142.064646) (xy 47.076906 -142.12035) (xy 47.019853 -142.170272) (xy 46.957817 -142.213847)
			(xy 46.8915 -142.250582) (xy 46.821654 -142.280059) (xy 46.749071 -142.301945) (xy 46.674573 -142.315992)
			(xy 46.599003 -142.322041) (xy 46.523219 -142.320022) (xy 46.448079 -142.30996) (xy 46.374434 -142.291968)
			(xy 46.303118 -142.26625) (xy 46.234941 -142.233098) (xy 46.170673 -142.192886) (xy 46.111044 -142.146071)
			(xy 46.056728 -142.093183) (xy 46.008342 -142.034821) (xy 45.966434 -141.971646) (xy 45.931478 -141.904375)
			(xy 45.903871 -141.83377) (xy 45.883925 -141.760629) (xy 45.871866 -141.685784) (xy 45.867831 -141.61008)
			(xy 44.751752 -141.61008) (xy 44.751752 -142.321788) (xy 43.328336 -142.321788) (xy 43.328336 -140.898372)
			(xy 43.055406 -140.898372) (xy 43.015228 -140.989744) (xy 42.961276 -141.09254) (xy 42.900362 -141.191368)
			(xy 42.832774 -141.285759) (xy 42.758835 -141.375261) (xy 42.678897 -141.459449) (xy 42.593342 -141.537922)
			(xy 42.502576 -141.610305) (xy 42.407033 -141.676254) (xy 42.307168 -141.735454) (xy 42.203456 -141.787623)
			(xy 42.096393 -141.832512) (xy 41.986487 -141.869908) (xy 41.874263 -141.899633) (xy 41.760257 -141.921544)
			(xy 41.64501 -141.935537) (xy 41.529072 -141.941546) (xy 41.412996 -141.939543) (xy 41.297334 -141.929535)
			(xy 41.182639 -141.911572) (xy 41.069456 -141.885739) (xy 40.958325 -141.852159) (xy 40.849776 -141.810991)
			(xy 40.744326 -141.762433) (xy 40.642477 -141.706716) (xy 40.544714 -141.644104) (xy 40.451504 -141.574897)
			(xy 40.363291 -141.499424) (xy 40.280495 -141.418045) (xy 40.203511 -141.331148) (xy 40.132706 -141.239147)
			(xy 40.068416 -141.14248) (xy 40.010949 -141.041608) (xy 39.960578 -140.937011) (xy 39.917543 -140.829188)
			(xy 39.882049 -140.718654) (xy 39.854266 -140.605934) (xy 39.834326 -140.491566) (xy 39.822324 -140.376094)
			(xy 39.818317 -140.26007) (xy 27.89936 -140.26007) (xy 27.89936 -141.293358) (xy 29.519874 -141.293358)
			(xy 29.519874 -141.206458) (xy 29.527892 -141.119929) (xy 29.54386 -141.034509) (xy 29.567641 -140.950927)
			(xy 29.599033 -140.869895) (xy 29.637767 -140.792106) (xy 29.683514 -140.718222) (xy 29.735883 -140.648875)
			(xy 29.794427 -140.584655) (xy 29.858647 -140.526111) (xy 29.927994 -140.473742) (xy 30.001878 -140.427995)
			(xy 30.079667 -140.389261) (xy 30.160699 -140.357869) (xy 30.244281 -140.334088) (xy 30.329701 -140.31812)
			(xy 30.41623 -140.310102) (xy 30.50313 -140.310102) (xy 30.589659 -140.31812) (xy 30.675079 -140.334088)
			(xy 30.758661 -140.357869) (xy 30.839693 -140.389261) (xy 30.917482 -140.427995) (xy 30.991366 -140.473742)
			(xy 31.060713 -140.526111) (xy 31.124933 -140.584655) (xy 31.183477 -140.648875) (xy 31.235846 -140.718222)
			(xy 31.281593 -140.792106) (xy 31.320327 -140.869895) (xy 31.351719 -140.950927) (xy 31.3755 -141.034509)
			(xy 31.391468 -141.119929) (xy 31.399486 -141.206458) (xy 31.399988 -141.249908) (xy 31.399486 -141.293358)
			(xy 34.599874 -141.293358) (xy 34.599874 -141.206458) (xy 34.607892 -141.119929) (xy 34.62386 -141.034509)
			(xy 34.647641 -140.950927) (xy 34.679033 -140.869895) (xy 34.717767 -140.792106) (xy 34.763514 -140.718222)
			(xy 34.815883 -140.648875) (xy 34.874427 -140.584655) (xy 34.938647 -140.526111) (xy 35.007994 -140.473742)
			(xy 35.081878 -140.427995) (xy 35.159667 -140.389261) (xy 35.240699 -140.357869) (xy 35.324281 -140.334088)
			(xy 35.409701 -140.31812) (xy 35.49623 -140.310102) (xy 35.58313 -140.310102) (xy 35.669659 -140.31812)
			(xy 35.755079 -140.334088) (xy 35.838661 -140.357869) (xy 35.919693 -140.389261) (xy 35.997482 -140.427995)
			(xy 36.071366 -140.473742) (xy 36.140713 -140.526111) (xy 36.204933 -140.584655) (xy 36.263477 -140.648875)
			(xy 36.315846 -140.718222) (xy 36.361593 -140.792106) (xy 36.400327 -140.869895) (xy 36.431719 -140.950927)
			(xy 36.4555 -141.034509) (xy 36.471468 -141.119929) (xy 36.479486 -141.206458) (xy 36.479988 -141.249908)
			(xy 36.479486 -141.293358) (xy 36.471468 -141.379887) (xy 36.4555 -141.465307) (xy 36.431719 -141.548889)
			(xy 36.400327 -141.629921) (xy 36.361593 -141.70771) (xy 36.315846 -141.781594) (xy 36.263477 -141.850941)
			(xy 36.204933 -141.915161) (xy 36.140713 -141.973705) (xy 36.071366 -142.026074) (xy 35.997482 -142.071821)
			(xy 35.919693 -142.110555) (xy 35.838661 -142.141947) (xy 35.755079 -142.165728) (xy 35.669659 -142.181696)
			(xy 35.58313 -142.189714) (xy 35.49623 -142.189714) (xy 35.409701 -142.181696) (xy 35.324281 -142.165728)
			(xy 35.240699 -142.141947) (xy 35.159667 -142.110555) (xy 35.081878 -142.071821) (xy 35.007994 -142.026074)
			(xy 34.938647 -141.973705) (xy 34.874427 -141.915161) (xy 34.815883 -141.850941) (xy 34.763514 -141.781594)
			(xy 34.717767 -141.70771) (xy 34.679033 -141.629921) (xy 34.647641 -141.548889) (xy 34.62386 -141.465307)
			(xy 34.607892 -141.379887) (xy 34.599874 -141.293358) (xy 31.399486 -141.293358) (xy 31.391468 -141.379887)
			(xy 31.3755 -141.465307) (xy 31.351719 -141.548889) (xy 31.320327 -141.629921) (xy 31.281593 -141.70771)
			(xy 31.235846 -141.781594) (xy 31.183477 -141.850941) (xy 31.124933 -141.915161) (xy 31.060713 -141.973705)
			(xy 30.991366 -142.026074) (xy 30.917482 -142.071821) (xy 30.839693 -142.110555) (xy 30.758661 -142.141947)
			(xy 30.675079 -142.165728) (xy 30.589659 -142.181696) (xy 30.50313 -142.189714) (xy 30.41623 -142.189714)
			(xy 30.329701 -142.181696) (xy 30.244281 -142.165728) (xy 30.160699 -142.141947) (xy 30.079667 -142.110555)
			(xy 30.001878 -142.071821) (xy 29.927994 -142.026074) (xy 29.858647 -141.973705) (xy 29.794427 -141.915161)
			(xy 29.735883 -141.850941) (xy 29.683514 -141.781594) (xy 29.637767 -141.70771) (xy 29.599033 -141.629921)
			(xy 29.567641 -141.548889) (xy 29.54386 -141.465307) (xy 29.527892 -141.379887) (xy 29.519874 -141.293358)
			(xy 27.89936 -141.293358) (xy 27.89936 -146.428714) (xy 80.994502 -146.428714) (xy 80.998573 -146.373092)
			(xy 81.010699 -146.318655) (xy 81.030622 -146.266564) (xy 81.057918 -146.217929) (xy 81.092004 -146.173786)
			(xy 81.132153 -146.135077) (xy 81.177511 -146.102626) (xy 81.227111 -146.077125) (xy 81.279895 -146.059118)
			(xy 81.334738 -146.048988) (xy 81.390472 -146.046951) (xy 81.445909 -146.053051) (xy 81.499866 -146.067157)
			(xy 81.551195 -146.088969) (xy 81.598801 -146.118023) (xy 81.641669 -146.153698) (xy 81.678886 -146.195235)
			(xy 81.709659 -146.241748) (xy 81.733331 -146.292245) (xy 81.749399 -146.345652) (xy 81.757519 -146.400828)
			(xy 81.758028 -146.428714) (xy 81.757519 -146.4566) (xy 81.749399 -146.511776) (xy 81.733331 -146.565183)
			(xy 81.709659 -146.61568) (xy 81.678886 -146.662193) (xy 81.641669 -146.70373) (xy 81.598801 -146.739405)
			(xy 81.551195 -146.768459) (xy 81.499866 -146.790271) (xy 81.445909 -146.804377) (xy 81.427415 -146.806412)
			(xy 85.1187 -146.806412) (xy 85.122771 -146.75079) (xy 85.134897 -146.696353) (xy 85.15482 -146.644262)
			(xy 85.182116 -146.595627) (xy 85.216202 -146.551484) (xy 85.256351 -146.512775) (xy 85.301709 -146.480324)
			(xy 85.351309 -146.454823) (xy 85.404093 -146.436816) (xy 85.458936 -146.426686) (xy 85.51467 -146.424649)
			(xy 85.570107 -146.430749) (xy 85.624064 -146.444855) (xy 85.675393 -146.466667) (xy 85.722999 -146.495721)
			(xy 85.765867 -146.531396) (xy 85.803084 -146.572933) (xy 85.833857 -146.619446) (xy 85.857529 -146.669943)
			(xy 85.873597 -146.72335) (xy 85.881717 -146.778526) (xy 85.882226 -146.806412) (xy 85.881717 -146.834298)
			(xy 85.873597 -146.889474) (xy 85.857529 -146.942881) (xy 85.833857 -146.993378) (xy 85.803084 -147.039891)
			(xy 85.765867 -147.081428) (xy 85.722999 -147.117103) (xy 85.675393 -147.146157) (xy 85.624064 -147.167969)
			(xy 85.570107 -147.182075) (xy 85.51467 -147.188175) (xy 85.458936 -147.186138) (xy 85.404093 -147.176008)
			(xy 85.351309 -147.158001) (xy 85.301709 -147.1325) (xy 85.256351 -147.100049) (xy 85.216202 -147.06134)
			(xy 85.182116 -147.017197) (xy 85.15482 -146.968562) (xy 85.134897 -146.916471) (xy 85.122771 -146.862034)
			(xy 85.1187 -146.806412) (xy 81.427415 -146.806412) (xy 81.390472 -146.810477) (xy 81.334738 -146.80844)
			(xy 81.279895 -146.79831) (xy 81.227111 -146.780303) (xy 81.177511 -146.754802) (xy 81.132153 -146.722351)
			(xy 81.092004 -146.683642) (xy 81.057918 -146.639499) (xy 81.030622 -146.590864) (xy 81.010699 -146.538773)
			(xy 80.998573 -146.484336) (xy 80.994502 -146.428714) (xy 27.89936 -146.428714) (xy 27.89936 -147.352004)
			(xy 86.714582 -147.352004) (xy 86.718653 -147.296382) (xy 86.730779 -147.241945) (xy 86.750702 -147.189854)
			(xy 86.777998 -147.141219) (xy 86.812084 -147.097076) (xy 86.852233 -147.058367) (xy 86.897591 -147.025916)
			(xy 86.947191 -147.000415) (xy 86.999975 -146.982408) (xy 87.054818 -146.972278) (xy 87.110552 -146.970241)
			(xy 87.165989 -146.976341) (xy 87.219946 -146.990447) (xy 87.271275 -147.012259) (xy 87.318881 -147.041313)
			(xy 87.361749 -147.076988) (xy 87.398966 -147.118525) (xy 87.429739 -147.165038) (xy 87.453411 -147.215535)
			(xy 87.469479 -147.268942) (xy 87.477599 -147.324118) (xy 87.478108 -147.352004) (xy 87.477599 -147.37989)
			(xy 87.469479 -147.435066) (xy 87.453411 -147.488473) (xy 87.429739 -147.53897) (xy 87.398966 -147.585483)
			(xy 87.361749 -147.62702) (xy 87.318881 -147.662695) (xy 87.271275 -147.691749) (xy 87.219946 -147.713561)
			(xy 87.165989 -147.727667) (xy 87.110552 -147.733767) (xy 87.054818 -147.73173) (xy 86.999975 -147.7216)
			(xy 86.947191 -147.703593) (xy 86.897591 -147.678092) (xy 86.852233 -147.645641) (xy 86.812084 -147.606932)
			(xy 86.777998 -147.562789) (xy 86.750702 -147.514154) (xy 86.730779 -147.462063) (xy 86.718653 -147.407626)
			(xy 86.714582 -147.352004) (xy 27.89936 -147.352004) (xy 27.89936 -147.856194) (xy 80.721452 -147.856194)
			(xy 80.725523 -147.800572) (xy 80.737649 -147.746135) (xy 80.757572 -147.694044) (xy 80.784868 -147.645409)
			(xy 80.818954 -147.601266) (xy 80.859103 -147.562557) (xy 80.904461 -147.530106) (xy 80.954061 -147.504605)
			(xy 81.006845 -147.486598) (xy 81.061688 -147.476468) (xy 81.117422 -147.474431) (xy 81.172859 -147.480531)
			(xy 81.226816 -147.494637) (xy 81.278145 -147.516449) (xy 81.325751 -147.545503) (xy 81.368619 -147.581178)
			(xy 81.405836 -147.622715) (xy 81.436609 -147.669228) (xy 81.460281 -147.719725) (xy 81.476349 -147.773132)
			(xy 81.484469 -147.828308) (xy 81.484978 -147.856194) (xy 81.484469 -147.88408) (xy 81.476349 -147.939256)
			(xy 81.460281 -147.992663) (xy 81.436609 -148.04316) (xy 81.405836 -148.089673) (xy 81.368619 -148.13121)
			(xy 81.325751 -148.166885) (xy 81.278145 -148.195939) (xy 81.226816 -148.217751) (xy 81.172859 -148.231857)
			(xy 81.117422 -148.237957) (xy 81.061688 -148.23592) (xy 81.006845 -148.22579) (xy 80.954061 -148.207783)
			(xy 80.904461 -148.182282) (xy 80.859103 -148.149831) (xy 80.818954 -148.111122) (xy 80.784868 -148.066979)
			(xy 80.757572 -148.018344) (xy 80.737649 -147.966253) (xy 80.725523 -147.911816) (xy 80.721452 -147.856194)
			(xy 27.89936 -147.856194) (xy 27.89936 -148.51761) (xy 83.345526 -148.51761) (xy 83.349597 -148.461988)
			(xy 83.361723 -148.407551) (xy 83.381646 -148.35546) (xy 83.408942 -148.306825) (xy 83.443028 -148.262682)
			(xy 83.483177 -148.223973) (xy 83.528535 -148.191522) (xy 83.578135 -148.166021) (xy 83.630919 -148.148014)
			(xy 83.685762 -148.137884) (xy 83.741496 -148.135847) (xy 83.796933 -148.141947) (xy 83.85089 -148.156053)
			(xy 83.902219 -148.177865) (xy 83.949825 -148.206919) (xy 83.992693 -148.242594) (xy 84.02991 -148.284131)
			(xy 84.060683 -148.330644) (xy 84.084355 -148.381141) (xy 84.100423 -148.434548) (xy 84.108543 -148.489724)
			(xy 84.109052 -148.51761) (xy 84.108543 -148.545496) (xy 84.100423 -148.600672) (xy 84.084355 -148.654079)
			(xy 84.060683 -148.704576) (xy 84.02991 -148.751089) (xy 83.992693 -148.792626) (xy 83.949825 -148.828301)
			(xy 83.902219 -148.857355) (xy 83.85089 -148.879167) (xy 83.796933 -148.893273) (xy 83.741496 -148.899373)
			(xy 83.685762 -148.897336) (xy 83.630919 -148.887206) (xy 83.578135 -148.869199) (xy 83.528535 -148.843698)
			(xy 83.483177 -148.811247) (xy 83.443028 -148.772538) (xy 83.408942 -148.728395) (xy 83.381646 -148.67976)
			(xy 83.361723 -148.627669) (xy 83.349597 -148.573232) (xy 83.345526 -148.51761) (xy 27.89936 -148.51761)
			(xy 27.89936 -148.90242) (xy 85.31428 -148.90242) (xy 85.318351 -148.846798) (xy 85.330477 -148.792361)
			(xy 85.3504 -148.74027) (xy 85.377696 -148.691635) (xy 85.411782 -148.647492) (xy 85.451931 -148.608783)
			(xy 85.497289 -148.576332) (xy 85.546889 -148.550831) (xy 85.599673 -148.532824) (xy 85.654516 -148.522694)
			(xy 85.71025 -148.520657) (xy 85.765687 -148.526757) (xy 85.819644 -148.540863) (xy 85.870973 -148.562675)
			(xy 85.918579 -148.591729) (xy 85.961447 -148.627404) (xy 85.998664 -148.668941) (xy 86.029437 -148.715454)
			(xy 86.053109 -148.765951) (xy 86.069177 -148.819358) (xy 86.077297 -148.874534) (xy 86.077806 -148.90242)
			(xy 86.077297 -148.930306) (xy 86.069177 -148.985482) (xy 86.053109 -149.038889) (xy 86.029437 -149.089386)
			(xy 85.998664 -149.135899) (xy 85.961447 -149.177436) (xy 85.918579 -149.213111) (xy 85.870973 -149.242165)
			(xy 85.819644 -149.263977) (xy 85.765687 -149.278083) (xy 85.71025 -149.284183) (xy 85.654516 -149.282146)
			(xy 85.599673 -149.272016) (xy 85.546889 -149.254009) (xy 85.497289 -149.228508) (xy 85.451931 -149.196057)
			(xy 85.411782 -149.157348) (xy 85.377696 -149.113205) (xy 85.3504 -149.06457) (xy 85.330477 -149.012479)
			(xy 85.318351 -148.958042) (xy 85.31428 -148.90242) (xy 27.89936 -148.90242) (xy 27.89936 -150.919027)
			(xy 58.029594 -150.919027) (xy 58.029594 -150.847705) (xy 58.03758 -150.776831) (xy 58.05345 -150.707296)
			(xy 58.077007 -150.639976) (xy 58.107952 -150.575717) (xy 58.145898 -150.515326) (xy 58.190367 -150.459564)
			(xy 58.2408 -150.409131) (xy 58.296562 -150.364662) (xy 58.356953 -150.326716) (xy 58.421212 -150.295771)
			(xy 58.488532 -150.272214) (xy 58.558067 -150.256344) (xy 58.628941 -150.248358) (xy 58.700263 -150.248358)
			(xy 58.771137 -150.256344) (xy 58.840672 -150.272214) (xy 58.907992 -150.295771) (xy 58.972251 -150.326716)
			(xy 59.032642 -150.364662) (xy 59.088404 -150.409131) (xy 59.138837 -150.459564) (xy 59.183306 -150.515326)
			(xy 59.221252 -150.575717) (xy 59.252197 -150.639976) (xy 59.275754 -150.707296) (xy 59.291624 -150.776831)
			(xy 59.29961 -150.847705) (xy 59.30011 -150.883366) (xy 59.29961 -150.919027) (xy 59.916306 -150.919027)
			(xy 59.916306 -150.847705) (xy 59.924292 -150.776831) (xy 59.940162 -150.707296) (xy 59.963719 -150.639976)
			(xy 59.994664 -150.575717) (xy 60.03261 -150.515326) (xy 60.077079 -150.459564) (xy 60.127512 -150.409131)
			(xy 60.183274 -150.364662) (xy 60.243665 -150.326716) (xy 60.307924 -150.295771) (xy 60.375244 -150.272214)
			(xy 60.444779 -150.256344) (xy 60.515653 -150.248358) (xy 60.586975 -150.248358) (xy 60.657849 -150.256344)
			(xy 60.727384 -150.272214) (xy 60.794704 -150.295771) (xy 60.858963 -150.326716) (xy 60.919354 -150.364662)
			(xy 60.975116 -150.409131) (xy 61.025549 -150.459564) (xy 61.070018 -150.515326) (xy 61.107964 -150.575717)
			(xy 61.138909 -150.639976) (xy 61.162466 -150.707296) (xy 61.178336 -150.776831) (xy 61.186322 -150.847705)
			(xy 61.186822 -150.883366) (xy 61.186322 -150.919027) (xy 62.157348 -150.919027) (xy 62.157348 -150.847705)
			(xy 62.165334 -150.776831) (xy 62.181204 -150.707296) (xy 62.204761 -150.639976) (xy 62.235706 -150.575717)
			(xy 62.273652 -150.515326) (xy 62.318121 -150.459564) (xy 62.368554 -150.409131) (xy 62.424316 -150.364662)
			(xy 62.484707 -150.326716) (xy 62.548966 -150.295771) (xy 62.616286 -150.272214) (xy 62.685821 -150.256344)
			(xy 62.756695 -150.248358) (xy 62.828017 -150.248358) (xy 62.898891 -150.256344) (xy 62.968426 -150.272214)
			(xy 63.035746 -150.295771) (xy 63.100005 -150.326716) (xy 63.160396 -150.364662) (xy 63.216158 -150.409131)
			(xy 63.266591 -150.459564) (xy 63.31106 -150.515326) (xy 63.349006 -150.575717) (xy 63.379951 -150.639976)
			(xy 63.403508 -150.707296) (xy 63.419378 -150.776831) (xy 63.427364 -150.847705) (xy 63.427864 -150.883366)
			(xy 63.427364 -150.919027) (xy 64.061332 -150.919027) (xy 64.061332 -150.847705) (xy 64.069318 -150.776831)
			(xy 64.085188 -150.707296) (xy 64.108745 -150.639976) (xy 64.13969 -150.575717) (xy 64.177636 -150.515326)
			(xy 64.222105 -150.459564) (xy 64.272538 -150.409131) (xy 64.3283 -150.364662) (xy 64.388691 -150.326716)
			(xy 64.45295 -150.295771) (xy 64.52027 -150.272214) (xy 64.589805 -150.256344) (xy 64.660679 -150.248358)
			(xy 64.732001 -150.248358) (xy 64.802875 -150.256344) (xy 64.87241 -150.272214) (xy 64.93973 -150.295771)
			(xy 65.003989 -150.326716) (xy 65.06438 -150.364662) (xy 65.120142 -150.409131) (xy 65.170575 -150.459564)
			(xy 65.215044 -150.515326) (xy 65.25299 -150.575717) (xy 65.283935 -150.639976) (xy 65.307492 -150.707296)
			(xy 65.323362 -150.776831) (xy 65.331348 -150.847705) (xy 65.331848 -150.883366) (xy 65.331348 -150.919027)
			(xy 65.323362 -150.989901) (xy 65.307492 -151.059436) (xy 65.283935 -151.126756) (xy 65.25299 -151.191015)
			(xy 65.215044 -151.251406) (xy 65.202481 -151.26716) (xy 71.969884 -151.26716) (xy 71.969884 -150.358348)
			(xy 71.97058 -150.322282) (xy 71.980899 -150.250891) (xy 71.990458 -150.216108) (xy 71.995284 -150.198582)
			(xy 71.995284 -149.82444) (xy 72.9615 -149.82444) (xy 72.9615 -150.198582) (xy 72.966326 -150.216108)
			(xy 72.975865 -150.250895) (xy 72.986194 -150.322284) (xy 72.9869 -150.358348) (xy 72.9869 -150.42261)
			(xy 73.401428 -150.42261) (xy 73.401428 -149.513798) (xy 73.40192 -149.481062) (xy 73.410362 -149.416136)
			(xy 73.427067 -149.352831) (xy 73.451759 -149.292193) (xy 73.48403 -149.235226) (xy 73.503282 -149.208744)
			(xy 73.528428 -149.174962) (xy 73.528428 -149.157944) (xy 73.543922 -149.157944) (xy 73.579736 -149.127464)
			(xy 73.604913 -149.106611) (xy 73.659645 -149.07086) (xy 73.71851 -149.042421) (xy 73.780535 -149.021766)
			(xy 73.844697 -149.009235) (xy 73.909936 -149.005035) (xy 73.975175 -149.009235) (xy 74.039337 -149.021766)
			(xy 74.101362 -149.042421) (xy 74.160227 -149.07086) (xy 74.214959 -149.106611) (xy 74.240136 -149.127464)
			(xy 74.27595 -149.157944) (xy 74.291444 -149.157944) (xy 74.291444 -149.174962) (xy 74.31659 -149.208744)
			(xy 74.331794 -149.229556) (xy 74.358385 -149.273712) (xy 74.369676 -149.296882) (xy 74.37695 -149.311112)
			(xy 74.397344 -149.335703) (xy 74.423206 -149.354458) (xy 74.452915 -149.366204) (xy 74.484611 -149.370202)
			(xy 74.516307 -149.366204) (xy 74.546016 -149.354458) (xy 74.571878 -149.335703) (xy 74.592272 -149.311112)
			(xy 74.599546 -149.296882) (xy 74.610816 -149.273701) (xy 74.637416 -149.229549) (xy 74.652632 -149.208744)
			(xy 74.678032 -149.174962) (xy 74.678032 -149.157944) (xy 74.693272 -149.157944) (xy 74.729086 -149.127464)
			(xy 74.754263 -149.106611) (xy 74.808995 -149.07086) (xy 74.86786 -149.042421) (xy 74.929885 -149.021766)
			(xy 74.994047 -149.009235) (xy 75.059286 -149.005035) (xy 75.124525 -149.009235) (xy 75.188687 -149.021766)
			(xy 75.250712 -149.042421) (xy 75.309577 -149.07086) (xy 75.364309 -149.106611) (xy 75.389486 -149.127464)
			(xy 75.4253 -149.157944) (xy 75.44054 -149.157944) (xy 75.44054 -149.174962) (xy 75.46594 -149.208744)
			(xy 75.485154 -149.235243) (xy 75.517386 -149.292212) (xy 75.542029 -149.35285) (xy 75.558504 -149.4155)
			(xy 80.319878 -149.4155) (xy 80.323949 -149.359878) (xy 80.336075 -149.305441) (xy 80.355998 -149.25335)
			(xy 80.383294 -149.204715) (xy 80.41738 -149.160572) (xy 80.457529 -149.121863) (xy 80.502887 -149.089412)
			(xy 80.552487 -149.063911) (xy 80.605271 -149.045904) (xy 80.660114 -149.035774) (xy 80.715848 -149.033737)
			(xy 80.771285 -149.039837) (xy 80.825242 -149.053943) (xy 80.876571 -149.075755) (xy 80.924177 -149.104809)
			(xy 80.967045 -149.140484) (xy 81.004262 -149.182021) (xy 81.035035 -149.228534) (xy 81.058707 -149.279031)
			(xy 81.074775 -149.332438) (xy 81.082895 -149.387614) (xy 81.083404 -149.4155) (xy 81.082895 -149.443386)
			(xy 81.074775 -149.498562) (xy 81.058707 -149.551969) (xy 81.035035 -149.602466) (xy 81.00665 -149.64537)
			(xy 81.850736 -149.64537) (xy 81.854807 -149.589748) (xy 81.866933 -149.535311) (xy 81.886856 -149.48322)
			(xy 81.914152 -149.434585) (xy 81.948238 -149.390442) (xy 81.988387 -149.351733) (xy 82.033745 -149.319282)
			(xy 82.083345 -149.293781) (xy 82.136129 -149.275774) (xy 82.190972 -149.265644) (xy 82.246706 -149.263607)
			(xy 82.302143 -149.269707) (xy 82.3561 -149.283813) (xy 82.407429 -149.305625) (xy 82.455035 -149.334679)
			(xy 82.497903 -149.370354) (xy 82.53512 -149.411891) (xy 82.565893 -149.458404) (xy 82.589565 -149.508901)
			(xy 82.605633 -149.562308) (xy 82.613753 -149.617484) (xy 82.614262 -149.64537) (xy 82.613753 -149.673256)
			(xy 82.605633 -149.728432) (xy 82.589565 -149.781839) (xy 82.575548 -149.81174) (xy 83.9122 -149.81174)
			(xy 83.916271 -149.756118) (xy 83.928397 -149.701681) (xy 83.94832 -149.64959) (xy 83.975616 -149.600955)
			(xy 84.009702 -149.556812) (xy 84.049851 -149.518103) (xy 84.095209 -149.485652) (xy 84.144809 -149.460151)
			(xy 84.197593 -149.442144) (xy 84.252436 -149.432014) (xy 84.30817 -149.429977) (xy 84.363607 -149.436077)
			(xy 84.417564 -149.450183) (xy 84.468893 -149.471995) (xy 84.516499 -149.501049) (xy 84.559367 -149.536724)
			(xy 84.596584 -149.578261) (xy 84.627357 -149.624774) (xy 84.651029 -149.675271) (xy 84.667097 -149.728678)
			(xy 84.675217 -149.783854) (xy 84.675726 -149.81174) (xy 84.675217 -149.839626) (xy 84.667097 -149.894802)
			(xy 84.651029 -149.948209) (xy 84.627357 -149.998706) (xy 84.596584 -150.045219) (xy 84.559367 -150.086756)
			(xy 84.516499 -150.122431) (xy 84.468893 -150.151485) (xy 84.417564 -150.173297) (xy 84.363607 -150.187403)
			(xy 84.30817 -150.193503) (xy 84.252436 -150.191466) (xy 84.197593 -150.181336) (xy 84.144809 -150.163329)
			(xy 84.095209 -150.137828) (xy 84.049851 -150.105377) (xy 84.009702 -150.066668) (xy 83.975616 -150.022525)
			(xy 83.94832 -149.97389) (xy 83.928397 -149.921799) (xy 83.916271 -149.867362) (xy 83.9122 -149.81174)
			(xy 82.575548 -149.81174) (xy 82.565893 -149.832336) (xy 82.53512 -149.878849) (xy 82.497903 -149.920386)
			(xy 82.455035 -149.956061) (xy 82.407429 -149.985115) (xy 82.3561 -150.006927) (xy 82.302143 -150.021033)
			(xy 82.246706 -150.027133) (xy 82.190972 -150.025096) (xy 82.136129 -150.014966) (xy 82.083345 -149.996959)
			(xy 82.033745 -149.971458) (xy 81.988387 -149.939007) (xy 81.948238 -149.900298) (xy 81.914152 -149.856155)
			(xy 81.886856 -149.80752) (xy 81.866933 -149.755429) (xy 81.854807 -149.700992) (xy 81.850736 -149.64537)
			(xy 81.00665 -149.64537) (xy 81.004262 -149.648979) (xy 80.967045 -149.690516) (xy 80.924177 -149.726191)
			(xy 80.876571 -149.755245) (xy 80.825242 -149.777057) (xy 80.771285 -149.791163) (xy 80.715848 -149.797263)
			(xy 80.660114 -149.795226) (xy 80.605271 -149.785096) (xy 80.552487 -149.767089) (xy 80.502887 -149.741588)
			(xy 80.457529 -149.709137) (xy 80.41738 -149.670428) (xy 80.383294 -149.626285) (xy 80.355998 -149.57765)
			(xy 80.336075 -149.525559) (xy 80.323949 -149.471122) (xy 80.319878 -149.4155) (xy 75.558504 -149.4155)
			(xy 75.558676 -149.416153) (xy 75.567049 -149.48107) (xy 75.56754 -149.513798) (xy 75.56754 -150.42261)
			(xy 75.567145 -150.455064) (xy 75.558894 -150.519445) (xy 75.542516 -150.582252) (xy 75.518275 -150.642463)
			(xy 75.486568 -150.699099) (xy 75.481585 -150.70582) (xy 80.86039 -150.70582) (xy 80.864461 -150.650198)
			(xy 80.876587 -150.595761) (xy 80.89651 -150.54367) (xy 80.923806 -150.495035) (xy 80.957892 -150.450892)
			(xy 80.998041 -150.412183) (xy 81.043399 -150.379732) (xy 81.092999 -150.354231) (xy 81.145783 -150.336224)
			(xy 81.200626 -150.326094) (xy 81.25636 -150.324057) (xy 81.311797 -150.330157) (xy 81.365754 -150.344263)
			(xy 81.417083 -150.366075) (xy 81.464689 -150.395129) (xy 81.507557 -150.430804) (xy 81.544774 -150.472341)
			(xy 81.575547 -150.518854) (xy 81.599219 -150.569351) (xy 81.615287 -150.622758) (xy 81.623407 -150.677934)
			(xy 81.623916 -150.70582) (xy 81.623407 -150.733706) (xy 81.615287 -150.788882) (xy 81.599219 -150.842289)
			(xy 81.575547 -150.892786) (xy 81.544774 -150.939299) (xy 81.507557 -150.980836) (xy 81.464689 -151.016511)
			(xy 81.417083 -151.045565) (xy 81.365754 -151.067377) (xy 81.311797 -151.081483) (xy 81.25636 -151.087583)
			(xy 81.200626 -151.085546) (xy 81.145783 -151.075416) (xy 81.092999 -151.057409) (xy 81.043399 -151.031908)
			(xy 80.998041 -150.999457) (xy 80.957892 -150.960748) (xy 80.923806 -150.916605) (xy 80.89651 -150.86797)
			(xy 80.876587 -150.815879) (xy 80.864461 -150.761442) (xy 80.86039 -150.70582) (xy 75.481585 -150.70582)
			(xy 75.447909 -150.751238) (xy 75.402928 -150.798032) (xy 75.352356 -150.838719) (xy 75.297017 -150.872639)
			(xy 75.23781 -150.899238) (xy 75.175698 -150.918084) (xy 75.111694 -150.928871) (xy 75.046836 -150.931423)
			(xy 74.982182 -150.925698) (xy 74.918782 -150.91179) (xy 74.857668 -150.889924) (xy 74.799835 -150.860458)
			(xy 74.746223 -150.823869) (xy 74.697704 -150.780754) (xy 74.676 -150.75662) (xy 74.661419 -150.740545)
			(xy 74.627775 -150.713135) (xy 74.589959 -150.691847) (xy 74.549073 -150.677301) (xy 74.506309 -150.66992)
			(xy 74.462913 -150.66992) (xy 74.420149 -150.677301) (xy 74.379263 -150.691847) (xy 74.341447 -150.713135)
			(xy 74.307803 -150.740545) (xy 74.293222 -150.75662) (xy 74.271591 -150.780828) (xy 74.223062 -150.823956)
			(xy 74.169437 -150.860555) (xy 74.11159 -150.89003) (xy 74.050462 -150.911902) (xy 73.987047 -150.925815)
			(xy 73.922376 -150.931543) (xy 73.857503 -150.928991) (xy 73.793482 -150.918203) (xy 73.731355 -150.899353)
			(xy 73.672133 -150.872748) (xy 73.616779 -150.838821) (xy 73.566195 -150.798124) (xy 73.521202 -150.751319)
			(xy 73.482533 -150.699167) (xy 73.450817 -150.642517) (xy 73.426571 -150.582291) (xy 73.410188 -150.519469)
			(xy 73.401935 -150.455072) (xy 73.401428 -150.42261) (xy 72.9869 -150.42261) (xy 72.9869 -151.212804)
			(xy 84.390482 -151.212804) (xy 84.394553 -151.157182) (xy 84.406679 -151.102745) (xy 84.426602 -151.050654)
			(xy 84.453898 -151.002019) (xy 84.487984 -150.957876) (xy 84.528133 -150.919167) (xy 84.573491 -150.886716)
			(xy 84.623091 -150.861215) (xy 84.675875 -150.843208) (xy 84.730718 -150.833078) (xy 84.786452 -150.831041)
			(xy 84.841889 -150.837141) (xy 84.895846 -150.851247) (xy 84.947175 -150.873059) (xy 84.994781 -150.902113)
			(xy 85.037649 -150.937788) (xy 85.074866 -150.979325) (xy 85.105639 -151.025838) (xy 85.129311 -151.076335)
			(xy 85.145379 -151.129742) (xy 85.153499 -151.184918) (xy 85.154008 -151.212804) (xy 85.153499 -151.24069)
			(xy 85.145379 -151.295866) (xy 85.129311 -151.349273) (xy 85.105639 -151.39977) (xy 85.074866 -151.446283)
			(xy 85.037649 -151.48782) (xy 84.994781 -151.523495) (xy 84.947175 -151.552549) (xy 84.895846 -151.574361)
			(xy 84.841889 -151.588467) (xy 84.786452 -151.594567) (xy 84.730718 -151.59253) (xy 84.675875 -151.5824)
			(xy 84.623091 -151.564393) (xy 84.573491 -151.538892) (xy 84.528133 -151.506441) (xy 84.487984 -151.467732)
			(xy 84.453898 -151.423589) (xy 84.426602 -151.374954) (xy 84.406679 -151.322863) (xy 84.394553 -151.268426)
			(xy 84.390482 -151.212804) (xy 72.9869 -151.212804) (xy 72.9869 -151.26716) (xy 72.986398 -151.299121)
			(xy 72.978387 -151.362539) (xy 72.96249 -151.424453) (xy 72.938958 -151.483886) (xy 72.908164 -151.539901)
			(xy 72.870591 -151.591616) (xy 72.826834 -151.638213) (xy 72.777581 -151.678958) (xy 72.72361 -151.713209)
			(xy 72.665771 -151.740426) (xy 72.604978 -151.760179) (xy 72.542188 -151.772157) (xy 72.478392 -151.776171)
			(xy 72.414596 -151.772157) (xy 72.351806 -151.760179) (xy 72.291013 -151.740426) (xy 72.233174 -151.713209)
			(xy 72.179203 -151.678958) (xy 72.12995 -151.638213) (xy 72.086193 -151.591616) (xy 72.04862 -151.539901)
			(xy 72.017826 -151.483886) (xy 71.994294 -151.424453) (xy 71.978397 -151.362539) (xy 71.970386 -151.299121)
			(xy 71.969884 -151.26716) (xy 65.202481 -151.26716) (xy 65.170575 -151.307168) (xy 65.120142 -151.357601)
			(xy 65.06438 -151.40207) (xy 65.003989 -151.440016) (xy 64.93973 -151.470961) (xy 64.87241 -151.494518)
			(xy 64.802875 -151.510388) (xy 64.732001 -151.518374) (xy 64.660679 -151.518374) (xy 64.589805 -151.510388)
			(xy 64.52027 -151.494518) (xy 64.45295 -151.470961) (xy 64.388691 -151.440016) (xy 64.3283 -151.40207)
			(xy 64.272538 -151.357601) (xy 64.222105 -151.307168) (xy 64.177636 -151.251406) (xy 64.13969 -151.191015)
			(xy 64.108745 -151.126756) (xy 64.085188 -151.059436) (xy 64.069318 -150.989901) (xy 64.061332 -150.919027)
			(xy 63.427364 -150.919027) (xy 63.419378 -150.989901) (xy 63.403508 -151.059436) (xy 63.379951 -151.126756)
			(xy 63.349006 -151.191015) (xy 63.31106 -151.251406) (xy 63.266591 -151.307168) (xy 63.216158 -151.357601)
			(xy 63.160396 -151.40207) (xy 63.100005 -151.440016) (xy 63.035746 -151.470961) (xy 62.968426 -151.494518)
			(xy 62.898891 -151.510388) (xy 62.828017 -151.518374) (xy 62.756695 -151.518374) (xy 62.685821 -151.510388)
			(xy 62.616286 -151.494518) (xy 62.548966 -151.470961) (xy 62.484707 -151.440016) (xy 62.424316 -151.40207)
			(xy 62.368554 -151.357601) (xy 62.318121 -151.307168) (xy 62.273652 -151.251406) (xy 62.235706 -151.191015)
			(xy 62.204761 -151.126756) (xy 62.181204 -151.059436) (xy 62.165334 -150.989901) (xy 62.157348 -150.919027)
			(xy 61.186322 -150.919027) (xy 61.178336 -150.989901) (xy 61.162466 -151.059436) (xy 61.138909 -151.126756)
			(xy 61.107964 -151.191015) (xy 61.070018 -151.251406) (xy 61.025549 -151.307168) (xy 60.975116 -151.357601)
			(xy 60.919354 -151.40207) (xy 60.858963 -151.440016) (xy 60.794704 -151.470961) (xy 60.727384 -151.494518)
			(xy 60.657849 -151.510388) (xy 60.586975 -151.518374) (xy 60.515653 -151.518374) (xy 60.444779 -151.510388)
			(xy 60.375244 -151.494518) (xy 60.307924 -151.470961) (xy 60.243665 -151.440016) (xy 60.183274 -151.40207)
			(xy 60.127512 -151.357601) (xy 60.077079 -151.307168) (xy 60.03261 -151.251406) (xy 59.994664 -151.191015)
			(xy 59.963719 -151.126756) (xy 59.940162 -151.059436) (xy 59.924292 -150.989901) (xy 59.916306 -150.919027)
			(xy 59.29961 -150.919027) (xy 59.291624 -150.989901) (xy 59.275754 -151.059436) (xy 59.252197 -151.126756)
			(xy 59.221252 -151.191015) (xy 59.183306 -151.251406) (xy 59.138837 -151.307168) (xy 59.088404 -151.357601)
			(xy 59.032642 -151.40207) (xy 58.972251 -151.440016) (xy 58.907992 -151.470961) (xy 58.840672 -151.494518)
			(xy 58.771137 -151.510388) (xy 58.700263 -151.518374) (xy 58.628941 -151.518374) (xy 58.558067 -151.510388)
			(xy 58.488532 -151.494518) (xy 58.421212 -151.470961) (xy 58.356953 -151.440016) (xy 58.296562 -151.40207)
			(xy 58.2408 -151.357601) (xy 58.190367 -151.307168) (xy 58.145898 -151.251406) (xy 58.107952 -151.191015)
			(xy 58.077007 -151.126756) (xy 58.05345 -151.059436) (xy 58.03758 -150.989901) (xy 58.029594 -150.919027)
			(xy 27.89936 -150.919027) (xy 27.89936 -151.965575) (xy 48.168042 -151.965575) (xy 48.168042 -151.884465)
			(xy 48.175992 -151.803746) (xy 48.191815 -151.724195) (xy 48.21536 -151.646579) (xy 48.246399 -151.571643)
			(xy 48.284634 -151.500111) (xy 48.329696 -151.432671) (xy 48.381151 -151.369972) (xy 48.438504 -151.312619)
			(xy 48.501203 -151.261164) (xy 48.568643 -151.216102) (xy 48.640175 -151.177867) (xy 48.715111 -151.146828)
			(xy 48.792727 -151.123283) (xy 48.872278 -151.10746) (xy 48.952997 -151.09951) (xy 49.034107 -151.09951)
			(xy 49.114826 -151.10746) (xy 49.194377 -151.123283) (xy 49.271993 -151.146828) (xy 49.346929 -151.177867)
			(xy 49.418461 -151.216102) (xy 49.485901 -151.261164) (xy 49.5486 -151.312619) (xy 49.605953 -151.369972)
			(xy 49.657408 -151.432671) (xy 49.70247 -151.500111) (xy 49.740705 -151.571643) (xy 49.771744 -151.646579)
			(xy 49.795289 -151.724195) (xy 49.811112 -151.803746) (xy 49.819062 -151.884465) (xy 49.81956 -151.92502)
			(xy 49.819062 -151.965575) (xy 49.811112 -152.046294) (xy 49.795289 -152.125845) (xy 49.771744 -152.203461)
			(xy 49.740705 -152.278397) (xy 49.70247 -152.349929) (xy 49.657408 -152.417369) (xy 49.605953 -152.480068)
			(xy 49.5486 -152.537421) (xy 49.485901 -152.588876) (xy 49.418461 -152.633938) (xy 49.346929 -152.672173)
			(xy 49.271993 -152.703212) (xy 49.194377 -152.726757) (xy 49.114826 -152.74258) (xy 49.034107 -152.75053)
			(xy 48.952997 -152.75053) (xy 48.872278 -152.74258) (xy 48.792727 -152.726757) (xy 48.715111 -152.703212)
			(xy 48.640175 -152.672173) (xy 48.568643 -152.633938) (xy 48.501203 -152.588876) (xy 48.438504 -152.537421)
			(xy 48.381151 -152.480068) (xy 48.329696 -152.417369) (xy 48.284634 -152.349929) (xy 48.246399 -152.278397)
			(xy 48.21536 -152.203461) (xy 48.191815 -152.125845) (xy 48.175992 -152.046294) (xy 48.168042 -151.965575)
			(xy 27.89936 -151.965575) (xy 27.89936 -152.819963) (xy 58.029594 -152.819963) (xy 58.029594 -152.748641)
			(xy 58.03758 -152.677767) (xy 58.05345 -152.608232) (xy 58.077007 -152.540912) (xy 58.107952 -152.476653)
			(xy 58.145898 -152.416262) (xy 58.190367 -152.3605) (xy 58.2408 -152.310067) (xy 58.296562 -152.265598)
			(xy 58.356953 -152.227652) (xy 58.421212 -152.196707) (xy 58.488532 -152.17315) (xy 58.558067 -152.15728)
			(xy 58.628941 -152.149294) (xy 58.700263 -152.149294) (xy 58.771137 -152.15728) (xy 58.840672 -152.17315)
			(xy 58.907992 -152.196707) (xy 58.972251 -152.227652) (xy 59.032642 -152.265598) (xy 59.088404 -152.310067)
			(xy 59.138837 -152.3605) (xy 59.183306 -152.416262) (xy 59.221252 -152.476653) (xy 59.252197 -152.540912)
			(xy 59.275754 -152.608232) (xy 59.291624 -152.677767) (xy 59.29961 -152.748641) (xy 59.30011 -152.784302)
			(xy 59.29961 -152.819963) (xy 59.916306 -152.819963) (xy 59.916306 -152.748641) (xy 59.924292 -152.677767)
			(xy 59.940162 -152.608232) (xy 59.963719 -152.540912) (xy 59.994664 -152.476653) (xy 60.03261 -152.416262)
			(xy 60.077079 -152.3605) (xy 60.127512 -152.310067) (xy 60.183274 -152.265598) (xy 60.243665 -152.227652)
			(xy 60.307924 -152.196707) (xy 60.375244 -152.17315) (xy 60.444779 -152.15728) (xy 60.515653 -152.149294)
			(xy 60.586975 -152.149294) (xy 60.657849 -152.15728) (xy 60.727384 -152.17315) (xy 60.794704 -152.196707)
			(xy 60.858963 -152.227652) (xy 60.919354 -152.265598) (xy 60.975116 -152.310067) (xy 61.025549 -152.3605)
			(xy 61.070018 -152.416262) (xy 61.107964 -152.476653) (xy 61.138909 -152.540912) (xy 61.162466 -152.608232)
			(xy 61.178336 -152.677767) (xy 61.186322 -152.748641) (xy 61.186822 -152.784302) (xy 61.186322 -152.819963)
			(xy 62.157348 -152.819963) (xy 62.157348 -152.748641) (xy 62.165334 -152.677767) (xy 62.181204 -152.608232)
			(xy 62.204761 -152.540912) (xy 62.235706 -152.476653) (xy 62.273652 -152.416262) (xy 62.318121 -152.3605)
			(xy 62.368554 -152.310067) (xy 62.424316 -152.265598) (xy 62.484707 -152.227652) (xy 62.548966 -152.196707)
			(xy 62.616286 -152.17315) (xy 62.685821 -152.15728) (xy 62.756695 -152.149294) (xy 62.828017 -152.149294)
			(xy 62.898891 -152.15728) (xy 62.968426 -152.17315) (xy 63.035746 -152.196707) (xy 63.100005 -152.227652)
			(xy 63.160396 -152.265598) (xy 63.216158 -152.310067) (xy 63.266591 -152.3605) (xy 63.31106 -152.416262)
			(xy 63.349006 -152.476653) (xy 63.379951 -152.540912) (xy 63.403508 -152.608232) (xy 63.419378 -152.677767)
			(xy 63.427364 -152.748641) (xy 63.427864 -152.784302) (xy 63.427364 -152.819963) (xy 64.061332 -152.819963)
			(xy 64.061332 -152.748641) (xy 64.069318 -152.677767) (xy 64.085188 -152.608232) (xy 64.108745 -152.540912)
			(xy 64.13969 -152.476653) (xy 64.177636 -152.416262) (xy 64.222105 -152.3605) (xy 64.272538 -152.310067)
			(xy 64.3283 -152.265598) (xy 64.388691 -152.227652) (xy 64.45295 -152.196707) (xy 64.52027 -152.17315)
			(xy 64.589805 -152.15728) (xy 64.660679 -152.149294) (xy 64.732001 -152.149294) (xy 64.795189 -152.156414)
			(xy 81.34045 -152.156414) (xy 81.344521 -152.100792) (xy 81.356647 -152.046355) (xy 81.37657 -151.994264)
			(xy 81.403866 -151.945629) (xy 81.437952 -151.901486) (xy 81.478101 -151.862777) (xy 81.523459 -151.830326)
			(xy 81.573059 -151.804825) (xy 81.625843 -151.786818) (xy 81.680686 -151.776688) (xy 81.73642 -151.774651)
			(xy 81.791857 -151.780751) (xy 81.845814 -151.794857) (xy 81.897143 -151.816669) (xy 81.944749 -151.845723)
			(xy 81.987617 -151.881398) (xy 82.024834 -151.922935) (xy 82.055607 -151.969448) (xy 82.079279 -152.019945)
			(xy 82.095347 -152.073352) (xy 82.103467 -152.128528) (xy 82.103976 -152.156414) (xy 82.103467 -152.1843)
			(xy 82.095347 -152.239476) (xy 82.079279 -152.292883) (xy 82.055607 -152.34338) (xy 82.024834 -152.389893)
			(xy 81.987617 -152.43143) (xy 81.944749 -152.467105) (xy 81.897143 -152.496159) (xy 81.845814 -152.517971)
			(xy 81.791857 -152.532077) (xy 81.73642 -152.538177) (xy 81.680686 -152.53614) (xy 81.625843 -152.52601)
			(xy 81.573059 -152.508003) (xy 81.523459 -152.482502) (xy 81.478101 -152.450051) (xy 81.437952 -152.411342)
			(xy 81.403866 -152.367199) (xy 81.37657 -152.318564) (xy 81.356647 -152.266473) (xy 81.344521 -152.212036)
			(xy 81.34045 -152.156414) (xy 64.795189 -152.156414) (xy 64.802875 -152.15728) (xy 64.87241 -152.17315)
			(xy 64.93973 -152.196707) (xy 65.003989 -152.227652) (xy 65.06438 -152.265598) (xy 65.120142 -152.310067)
			(xy 65.170575 -152.3605) (xy 65.215044 -152.416262) (xy 65.25299 -152.476653) (xy 65.283935 -152.540912)
			(xy 65.307492 -152.608232) (xy 65.323362 -152.677767) (xy 65.331348 -152.748641) (xy 65.331848 -152.784302)
			(xy 65.331348 -152.819963) (xy 65.323362 -152.890837) (xy 65.307492 -152.960372) (xy 65.283935 -153.027692)
			(xy 65.25299 -153.091951) (xy 65.215044 -153.152342) (xy 65.170575 -153.208104) (xy 65.120142 -153.258537)
			(xy 65.06438 -153.303006) (xy 65.003989 -153.340952) (xy 64.964186 -153.36012) (xy 86.39887 -153.36012)
			(xy 86.402874 -153.160022) (xy 86.414881 -152.960244) (xy 86.434872 -152.761107) (xy 86.462814 -152.562929)
			(xy 86.498662 -152.366027) (xy 86.54236 -152.170718) (xy 86.593837 -151.977313) (xy 86.653011 -151.786123)
			(xy 86.719787 -151.597453) (xy 86.794059 -151.411606) (xy 86.875706 -151.228879) (xy 86.964599 -151.049566)
			(xy 87.060595 -150.873952) (xy 87.16354 -150.70232) (xy 87.27327 -150.534944) (xy 87.389608 -150.372093)
			(xy 87.512369 -150.214026) (xy 87.641356 -150.060998) (xy 87.776363 -149.913253) (xy 87.917172 -149.771027)
			(xy 88.063559 -149.63455) (xy 88.215289 -149.504038) (xy 88.37212 -149.379702) (xy 88.533799 -149.26174)
			(xy 88.700069 -149.150341) (xy 88.870662 -149.045684) (xy 89.045306 -148.947936) (xy 89.223722 -148.857253)
			(xy 89.405622 -148.773782) (xy 89.590717 -148.697655) (xy 89.778709 -148.628995) (xy 89.969298 -148.567911)
			(xy 90.162178 -148.514501) (xy 90.35704 -148.468852) (xy 90.553573 -148.431035) (xy 90.751462 -148.401111)
			(xy 90.950389 -148.379129) (xy 91.150037 -148.365124) (xy 91.350085 -148.359118) (xy 91.550213 -148.36112)
			(xy 91.750101 -148.371128) (xy 91.949428 -148.389125) (xy 92.147876 -148.415083) (xy 92.345126 -148.44896)
			(xy 92.540863 -148.490702) (xy 92.734773 -148.540241) (xy 92.926546 -148.597499) (xy 93.115875 -148.662384)
			(xy 93.302455 -148.734792) (xy 93.48599 -148.814608) (xy 93.666184 -148.901702) (xy 93.842749 -148.995936)
			(xy 94.015402 -149.097159) (xy 94.183867 -149.205209) (xy 94.347875 -149.319912) (xy 94.507162 -149.441086)
			(xy 94.661473 -149.568535) (xy 94.810561 -149.702056) (xy 94.954188 -149.841436) (xy 95.092124 -149.98645)
			(xy 95.224147 -150.136867) (xy 95.350046 -150.292445) (xy 95.46962 -150.452937) (xy 95.582676 -150.618083)
			(xy 95.689035 -150.787621) (xy 95.788526 -150.961279) (xy 95.880989 -151.138778) (xy 95.966276 -151.319834)
			(xy 96.044251 -151.504158) (xy 96.114788 -151.691454) (xy 96.177776 -151.881422) (xy 96.233113 -152.073758)
			(xy 96.28071 -152.268154) (xy 96.320491 -152.464299) (xy 96.352393 -152.661878) (xy 96.376364 -152.860575)
			(xy 96.392366 -153.060073) (xy 96.400373 -153.260051) (xy 96.400874 -153.36012) (xy 96.400373 -153.460189)
			(xy 96.392366 -153.660167) (xy 96.376364 -153.859665) (xy 96.352393 -154.058362) (xy 96.320491 -154.255941)
			(xy 96.28071 -154.452086) (xy 96.233113 -154.646482) (xy 96.177776 -154.838818) (xy 96.114788 -155.028786)
			(xy 96.044251 -155.216082) (xy 95.966276 -155.400406) (xy 95.880989 -155.581462) (xy 95.788526 -155.758961)
			(xy 95.689035 -155.932619) (xy 95.582676 -156.102157) (xy 95.46962 -156.267303) (xy 95.350046 -156.427795)
			(xy 95.224147 -156.583373) (xy 95.092124 -156.73379) (xy 94.954188 -156.878804) (xy 94.810561 -157.018184)
			(xy 94.661473 -157.151705) (xy 94.507162 -157.279154) (xy 94.347875 -157.400328) (xy 94.183867 -157.515031)
			(xy 94.015402 -157.623081) (xy 93.842749 -157.724304) (xy 93.666184 -157.818538) (xy 93.48599 -157.905632)
			(xy 93.302455 -157.985448) (xy 93.115875 -158.057856) (xy 92.926546 -158.122741) (xy 92.734773 -158.179999)
			(xy 92.540863 -158.229538) (xy 92.345126 -158.27128) (xy 92.147876 -158.305157) (xy 91.949428 -158.331115)
			(xy 91.750101 -158.349112) (xy 91.550213 -158.35912) (xy 91.350085 -158.361122) (xy 91.150037 -158.355116)
			(xy 90.950389 -158.341111) (xy 90.751462 -158.319129) (xy 90.553573 -158.289205) (xy 90.35704 -158.251388)
			(xy 90.162178 -158.205739) (xy 89.969298 -158.152329) (xy 89.778709 -158.091245) (xy 89.590717 -158.022585)
			(xy 89.405622 -157.946458) (xy 89.223722 -157.862987) (xy 89.045306 -157.772304) (xy 88.870662 -157.674556)
			(xy 88.700069 -157.569899) (xy 88.533799 -157.4585) (xy 88.37212 -157.340538) (xy 88.215289 -157.216202)
			(xy 88.063559 -157.08569) (xy 87.917172 -156.949213) (xy 87.776363 -156.806987) (xy 87.641356 -156.659242)
			(xy 87.512369 -156.506214) (xy 87.389608 -156.348147) (xy 87.27327 -156.185296) (xy 87.16354 -156.01792)
			(xy 87.060595 -155.846288) (xy 86.964599 -155.670674) (xy 86.875706 -155.491361) (xy 86.794059 -155.308634)
			(xy 86.719787 -155.122787) (xy 86.653011 -154.934117) (xy 86.593837 -154.742927) (xy 86.54236 -154.549522)
			(xy 86.498662 -154.354213) (xy 86.462814 -154.157311) (xy 86.434872 -153.959133) (xy 86.414881 -153.759996)
			(xy 86.402874 -153.560218) (xy 86.39887 -153.36012) (xy 64.964186 -153.36012) (xy 64.93973 -153.371897)
			(xy 64.87241 -153.395454) (xy 64.802875 -153.411324) (xy 64.732001 -153.41931) (xy 64.660679 -153.41931)
			(xy 64.589805 -153.411324) (xy 64.52027 -153.395454) (xy 64.45295 -153.371897) (xy 64.388691 -153.340952)
			(xy 64.3283 -153.303006) (xy 64.272538 -153.258537) (xy 64.222105 -153.208104) (xy 64.177636 -153.152342)
			(xy 64.13969 -153.091951) (xy 64.108745 -153.027692) (xy 64.085188 -152.960372) (xy 64.069318 -152.890837)
			(xy 64.061332 -152.819963) (xy 63.427364 -152.819963) (xy 63.419378 -152.890837) (xy 63.403508 -152.960372)
			(xy 63.379951 -153.027692) (xy 63.349006 -153.091951) (xy 63.31106 -153.152342) (xy 63.266591 -153.208104)
			(xy 63.216158 -153.258537) (xy 63.160396 -153.303006) (xy 63.100005 -153.340952) (xy 63.035746 -153.371897)
			(xy 62.968426 -153.395454) (xy 62.898891 -153.411324) (xy 62.828017 -153.41931) (xy 62.756695 -153.41931)
			(xy 62.685821 -153.411324) (xy 62.616286 -153.395454) (xy 62.548966 -153.371897) (xy 62.484707 -153.340952)
			(xy 62.424316 -153.303006) (xy 62.368554 -153.258537) (xy 62.318121 -153.208104) (xy 62.273652 -153.152342)
			(xy 62.235706 -153.091951) (xy 62.204761 -153.027692) (xy 62.181204 -152.960372) (xy 62.165334 -152.890837)
			(xy 62.157348 -152.819963) (xy 61.186322 -152.819963) (xy 61.178336 -152.890837) (xy 61.162466 -152.960372)
			(xy 61.138909 -153.027692) (xy 61.107964 -153.091951) (xy 61.070018 -153.152342) (xy 61.025549 -153.208104)
			(xy 60.975116 -153.258537) (xy 60.919354 -153.303006) (xy 60.858963 -153.340952) (xy 60.794704 -153.371897)
			(xy 60.727384 -153.395454) (xy 60.657849 -153.411324) (xy 60.586975 -153.41931) (xy 60.515653 -153.41931)
			(xy 60.444779 -153.411324) (xy 60.375244 -153.395454) (xy 60.307924 -153.371897) (xy 60.243665 -153.340952)
			(xy 60.183274 -153.303006) (xy 60.127512 -153.258537) (xy 60.077079 -153.208104) (xy 60.03261 -153.152342)
			(xy 59.994664 -153.091951) (xy 59.963719 -153.027692) (xy 59.940162 -152.960372) (xy 59.924292 -152.890837)
			(xy 59.916306 -152.819963) (xy 59.29961 -152.819963) (xy 59.291624 -152.890837) (xy 59.275754 -152.960372)
			(xy 59.252197 -153.027692) (xy 59.221252 -153.091951) (xy 59.183306 -153.152342) (xy 59.138837 -153.208104)
			(xy 59.088404 -153.258537) (xy 59.032642 -153.303006) (xy 58.972251 -153.340952) (xy 58.907992 -153.371897)
			(xy 58.840672 -153.395454) (xy 58.771137 -153.411324) (xy 58.700263 -153.41931) (xy 58.628941 -153.41931)
			(xy 58.558067 -153.411324) (xy 58.488532 -153.395454) (xy 58.421212 -153.371897) (xy 58.356953 -153.340952)
			(xy 58.296562 -153.303006) (xy 58.2408 -153.258537) (xy 58.190367 -153.208104) (xy 58.145898 -153.152342)
			(xy 58.107952 -153.091951) (xy 58.077007 -153.027692) (xy 58.05345 -152.960372) (xy 58.03758 -152.890837)
			(xy 58.029594 -152.819963) (xy 27.89936 -152.819963) (xy 27.89936 -154.495093) (xy 58.029594 -154.495093)
			(xy 58.029594 -154.423771) (xy 58.03758 -154.352897) (xy 58.05345 -154.283362) (xy 58.077007 -154.216042)
			(xy 58.107952 -154.151783) (xy 58.145898 -154.091392) (xy 58.190367 -154.03563) (xy 58.2408 -153.985197)
			(xy 58.296562 -153.940728) (xy 58.356953 -153.902782) (xy 58.421212 -153.871837) (xy 58.488532 -153.84828)
			(xy 58.558067 -153.83241) (xy 58.628941 -153.824424) (xy 58.700263 -153.824424) (xy 58.771137 -153.83241)
			(xy 58.840672 -153.84828) (xy 58.907992 -153.871837) (xy 58.972251 -153.902782) (xy 59.032642 -153.940728)
			(xy 59.088404 -153.985197) (xy 59.138837 -154.03563) (xy 59.183306 -154.091392) (xy 59.221252 -154.151783)
			(xy 59.252197 -154.216042) (xy 59.275754 -154.283362) (xy 59.291624 -154.352897) (xy 59.29961 -154.423771)
			(xy 59.30011 -154.459432) (xy 59.29961 -154.495093) (xy 59.916306 -154.495093) (xy 59.916306 -154.423771)
			(xy 59.924292 -154.352897) (xy 59.940162 -154.283362) (xy 59.963719 -154.216042) (xy 59.994664 -154.151783)
			(xy 60.03261 -154.091392) (xy 60.077079 -154.03563) (xy 60.127512 -153.985197) (xy 60.183274 -153.940728)
			(xy 60.243665 -153.902782) (xy 60.307924 -153.871837) (xy 60.375244 -153.84828) (xy 60.444779 -153.83241)
			(xy 60.515653 -153.824424) (xy 60.586975 -153.824424) (xy 60.657849 -153.83241) (xy 60.727384 -153.84828)
			(xy 60.794704 -153.871837) (xy 60.858963 -153.902782) (xy 60.919354 -153.940728) (xy 60.975116 -153.985197)
			(xy 61.025549 -154.03563) (xy 61.070018 -154.091392) (xy 61.107964 -154.151783) (xy 61.138909 -154.216042)
			(xy 61.162466 -154.283362) (xy 61.178336 -154.352897) (xy 61.186322 -154.423771) (xy 61.186822 -154.459432)
			(xy 61.186322 -154.495093) (xy 62.157348 -154.495093) (xy 62.157348 -154.423771) (xy 62.165334 -154.352897)
			(xy 62.181204 -154.283362) (xy 62.204761 -154.216042) (xy 62.235706 -154.151783) (xy 62.273652 -154.091392)
			(xy 62.318121 -154.03563) (xy 62.368554 -153.985197) (xy 62.424316 -153.940728) (xy 62.484707 -153.902782)
			(xy 62.548966 -153.871837) (xy 62.616286 -153.84828) (xy 62.685821 -153.83241) (xy 62.756695 -153.824424)
			(xy 62.828017 -153.824424) (xy 62.898891 -153.83241) (xy 62.968426 -153.84828) (xy 63.035746 -153.871837)
			(xy 63.100005 -153.902782) (xy 63.160396 -153.940728) (xy 63.216158 -153.985197) (xy 63.266591 -154.03563)
			(xy 63.31106 -154.091392) (xy 63.349006 -154.151783) (xy 63.379951 -154.216042) (xy 63.403508 -154.283362)
			(xy 63.419378 -154.352897) (xy 63.427364 -154.423771) (xy 63.427864 -154.459432) (xy 63.427364 -154.495093)
			(xy 64.061332 -154.495093) (xy 64.061332 -154.423771) (xy 64.069318 -154.352897) (xy 64.085188 -154.283362)
			(xy 64.108745 -154.216042) (xy 64.13969 -154.151783) (xy 64.177636 -154.091392) (xy 64.222105 -154.03563)
			(xy 64.272538 -153.985197) (xy 64.3283 -153.940728) (xy 64.388691 -153.902782) (xy 64.45295 -153.871837)
			(xy 64.52027 -153.84828) (xy 64.589805 -153.83241) (xy 64.660679 -153.824424) (xy 64.732001 -153.824424)
			(xy 64.802875 -153.83241) (xy 64.87241 -153.84828) (xy 64.93973 -153.871837) (xy 65.003989 -153.902782)
			(xy 65.06438 -153.940728) (xy 65.120142 -153.985197) (xy 65.170575 -154.03563) (xy 65.215044 -154.091392)
			(xy 65.25299 -154.151783) (xy 65.283935 -154.216042) (xy 65.307492 -154.283362) (xy 65.323362 -154.352897)
			(xy 65.331348 -154.423771) (xy 65.331848 -154.459432) (xy 65.331348 -154.495093) (xy 65.323362 -154.565967)
			(xy 65.307492 -154.635502) (xy 65.283935 -154.702822) (xy 65.25299 -154.767081) (xy 65.215044 -154.827472)
			(xy 65.170575 -154.883234) (xy 65.120142 -154.933667) (xy 65.06438 -154.978136) (xy 65.003989 -155.016082)
			(xy 64.93973 -155.047027) (xy 64.87241 -155.070584) (xy 64.802875 -155.086454) (xy 64.732001 -155.09444)
			(xy 64.660679 -155.09444) (xy 64.589805 -155.086454) (xy 64.52027 -155.070584) (xy 64.45295 -155.047027)
			(xy 64.388691 -155.016082) (xy 64.3283 -154.978136) (xy 64.272538 -154.933667) (xy 64.222105 -154.883234)
			(xy 64.177636 -154.827472) (xy 64.13969 -154.767081) (xy 64.108745 -154.702822) (xy 64.085188 -154.635502)
			(xy 64.069318 -154.565967) (xy 64.061332 -154.495093) (xy 63.427364 -154.495093) (xy 63.419378 -154.565967)
			(xy 63.403508 -154.635502) (xy 63.379951 -154.702822) (xy 63.349006 -154.767081) (xy 63.31106 -154.827472)
			(xy 63.266591 -154.883234) (xy 63.216158 -154.933667) (xy 63.160396 -154.978136) (xy 63.100005 -155.016082)
			(xy 63.035746 -155.047027) (xy 62.968426 -155.070584) (xy 62.898891 -155.086454) (xy 62.828017 -155.09444)
			(xy 62.756695 -155.09444) (xy 62.685821 -155.086454) (xy 62.616286 -155.070584) (xy 62.548966 -155.047027)
			(xy 62.484707 -155.016082) (xy 62.424316 -154.978136) (xy 62.368554 -154.933667) (xy 62.318121 -154.883234)
			(xy 62.273652 -154.827472) (xy 62.235706 -154.767081) (xy 62.204761 -154.702822) (xy 62.181204 -154.635502)
			(xy 62.165334 -154.565967) (xy 62.157348 -154.495093) (xy 61.186322 -154.495093) (xy 61.178336 -154.565967)
			(xy 61.162466 -154.635502) (xy 61.138909 -154.702822) (xy 61.107964 -154.767081) (xy 61.070018 -154.827472)
			(xy 61.025549 -154.883234) (xy 60.975116 -154.933667) (xy 60.919354 -154.978136) (xy 60.858963 -155.016082)
			(xy 60.794704 -155.047027) (xy 60.727384 -155.070584) (xy 60.657849 -155.086454) (xy 60.586975 -155.09444)
			(xy 60.515653 -155.09444) (xy 60.444779 -155.086454) (xy 60.375244 -155.070584) (xy 60.307924 -155.047027)
			(xy 60.243665 -155.016082) (xy 60.183274 -154.978136) (xy 60.127512 -154.933667) (xy 60.077079 -154.883234)
			(xy 60.03261 -154.827472) (xy 59.994664 -154.767081) (xy 59.963719 -154.702822) (xy 59.940162 -154.635502)
			(xy 59.924292 -154.565967) (xy 59.916306 -154.495093) (xy 59.29961 -154.495093) (xy 59.291624 -154.565967)
			(xy 59.275754 -154.635502) (xy 59.252197 -154.702822) (xy 59.221252 -154.767081) (xy 59.183306 -154.827472)
			(xy 59.138837 -154.883234) (xy 59.088404 -154.933667) (xy 59.032642 -154.978136) (xy 58.972251 -155.016082)
			(xy 58.907992 -155.047027) (xy 58.840672 -155.070584) (xy 58.771137 -155.086454) (xy 58.700263 -155.09444)
			(xy 58.628941 -155.09444) (xy 58.558067 -155.086454) (xy 58.488532 -155.070584) (xy 58.421212 -155.047027)
			(xy 58.356953 -155.016082) (xy 58.296562 -154.978136) (xy 58.2408 -154.933667) (xy 58.190367 -154.883234)
			(xy 58.145898 -154.827472) (xy 58.107952 -154.767081) (xy 58.077007 -154.702822) (xy 58.05345 -154.635502)
			(xy 58.03758 -154.565967) (xy 58.029594 -154.495093) (xy 27.89936 -154.495093) (xy 27.89936 -156.506265)
			(xy 57.98616 -156.506265) (xy 57.98616 -156.434943) (xy 57.994146 -156.364069) (xy 58.010016 -156.294534)
			(xy 58.033573 -156.227214) (xy 58.064518 -156.162955) (xy 58.102464 -156.102564) (xy 58.146933 -156.046802)
			(xy 58.197366 -155.996369) (xy 58.253128 -155.9519) (xy 58.313519 -155.913954) (xy 58.377778 -155.883009)
			(xy 58.445098 -155.859452) (xy 58.514633 -155.843582) (xy 58.585507 -155.835596) (xy 58.656829 -155.835596)
			(xy 58.727703 -155.843582) (xy 58.797238 -155.859452) (xy 58.864558 -155.883009) (xy 58.928817 -155.913954)
			(xy 58.989208 -155.9519) (xy 59.04497 -155.996369) (xy 59.095403 -156.046802) (xy 59.139872 -156.102564)
			(xy 59.177818 -156.162955) (xy 59.208763 -156.227214) (xy 59.23232 -156.294534) (xy 59.24819 -156.364069)
			(xy 59.256176 -156.434943) (xy 59.256676 -156.470604) (xy 59.256176 -156.506265) (xy 59.872872 -156.506265)
			(xy 59.872872 -156.434943) (xy 59.880858 -156.364069) (xy 59.896728 -156.294534) (xy 59.920285 -156.227214)
			(xy 59.95123 -156.162955) (xy 59.989176 -156.102564) (xy 60.033645 -156.046802) (xy 60.084078 -155.996369)
			(xy 60.13984 -155.9519) (xy 60.200231 -155.913954) (xy 60.26449 -155.883009) (xy 60.33181 -155.859452)
			(xy 60.401345 -155.843582) (xy 60.472219 -155.835596) (xy 60.543541 -155.835596) (xy 60.614415 -155.843582)
			(xy 60.68395 -155.859452) (xy 60.75127 -155.883009) (xy 60.815529 -155.913954) (xy 60.87592 -155.9519)
			(xy 60.931682 -155.996369) (xy 60.982115 -156.046802) (xy 61.026584 -156.102564) (xy 61.06453 -156.162955)
			(xy 61.095475 -156.227214) (xy 61.119032 -156.294534) (xy 61.134902 -156.364069) (xy 61.142888 -156.434943)
			(xy 61.143388 -156.470604) (xy 61.142888 -156.506265) (xy 62.113914 -156.506265) (xy 62.113914 -156.434943)
			(xy 62.1219 -156.364069) (xy 62.13777 -156.294534) (xy 62.161327 -156.227214) (xy 62.192272 -156.162955)
			(xy 62.230218 -156.102564) (xy 62.274687 -156.046802) (xy 62.32512 -155.996369) (xy 62.380882 -155.9519)
			(xy 62.441273 -155.913954) (xy 62.505532 -155.883009) (xy 62.572852 -155.859452) (xy 62.642387 -155.843582)
			(xy 62.713261 -155.835596) (xy 62.784583 -155.835596) (xy 62.855457 -155.843582) (xy 62.924992 -155.859452)
			(xy 62.992312 -155.883009) (xy 63.056571 -155.913954) (xy 63.116962 -155.9519) (xy 63.172724 -155.996369)
			(xy 63.223157 -156.046802) (xy 63.267626 -156.102564) (xy 63.305572 -156.162955) (xy 63.336517 -156.227214)
			(xy 63.360074 -156.294534) (xy 63.375944 -156.364069) (xy 63.38393 -156.434943) (xy 63.38443 -156.470604)
			(xy 63.38393 -156.506265) (xy 64.017898 -156.506265) (xy 64.017898 -156.434943) (xy 64.025884 -156.364069)
			(xy 64.041754 -156.294534) (xy 64.065311 -156.227214) (xy 64.096256 -156.162955) (xy 64.134202 -156.102564)
			(xy 64.178671 -156.046802) (xy 64.229104 -155.996369) (xy 64.284866 -155.9519) (xy 64.345257 -155.913954)
			(xy 64.409516 -155.883009) (xy 64.476836 -155.859452) (xy 64.546371 -155.843582) (xy 64.617245 -155.835596)
			(xy 64.688567 -155.835596) (xy 64.759441 -155.843582) (xy 64.828976 -155.859452) (xy 64.896296 -155.883009)
			(xy 64.960555 -155.913954) (xy 65.020946 -155.9519) (xy 65.076708 -155.996369) (xy 65.127141 -156.046802)
			(xy 65.17161 -156.102564) (xy 65.209556 -156.162955) (xy 65.240501 -156.227214) (xy 65.264058 -156.294534)
			(xy 65.279928 -156.364069) (xy 65.287914 -156.434943) (xy 65.288414 -156.470604) (xy 65.287914 -156.506265)
			(xy 65.279928 -156.577139) (xy 65.264058 -156.646674) (xy 65.240501 -156.713994) (xy 65.209556 -156.778253)
			(xy 65.17161 -156.838644) (xy 65.127141 -156.894406) (xy 65.076708 -156.944839) (xy 65.020946 -156.989308)
			(xy 64.960555 -157.027254) (xy 64.896296 -157.058199) (xy 64.828976 -157.081756) (xy 64.759441 -157.097626)
			(xy 64.688567 -157.105612) (xy 64.617245 -157.105612) (xy 64.546371 -157.097626) (xy 64.476836 -157.081756)
			(xy 64.409516 -157.058199) (xy 64.345257 -157.027254) (xy 64.284866 -156.989308) (xy 64.229104 -156.944839)
			(xy 64.178671 -156.894406) (xy 64.134202 -156.838644) (xy 64.096256 -156.778253) (xy 64.065311 -156.713994)
			(xy 64.041754 -156.646674) (xy 64.025884 -156.577139) (xy 64.017898 -156.506265) (xy 63.38393 -156.506265)
			(xy 63.375944 -156.577139) (xy 63.360074 -156.646674) (xy 63.336517 -156.713994) (xy 63.305572 -156.778253)
			(xy 63.267626 -156.838644) (xy 63.223157 -156.894406) (xy 63.172724 -156.944839) (xy 63.116962 -156.989308)
			(xy 63.056571 -157.027254) (xy 62.992312 -157.058199) (xy 62.924992 -157.081756) (xy 62.855457 -157.097626)
			(xy 62.784583 -157.105612) (xy 62.713261 -157.105612) (xy 62.642387 -157.097626) (xy 62.572852 -157.081756)
			(xy 62.505532 -157.058199) (xy 62.441273 -157.027254) (xy 62.380882 -156.989308) (xy 62.32512 -156.944839)
			(xy 62.274687 -156.894406) (xy 62.230218 -156.838644) (xy 62.192272 -156.778253) (xy 62.161327 -156.713994)
			(xy 62.13777 -156.646674) (xy 62.1219 -156.577139) (xy 62.113914 -156.506265) (xy 61.142888 -156.506265)
			(xy 61.134902 -156.577139) (xy 61.119032 -156.646674) (xy 61.095475 -156.713994) (xy 61.06453 -156.778253)
			(xy 61.026584 -156.838644) (xy 60.982115 -156.894406) (xy 60.931682 -156.944839) (xy 60.87592 -156.989308)
			(xy 60.815529 -157.027254) (xy 60.75127 -157.058199) (xy 60.68395 -157.081756) (xy 60.614415 -157.097626)
			(xy 60.543541 -157.105612) (xy 60.472219 -157.105612) (xy 60.401345 -157.097626) (xy 60.33181 -157.081756)
			(xy 60.26449 -157.058199) (xy 60.200231 -157.027254) (xy 60.13984 -156.989308) (xy 60.084078 -156.944839)
			(xy 60.033645 -156.894406) (xy 59.989176 -156.838644) (xy 59.95123 -156.778253) (xy 59.920285 -156.713994)
			(xy 59.896728 -156.646674) (xy 59.880858 -156.577139) (xy 59.872872 -156.506265) (xy 59.256176 -156.506265)
			(xy 59.24819 -156.577139) (xy 59.23232 -156.646674) (xy 59.208763 -156.713994) (xy 59.177818 -156.778253)
			(xy 59.139872 -156.838644) (xy 59.095403 -156.894406) (xy 59.04497 -156.944839) (xy 58.989208 -156.989308)
			(xy 58.928817 -157.027254) (xy 58.864558 -157.058199) (xy 58.797238 -157.081756) (xy 58.727703 -157.097626)
			(xy 58.656829 -157.105612) (xy 58.585507 -157.105612) (xy 58.514633 -157.097626) (xy 58.445098 -157.081756)
			(xy 58.377778 -157.058199) (xy 58.313519 -157.027254) (xy 58.253128 -156.989308) (xy 58.197366 -156.944839)
			(xy 58.146933 -156.894406) (xy 58.102464 -156.838644) (xy 58.064518 -156.778253) (xy 58.033573 -156.713994)
			(xy 58.010016 -156.646674) (xy 57.994146 -156.577139) (xy 57.98616 -156.506265) (xy 27.89936 -156.506265)
			(xy 27.89936 -158.396787) (xy 57.98616 -158.396787) (xy 57.98616 -158.325465) (xy 57.994146 -158.254591)
			(xy 58.010016 -158.185056) (xy 58.033573 -158.117736) (xy 58.064518 -158.053477) (xy 58.102464 -157.993086)
			(xy 58.146933 -157.937324) (xy 58.197366 -157.886891) (xy 58.253128 -157.842422) (xy 58.313519 -157.804476)
			(xy 58.377778 -157.773531) (xy 58.445098 -157.749974) (xy 58.514633 -157.734104) (xy 58.585507 -157.726118)
			(xy 58.656829 -157.726118) (xy 58.727703 -157.734104) (xy 58.797238 -157.749974) (xy 58.864558 -157.773531)
			(xy 58.928817 -157.804476) (xy 58.989208 -157.842422) (xy 59.04497 -157.886891) (xy 59.095403 -157.937324)
			(xy 59.139872 -157.993086) (xy 59.177818 -158.053477) (xy 59.208763 -158.117736) (xy 59.23232 -158.185056)
			(xy 59.24819 -158.254591) (xy 59.256176 -158.325465) (xy 59.256676 -158.361126) (xy 59.256176 -158.396787)
			(xy 59.872872 -158.396787) (xy 59.872872 -158.325465) (xy 59.880858 -158.254591) (xy 59.896728 -158.185056)
			(xy 59.920285 -158.117736) (xy 59.95123 -158.053477) (xy 59.989176 -157.993086) (xy 60.033645 -157.937324)
			(xy 60.084078 -157.886891) (xy 60.13984 -157.842422) (xy 60.200231 -157.804476) (xy 60.26449 -157.773531)
			(xy 60.33181 -157.749974) (xy 60.401345 -157.734104) (xy 60.472219 -157.726118) (xy 60.543541 -157.726118)
			(xy 60.614415 -157.734104) (xy 60.68395 -157.749974) (xy 60.75127 -157.773531) (xy 60.815529 -157.804476)
			(xy 60.87592 -157.842422) (xy 60.931682 -157.886891) (xy 60.982115 -157.937324) (xy 61.026584 -157.993086)
			(xy 61.06453 -158.053477) (xy 61.095475 -158.117736) (xy 61.119032 -158.185056) (xy 61.134902 -158.254591)
			(xy 61.142888 -158.325465) (xy 61.143388 -158.361126) (xy 61.142888 -158.396787) (xy 62.113914 -158.396787)
			(xy 62.113914 -158.325465) (xy 62.1219 -158.254591) (xy 62.13777 -158.185056) (xy 62.161327 -158.117736)
			(xy 62.192272 -158.053477) (xy 62.230218 -157.993086) (xy 62.274687 -157.937324) (xy 62.32512 -157.886891)
			(xy 62.380882 -157.842422) (xy 62.441273 -157.804476) (xy 62.505532 -157.773531) (xy 62.572852 -157.749974)
			(xy 62.642387 -157.734104) (xy 62.713261 -157.726118) (xy 62.784583 -157.726118) (xy 62.855457 -157.734104)
			(xy 62.924992 -157.749974) (xy 62.992312 -157.773531) (xy 63.056571 -157.804476) (xy 63.116962 -157.842422)
			(xy 63.172724 -157.886891) (xy 63.223157 -157.937324) (xy 63.267626 -157.993086) (xy 63.305572 -158.053477)
			(xy 63.336517 -158.117736) (xy 63.360074 -158.185056) (xy 63.375944 -158.254591) (xy 63.38393 -158.325465)
			(xy 63.38443 -158.361126) (xy 63.38393 -158.396787) (xy 64.017898 -158.396787) (xy 64.017898 -158.325465)
			(xy 64.025884 -158.254591) (xy 64.041754 -158.185056) (xy 64.065311 -158.117736) (xy 64.096256 -158.053477)
			(xy 64.134202 -157.993086) (xy 64.178671 -157.937324) (xy 64.229104 -157.886891) (xy 64.284866 -157.842422)
			(xy 64.345257 -157.804476) (xy 64.409516 -157.773531) (xy 64.476836 -157.749974) (xy 64.546371 -157.734104)
			(xy 64.617245 -157.726118) (xy 64.688567 -157.726118) (xy 64.759441 -157.734104) (xy 64.828976 -157.749974)
			(xy 64.896296 -157.773531) (xy 64.960555 -157.804476) (xy 65.020946 -157.842422) (xy 65.076708 -157.886891)
			(xy 65.127141 -157.937324) (xy 65.17161 -157.993086) (xy 65.209556 -158.053477) (xy 65.240501 -158.117736)
			(xy 65.264058 -158.185056) (xy 65.279928 -158.254591) (xy 65.287914 -158.325465) (xy 65.288414 -158.361126)
			(xy 65.287914 -158.396787) (xy 65.279928 -158.467661) (xy 65.264058 -158.537196) (xy 65.240501 -158.604516)
			(xy 65.236321 -158.613195) (xy 67.292974 -158.613195) (xy 67.292974 -158.541873) (xy 67.30096 -158.470999)
			(xy 67.31683 -158.401464) (xy 67.340387 -158.334144) (xy 67.371332 -158.269885) (xy 67.409278 -158.209494)
			(xy 67.453747 -158.153732) (xy 67.50418 -158.103299) (xy 67.559942 -158.05883) (xy 67.620333 -158.020884)
			(xy 67.684592 -157.989939) (xy 67.751912 -157.966382) (xy 67.821447 -157.950512) (xy 67.892321 -157.942526)
			(xy 67.963643 -157.942526) (xy 68.034517 -157.950512) (xy 68.104052 -157.966382) (xy 68.171372 -157.989939)
			(xy 68.235631 -158.020884) (xy 68.296022 -158.05883) (xy 68.351784 -158.103299) (xy 68.402217 -158.153732)
			(xy 68.446686 -158.209494) (xy 68.484632 -158.269885) (xy 68.515577 -158.334144) (xy 68.539134 -158.401464)
			(xy 68.555004 -158.470999) (xy 68.56299 -158.541873) (xy 68.56349 -158.577534) (xy 68.56299 -158.613195)
			(xy 68.555004 -158.684069) (xy 68.553441 -158.690919) (xy 70.242168 -158.690919) (xy 70.242168 -158.619597)
			(xy 70.250154 -158.548723) (xy 70.266024 -158.479188) (xy 70.289581 -158.411868) (xy 70.320526 -158.347609)
			(xy 70.358472 -158.287218) (xy 70.402941 -158.231456) (xy 70.453374 -158.181023) (xy 70.509136 -158.136554)
			(xy 70.569527 -158.098608) (xy 70.633786 -158.067663) (xy 70.701106 -158.044106) (xy 70.770641 -158.028236)
			(xy 70.841515 -158.02025) (xy 70.912837 -158.02025) (xy 70.983711 -158.028236) (xy 71.053246 -158.044106)
			(xy 71.120566 -158.067663) (xy 71.184825 -158.098608) (xy 71.245216 -158.136554) (xy 71.300978 -158.181023)
			(xy 71.351411 -158.231456) (xy 71.39588 -158.287218) (xy 71.433826 -158.347609) (xy 71.464771 -158.411868)
			(xy 71.488328 -158.479188) (xy 71.504198 -158.548723) (xy 71.512184 -158.619597) (xy 71.512684 -158.655258)
			(xy 71.512184 -158.690919) (xy 71.504198 -158.761793) (xy 71.488328 -158.831328) (xy 71.464771 -158.898648)
			(xy 71.433826 -158.962907) (xy 71.39588 -159.023298) (xy 71.351411 -159.07906) (xy 71.300978 -159.129493)
			(xy 71.245216 -159.173962) (xy 71.184825 -159.211908) (xy 71.120566 -159.242853) (xy 71.053246 -159.26641)
			(xy 70.983711 -159.28228) (xy 70.912837 -159.290266) (xy 70.841515 -159.290266) (xy 70.770641 -159.28228)
			(xy 70.701106 -159.26641) (xy 70.633786 -159.242853) (xy 70.569527 -159.211908) (xy 70.509136 -159.173962)
			(xy 70.453374 -159.129493) (xy 70.402941 -159.07906) (xy 70.358472 -159.023298) (xy 70.320526 -158.962907)
			(xy 70.289581 -158.898648) (xy 70.266024 -158.831328) (xy 70.250154 -158.761793) (xy 70.242168 -158.690919)
			(xy 68.553441 -158.690919) (xy 68.539134 -158.753604) (xy 68.515577 -158.820924) (xy 68.484632 -158.885183)
			(xy 68.446686 -158.945574) (xy 68.402217 -159.001336) (xy 68.351784 -159.051769) (xy 68.296022 -159.096238)
			(xy 68.235631 -159.134184) (xy 68.171372 -159.165129) (xy 68.104052 -159.188686) (xy 68.034517 -159.204556)
			(xy 67.963643 -159.212542) (xy 67.892321 -159.212542) (xy 67.821447 -159.204556) (xy 67.751912 -159.188686)
			(xy 67.684592 -159.165129) (xy 67.620333 -159.134184) (xy 67.559942 -159.096238) (xy 67.50418 -159.051769)
			(xy 67.453747 -159.001336) (xy 67.409278 -158.945574) (xy 67.371332 -158.885183) (xy 67.340387 -158.820924)
			(xy 67.31683 -158.753604) (xy 67.30096 -158.684069) (xy 67.292974 -158.613195) (xy 65.236321 -158.613195)
			(xy 65.209556 -158.668775) (xy 65.17161 -158.729166) (xy 65.127141 -158.784928) (xy 65.076708 -158.835361)
			(xy 65.020946 -158.87983) (xy 64.960555 -158.917776) (xy 64.896296 -158.948721) (xy 64.828976 -158.972278)
			(xy 64.759441 -158.988148) (xy 64.688567 -158.996134) (xy 64.617245 -158.996134) (xy 64.546371 -158.988148)
			(xy 64.476836 -158.972278) (xy 64.409516 -158.948721) (xy 64.345257 -158.917776) (xy 64.284866 -158.87983)
			(xy 64.229104 -158.835361) (xy 64.178671 -158.784928) (xy 64.134202 -158.729166) (xy 64.096256 -158.668775)
			(xy 64.065311 -158.604516) (xy 64.041754 -158.537196) (xy 64.025884 -158.467661) (xy 64.017898 -158.396787)
			(xy 63.38393 -158.396787) (xy 63.375944 -158.467661) (xy 63.360074 -158.537196) (xy 63.336517 -158.604516)
			(xy 63.305572 -158.668775) (xy 63.267626 -158.729166) (xy 63.223157 -158.784928) (xy 63.172724 -158.835361)
			(xy 63.116962 -158.87983) (xy 63.056571 -158.917776) (xy 62.992312 -158.948721) (xy 62.924992 -158.972278)
			(xy 62.855457 -158.988148) (xy 62.784583 -158.996134) (xy 62.713261 -158.996134) (xy 62.642387 -158.988148)
			(xy 62.572852 -158.972278) (xy 62.505532 -158.948721) (xy 62.441273 -158.917776) (xy 62.380882 -158.87983)
			(xy 62.32512 -158.835361) (xy 62.274687 -158.784928) (xy 62.230218 -158.729166) (xy 62.192272 -158.668775)
			(xy 62.161327 -158.604516) (xy 62.13777 -158.537196) (xy 62.1219 -158.467661) (xy 62.113914 -158.396787)
			(xy 61.142888 -158.396787) (xy 61.134902 -158.467661) (xy 61.119032 -158.537196) (xy 61.095475 -158.604516)
			(xy 61.06453 -158.668775) (xy 61.026584 -158.729166) (xy 60.982115 -158.784928) (xy 60.931682 -158.835361)
			(xy 60.87592 -158.87983) (xy 60.815529 -158.917776) (xy 60.75127 -158.948721) (xy 60.68395 -158.972278)
			(xy 60.614415 -158.988148) (xy 60.543541 -158.996134) (xy 60.472219 -158.996134) (xy 60.401345 -158.988148)
			(xy 60.33181 -158.972278) (xy 60.26449 -158.948721) (xy 60.200231 -158.917776) (xy 60.13984 -158.87983)
			(xy 60.084078 -158.835361) (xy 60.033645 -158.784928) (xy 59.989176 -158.729166) (xy 59.95123 -158.668775)
			(xy 59.920285 -158.604516) (xy 59.896728 -158.537196) (xy 59.880858 -158.467661) (xy 59.872872 -158.396787)
			(xy 59.256176 -158.396787) (xy 59.24819 -158.467661) (xy 59.23232 -158.537196) (xy 59.208763 -158.604516)
			(xy 59.177818 -158.668775) (xy 59.139872 -158.729166) (xy 59.095403 -158.784928) (xy 59.04497 -158.835361)
			(xy 58.989208 -158.87983) (xy 58.928817 -158.917776) (xy 58.864558 -158.948721) (xy 58.797238 -158.972278)
			(xy 58.727703 -158.988148) (xy 58.656829 -158.996134) (xy 58.585507 -158.996134) (xy 58.514633 -158.988148)
			(xy 58.445098 -158.972278) (xy 58.377778 -158.948721) (xy 58.313519 -158.917776) (xy 58.253128 -158.87983)
			(xy 58.197366 -158.835361) (xy 58.146933 -158.784928) (xy 58.102464 -158.729166) (xy 58.064518 -158.668775)
			(xy 58.033573 -158.604516) (xy 58.010016 -158.537196) (xy 57.994146 -158.467661) (xy 57.98616 -158.396787)
			(xy 27.89936 -158.396787) (xy 27.89936 -160.437931) (xy 57.98616 -160.437931) (xy 57.98616 -160.366609)
			(xy 57.994146 -160.295735) (xy 58.010016 -160.2262) (xy 58.033573 -160.15888) (xy 58.064518 -160.094621)
			(xy 58.102464 -160.03423) (xy 58.146933 -159.978468) (xy 58.197366 -159.928035) (xy 58.253128 -159.883566)
			(xy 58.313519 -159.84562) (xy 58.377778 -159.814675) (xy 58.445098 -159.791118) (xy 58.514633 -159.775248)
			(xy 58.585507 -159.767262) (xy 58.656829 -159.767262) (xy 58.727703 -159.775248) (xy 58.797238 -159.791118)
			(xy 58.864558 -159.814675) (xy 58.928817 -159.84562) (xy 58.989208 -159.883566) (xy 59.04497 -159.928035)
			(xy 59.095403 -159.978468) (xy 59.139872 -160.03423) (xy 59.177818 -160.094621) (xy 59.208763 -160.15888)
			(xy 59.23232 -160.2262) (xy 59.24819 -160.295735) (xy 59.256176 -160.366609) (xy 59.256676 -160.40227)
			(xy 59.256176 -160.437931) (xy 59.872872 -160.437931) (xy 59.872872 -160.366609) (xy 59.880858 -160.295735)
			(xy 59.896728 -160.2262) (xy 59.920285 -160.15888) (xy 59.95123 -160.094621) (xy 59.989176 -160.03423)
			(xy 60.033645 -159.978468) (xy 60.084078 -159.928035) (xy 60.13984 -159.883566) (xy 60.200231 -159.84562)
			(xy 60.26449 -159.814675) (xy 60.33181 -159.791118) (xy 60.401345 -159.775248) (xy 60.472219 -159.767262)
			(xy 60.543541 -159.767262) (xy 60.614415 -159.775248) (xy 60.68395 -159.791118) (xy 60.75127 -159.814675)
			(xy 60.815529 -159.84562) (xy 60.87592 -159.883566) (xy 60.931682 -159.928035) (xy 60.982115 -159.978468)
			(xy 61.026584 -160.03423) (xy 61.06453 -160.094621) (xy 61.095475 -160.15888) (xy 61.119032 -160.2262)
			(xy 61.134902 -160.295735) (xy 61.142888 -160.366609) (xy 61.143388 -160.40227) (xy 61.142888 -160.437931)
			(xy 62.113914 -160.437931) (xy 62.113914 -160.366609) (xy 62.1219 -160.295735) (xy 62.13777 -160.2262)
			(xy 62.161327 -160.15888) (xy 62.192272 -160.094621) (xy 62.230218 -160.03423) (xy 62.274687 -159.978468)
			(xy 62.32512 -159.928035) (xy 62.380882 -159.883566) (xy 62.441273 -159.84562) (xy 62.505532 -159.814675)
			(xy 62.572852 -159.791118) (xy 62.642387 -159.775248) (xy 62.713261 -159.767262) (xy 62.784583 -159.767262)
			(xy 62.855457 -159.775248) (xy 62.924992 -159.791118) (xy 62.992312 -159.814675) (xy 63.056571 -159.84562)
			(xy 63.116962 -159.883566) (xy 63.172724 -159.928035) (xy 63.223157 -159.978468) (xy 63.267626 -160.03423)
			(xy 63.305572 -160.094621) (xy 63.336517 -160.15888) (xy 63.360074 -160.2262) (xy 63.375944 -160.295735)
			(xy 63.38393 -160.366609) (xy 63.38443 -160.40227) (xy 63.38393 -160.437931) (xy 64.017898 -160.437931)
			(xy 64.017898 -160.366609) (xy 64.025884 -160.295735) (xy 64.041754 -160.2262) (xy 64.065311 -160.15888)
			(xy 64.096256 -160.094621) (xy 64.134202 -160.03423) (xy 64.178671 -159.978468) (xy 64.229104 -159.928035)
			(xy 64.284866 -159.883566) (xy 64.345257 -159.84562) (xy 64.409516 -159.814675) (xy 64.476836 -159.791118)
			(xy 64.546371 -159.775248) (xy 64.617245 -159.767262) (xy 64.688567 -159.767262) (xy 64.759441 -159.775248)
			(xy 64.828976 -159.791118) (xy 64.896296 -159.814675) (xy 64.960555 -159.84562) (xy 65.020946 -159.883566)
			(xy 65.076708 -159.928035) (xy 65.127141 -159.978468) (xy 65.17161 -160.03423) (xy 65.209556 -160.094621)
			(xy 65.240501 -160.15888) (xy 65.264058 -160.2262) (xy 65.279928 -160.295735) (xy 65.287914 -160.366609)
			(xy 65.288414 -160.40227) (xy 65.287914 -160.437931) (xy 65.279928 -160.508805) (xy 65.264058 -160.57834)
			(xy 65.240501 -160.64566) (xy 65.209556 -160.709919) (xy 65.17161 -160.77031) (xy 65.127141 -160.826072)
			(xy 65.076708 -160.876505) (xy 65.020946 -160.920974) (xy 64.960555 -160.95892) (xy 64.896296 -160.989865)
			(xy 64.828976 -161.013422) (xy 64.759441 -161.029292) (xy 64.688567 -161.037278) (xy 64.617245 -161.037278)
			(xy 64.546371 -161.029292) (xy 64.476836 -161.013422) (xy 64.409516 -160.989865) (xy 64.345257 -160.95892)
			(xy 64.284866 -160.920974) (xy 64.229104 -160.876505) (xy 64.178671 -160.826072) (xy 64.134202 -160.77031)
			(xy 64.096256 -160.709919) (xy 64.065311 -160.64566) (xy 64.041754 -160.57834) (xy 64.025884 -160.508805)
			(xy 64.017898 -160.437931) (xy 63.38393 -160.437931) (xy 63.375944 -160.508805) (xy 63.360074 -160.57834)
			(xy 63.336517 -160.64566) (xy 63.305572 -160.709919) (xy 63.267626 -160.77031) (xy 63.223157 -160.826072)
			(xy 63.172724 -160.876505) (xy 63.116962 -160.920974) (xy 63.056571 -160.95892) (xy 62.992312 -160.989865)
			(xy 62.924992 -161.013422) (xy 62.855457 -161.029292) (xy 62.784583 -161.037278) (xy 62.713261 -161.037278)
			(xy 62.642387 -161.029292) (xy 62.572852 -161.013422) (xy 62.505532 -160.989865) (xy 62.441273 -160.95892)
			(xy 62.380882 -160.920974) (xy 62.32512 -160.876505) (xy 62.274687 -160.826072) (xy 62.230218 -160.77031)
			(xy 62.192272 -160.709919) (xy 62.161327 -160.64566) (xy 62.13777 -160.57834) (xy 62.1219 -160.508805)
			(xy 62.113914 -160.437931) (xy 61.142888 -160.437931) (xy 61.134902 -160.508805) (xy 61.119032 -160.57834)
			(xy 61.095475 -160.64566) (xy 61.06453 -160.709919) (xy 61.026584 -160.77031) (xy 60.982115 -160.826072)
			(xy 60.931682 -160.876505) (xy 60.87592 -160.920974) (xy 60.815529 -160.95892) (xy 60.75127 -160.989865)
			(xy 60.68395 -161.013422) (xy 60.614415 -161.029292) (xy 60.543541 -161.037278) (xy 60.472219 -161.037278)
			(xy 60.401345 -161.029292) (xy 60.33181 -161.013422) (xy 60.26449 -160.989865) (xy 60.200231 -160.95892)
			(xy 60.13984 -160.920974) (xy 60.084078 -160.876505) (xy 60.033645 -160.826072) (xy 59.989176 -160.77031)
			(xy 59.95123 -160.709919) (xy 59.920285 -160.64566) (xy 59.896728 -160.57834) (xy 59.880858 -160.508805)
			(xy 59.872872 -160.437931) (xy 59.256176 -160.437931) (xy 59.24819 -160.508805) (xy 59.23232 -160.57834)
			(xy 59.208763 -160.64566) (xy 59.177818 -160.709919) (xy 59.139872 -160.77031) (xy 59.095403 -160.826072)
			(xy 59.04497 -160.876505) (xy 58.989208 -160.920974) (xy 58.928817 -160.95892) (xy 58.864558 -160.989865)
			(xy 58.797238 -161.013422) (xy 58.727703 -161.029292) (xy 58.656829 -161.037278) (xy 58.585507 -161.037278)
			(xy 58.514633 -161.029292) (xy 58.445098 -161.013422) (xy 58.377778 -160.989865) (xy 58.313519 -160.95892)
			(xy 58.253128 -160.920974) (xy 58.197366 -160.876505) (xy 58.146933 -160.826072) (xy 58.102464 -160.77031)
			(xy 58.064518 -160.709919) (xy 58.033573 -160.64566) (xy 58.010016 -160.57834) (xy 57.994146 -160.508805)
			(xy 57.98616 -160.437931) (xy 27.89936 -160.437931) (xy 27.89936 -162.347757) (xy 57.98616 -162.347757)
			(xy 57.98616 -162.276435) (xy 57.994146 -162.205561) (xy 58.010016 -162.136026) (xy 58.033573 -162.068706)
			(xy 58.064518 -162.004447) (xy 58.102464 -161.944056) (xy 58.146933 -161.888294) (xy 58.197366 -161.837861)
			(xy 58.253128 -161.793392) (xy 58.313519 -161.755446) (xy 58.377778 -161.724501) (xy 58.445098 -161.700944)
			(xy 58.514633 -161.685074) (xy 58.585507 -161.677088) (xy 58.656829 -161.677088) (xy 58.727703 -161.685074)
			(xy 58.797238 -161.700944) (xy 58.864558 -161.724501) (xy 58.928817 -161.755446) (xy 58.989208 -161.793392)
			(xy 59.04497 -161.837861) (xy 59.095403 -161.888294) (xy 59.139872 -161.944056) (xy 59.177818 -162.004447)
			(xy 59.208763 -162.068706) (xy 59.23232 -162.136026) (xy 59.24819 -162.205561) (xy 59.256176 -162.276435)
			(xy 59.256676 -162.312096) (xy 59.256176 -162.347757) (xy 59.872872 -162.347757) (xy 59.872872 -162.276435)
			(xy 59.880858 -162.205561) (xy 59.896728 -162.136026) (xy 59.920285 -162.068706) (xy 59.95123 -162.004447)
			(xy 59.989176 -161.944056) (xy 60.033645 -161.888294) (xy 60.084078 -161.837861) (xy 60.13984 -161.793392)
			(xy 60.200231 -161.755446) (xy 60.26449 -161.724501) (xy 60.33181 -161.700944) (xy 60.401345 -161.685074)
			(xy 60.472219 -161.677088) (xy 60.543541 -161.677088) (xy 60.614415 -161.685074) (xy 60.68395 -161.700944)
			(xy 60.75127 -161.724501) (xy 60.815529 -161.755446) (xy 60.87592 -161.793392) (xy 60.931682 -161.837861)
			(xy 60.982115 -161.888294) (xy 61.026584 -161.944056) (xy 61.06453 -162.004447) (xy 61.095475 -162.068706)
			(xy 61.119032 -162.136026) (xy 61.134902 -162.205561) (xy 61.142888 -162.276435) (xy 61.143388 -162.312096)
			(xy 61.142888 -162.347757) (xy 62.113914 -162.347757) (xy 62.113914 -162.276435) (xy 62.1219 -162.205561)
			(xy 62.13777 -162.136026) (xy 62.161327 -162.068706) (xy 62.192272 -162.004447) (xy 62.230218 -161.944056)
			(xy 62.274687 -161.888294) (xy 62.32512 -161.837861) (xy 62.380882 -161.793392) (xy 62.441273 -161.755446)
			(xy 62.505532 -161.724501) (xy 62.572852 -161.700944) (xy 62.642387 -161.685074) (xy 62.713261 -161.677088)
			(xy 62.784583 -161.677088) (xy 62.855457 -161.685074) (xy 62.924992 -161.700944) (xy 62.992312 -161.724501)
			(xy 63.056571 -161.755446) (xy 63.116962 -161.793392) (xy 63.172724 -161.837861) (xy 63.223157 -161.888294)
			(xy 63.267626 -161.944056) (xy 63.305572 -162.004447) (xy 63.336517 -162.068706) (xy 63.360074 -162.136026)
			(xy 63.375944 -162.205561) (xy 63.38393 -162.276435) (xy 63.38443 -162.312096) (xy 63.38393 -162.347757)
			(xy 64.017898 -162.347757) (xy 64.017898 -162.276435) (xy 64.025884 -162.205561) (xy 64.041754 -162.136026)
			(xy 64.065311 -162.068706) (xy 64.096256 -162.004447) (xy 64.134202 -161.944056) (xy 64.178671 -161.888294)
			(xy 64.229104 -161.837861) (xy 64.284866 -161.793392) (xy 64.345257 -161.755446) (xy 64.409516 -161.724501)
			(xy 64.476836 -161.700944) (xy 64.546371 -161.685074) (xy 64.617245 -161.677088) (xy 64.688567 -161.677088)
			(xy 64.759441 -161.685074) (xy 64.828976 -161.700944) (xy 64.896296 -161.724501) (xy 64.960555 -161.755446)
			(xy 65.020946 -161.793392) (xy 65.076708 -161.837861) (xy 65.127141 -161.888294) (xy 65.17161 -161.944056)
			(xy 65.209556 -162.004447) (xy 65.240501 -162.068706) (xy 65.264058 -162.136026) (xy 65.279928 -162.205561)
			(xy 65.287914 -162.276435) (xy 65.288414 -162.312096) (xy 65.287914 -162.347757) (xy 65.279928 -162.418631)
			(xy 65.264058 -162.488166) (xy 65.240501 -162.555486) (xy 65.209556 -162.619745) (xy 65.17161 -162.680136)
			(xy 65.127141 -162.735898) (xy 65.076708 -162.786331) (xy 65.020946 -162.8308) (xy 64.960555 -162.868746)
			(xy 64.896296 -162.899691) (xy 64.828976 -162.923248) (xy 64.759441 -162.939118) (xy 64.688567 -162.947104)
			(xy 64.617245 -162.947104) (xy 64.546371 -162.939118) (xy 64.476836 -162.923248) (xy 64.409516 -162.899691)
			(xy 64.345257 -162.868746) (xy 64.284866 -162.8308) (xy 64.229104 -162.786331) (xy 64.178671 -162.735898)
			(xy 64.134202 -162.680136) (xy 64.096256 -162.619745) (xy 64.065311 -162.555486) (xy 64.041754 -162.488166)
			(xy 64.025884 -162.418631) (xy 64.017898 -162.347757) (xy 63.38393 -162.347757) (xy 63.375944 -162.418631)
			(xy 63.360074 -162.488166) (xy 63.336517 -162.555486) (xy 63.305572 -162.619745) (xy 63.267626 -162.680136)
			(xy 63.223157 -162.735898) (xy 63.172724 -162.786331) (xy 63.116962 -162.8308) (xy 63.056571 -162.868746)
			(xy 62.992312 -162.899691) (xy 62.924992 -162.923248) (xy 62.855457 -162.939118) (xy 62.784583 -162.947104)
			(xy 62.713261 -162.947104) (xy 62.642387 -162.939118) (xy 62.572852 -162.923248) (xy 62.505532 -162.899691)
			(xy 62.441273 -162.868746) (xy 62.380882 -162.8308) (xy 62.32512 -162.786331) (xy 62.274687 -162.735898)
			(xy 62.230218 -162.680136) (xy 62.192272 -162.619745) (xy 62.161327 -162.555486) (xy 62.13777 -162.488166)
			(xy 62.1219 -162.418631) (xy 62.113914 -162.347757) (xy 61.142888 -162.347757) (xy 61.134902 -162.418631)
			(xy 61.119032 -162.488166) (xy 61.095475 -162.555486) (xy 61.06453 -162.619745) (xy 61.026584 -162.680136)
			(xy 60.982115 -162.735898) (xy 60.931682 -162.786331) (xy 60.87592 -162.8308) (xy 60.815529 -162.868746)
			(xy 60.75127 -162.899691) (xy 60.68395 -162.923248) (xy 60.614415 -162.939118) (xy 60.543541 -162.947104)
			(xy 60.472219 -162.947104) (xy 60.401345 -162.939118) (xy 60.33181 -162.923248) (xy 60.26449 -162.899691)
			(xy 60.200231 -162.868746) (xy 60.13984 -162.8308) (xy 60.084078 -162.786331) (xy 60.033645 -162.735898)
			(xy 59.989176 -162.680136) (xy 59.95123 -162.619745) (xy 59.920285 -162.555486) (xy 59.896728 -162.488166)
			(xy 59.880858 -162.418631) (xy 59.872872 -162.347757) (xy 59.256176 -162.347757) (xy 59.24819 -162.418631)
			(xy 59.23232 -162.488166) (xy 59.208763 -162.555486) (xy 59.177818 -162.619745) (xy 59.139872 -162.680136)
			(xy 59.095403 -162.735898) (xy 59.04497 -162.786331) (xy 58.989208 -162.8308) (xy 58.928817 -162.868746)
			(xy 58.864558 -162.899691) (xy 58.797238 -162.923248) (xy 58.727703 -162.939118) (xy 58.656829 -162.947104)
			(xy 58.585507 -162.947104) (xy 58.514633 -162.939118) (xy 58.445098 -162.923248) (xy 58.377778 -162.899691)
			(xy 58.313519 -162.868746) (xy 58.253128 -162.8308) (xy 58.197366 -162.786331) (xy 58.146933 -162.735898)
			(xy 58.102464 -162.680136) (xy 58.064518 -162.619745) (xy 58.033573 -162.555486) (xy 58.010016 -162.488166)
			(xy 57.994146 -162.418631) (xy 57.98616 -162.347757) (xy 27.89936 -162.347757) (xy 27.89936 -173.178385)
			(xy 47.641754 -173.178385) (xy 47.641754 -173.097275) (xy 47.649704 -173.016556) (xy 47.665527 -172.937005)
			(xy 47.689072 -172.859389) (xy 47.720111 -172.784453) (xy 47.758346 -172.712921) (xy 47.803408 -172.645481)
			(xy 47.854863 -172.582782) (xy 47.912216 -172.525429) (xy 47.974915 -172.473974) (xy 48.042355 -172.428912)
			(xy 48.113887 -172.390677) (xy 48.188823 -172.359638) (xy 48.266439 -172.336093) (xy 48.34599 -172.32027)
			(xy 48.426709 -172.31232) (xy 48.507819 -172.31232) (xy 48.588538 -172.32027) (xy 48.668089 -172.336093)
			(xy 48.745705 -172.359638) (xy 48.820641 -172.390677) (xy 48.892173 -172.428912) (xy 48.959613 -172.473974)
			(xy 49.022312 -172.525429) (xy 49.079665 -172.582782) (xy 49.13112 -172.645481) (xy 49.176182 -172.712921)
			(xy 49.214417 -172.784453) (xy 49.245456 -172.859389) (xy 49.269001 -172.937005) (xy 49.284824 -173.016556)
			(xy 49.292774 -173.097275) (xy 49.293272 -173.13783) (xy 49.292774 -173.178385) (xy 49.284824 -173.259104)
			(xy 49.269001 -173.338655) (xy 49.245456 -173.416271) (xy 49.214417 -173.491207) (xy 49.176182 -173.562739)
			(xy 49.13112 -173.630179) (xy 49.079665 -173.692878) (xy 49.022312 -173.750231) (xy 48.959613 -173.801686)
			(xy 48.892173 -173.846748) (xy 48.820641 -173.884983) (xy 48.745705 -173.916022) (xy 48.668089 -173.939567)
			(xy 48.588538 -173.95539) (xy 48.507819 -173.96334) (xy 48.426709 -173.96334) (xy 48.34599 -173.95539)
			(xy 48.266439 -173.939567) (xy 48.188823 -173.916022) (xy 48.113887 -173.884983) (xy 48.042355 -173.846748)
			(xy 47.974915 -173.801686) (xy 47.912216 -173.750231) (xy 47.854863 -173.692878) (xy 47.803408 -173.630179)
			(xy 47.758346 -173.562739) (xy 47.720111 -173.491207) (xy 47.689072 -173.416271) (xy 47.665527 -173.338655)
			(xy 47.649704 -173.259104) (xy 47.641754 -173.178385) (xy 27.89936 -173.178385) (xy 27.89936 -175.545496)
			(xy 68.099432 -175.545496) (xy 68.099432 -174.546768) (xy 68.09992 -174.514727) (xy 68.108001 -174.451157)
			(xy 68.124005 -174.389105) (xy 68.147679 -174.329556) (xy 68.178648 -174.273454) (xy 68.21642 -174.221687)
			(xy 68.260397 -174.175077) (xy 68.309882 -174.134362) (xy 68.364091 -174.100187) (xy 68.422164 -174.073094)
			(xy 68.483181 -174.053512) (xy 68.546175 -174.041752) (xy 68.610147 -174.038001) (xy 68.674084 -174.042317)
			(xy 68.736972 -174.054633) (xy 68.797813 -174.074752) (xy 68.855645 -174.102357) (xy 68.90955 -174.137009)
			(xy 68.958674 -174.17816) (xy 68.980812 -174.201328) (xy 68.997005 -174.218027) (xy 69.034305 -174.24581)
			(xy 69.076036 -174.266345) (xy 69.120806 -174.278946) (xy 69.167121 -174.283194) (xy 69.213436 -174.278946)
			(xy 69.258206 -174.266345) (xy 69.299937 -174.24581) (xy 69.337237 -174.218027) (xy 69.35343 -174.201328)
			(xy 69.375856 -174.177923) (xy 69.425574 -174.136332) (xy 69.480176 -174.101399) (xy 69.538775 -174.073688)
			(xy 69.60042 -174.053651) (xy 69.664113 -174.041612) (xy 69.728819 -174.037766) (xy 69.793489 -174.042176)
			(xy 69.857075 -174.054771) (xy 69.918543 -174.075344) (xy 69.976898 -174.103565) (xy 70.031193 -174.138973)
			(xy 70.080547 -174.180995) (xy 70.10273 -174.20463) (xy 70.118941 -174.221658) (xy 70.156456 -174.249988)
			(xy 70.198538 -174.270942) (xy 70.243753 -174.283807) (xy 70.290563 -174.288145) (xy 70.337373 -174.283807)
			(xy 70.382588 -174.270942) (xy 70.42467 -174.249988) (xy 70.462185 -174.221658) (xy 70.478396 -174.20463)
			(xy 70.500514 -174.181072) (xy 70.549711 -174.139175) (xy 70.603819 -174.103848) (xy 70.661966 -174.07566)
			(xy 70.723216 -174.055066) (xy 70.786581 -174.042397) (xy 70.851041 -174.037858) (xy 70.915556 -174.041521)
			(xy 70.979088 -174.053327) (xy 71.040612 -174.073087) (xy 71.099137 -174.100482) (xy 71.15372 -174.135071)
			(xy 71.203482 -174.176295) (xy 71.225918 -174.19955) (xy 71.242098 -174.216083) (xy 71.279299 -174.24357)
			(xy 71.320857 -174.263877) (xy 71.365402 -174.276336) (xy 71.411465 -174.280535) (xy 71.457528 -174.276336)
			(xy 71.502073 -174.263877) (xy 71.543631 -174.24357) (xy 71.580832 -174.216083) (xy 71.597012 -174.19955)
			(xy 71.619261 -174.176561) (xy 71.668462 -174.135668) (xy 71.722404 -174.101271) (xy 71.780236 -174.073914)
			(xy 71.841043 -174.054029) (xy 71.903864 -174.04193) (xy 71.967707 -174.037809) (xy 72.031563 -174.041731)
			(xy 72.094421 -174.053634) (xy 72.15529 -174.073329) (xy 72.213207 -174.100506) (xy 72.267256 -174.134735)
			(xy 72.316583 -174.175474) (xy 72.360409 -174.222081) (xy 72.398042 -174.273818) (xy 72.428885 -174.329868)
			(xy 72.452452 -174.389345) (xy 72.468371 -174.451309) (xy 72.476389 -174.51478) (xy 72.476868 -174.546768)
			(xy 72.476868 -175.545496) (xy 72.476374 -175.578232) (xy 72.467933 -175.643158) (xy 72.451228 -175.706463)
			(xy 72.426536 -175.767101) (xy 72.394265 -175.824068) (xy 72.375014 -175.85055) (xy 72.349868 -175.884332)
			(xy 72.349868 -175.901604) (xy 72.334374 -175.901604) (xy 72.29856 -175.93183) (xy 72.273383 -175.952683)
			(xy 72.218651 -175.988434) (xy 72.159786 -176.016873) (xy 72.097761 -176.037528) (xy 72.033599 -176.050059)
			(xy 71.96836 -176.054259) (xy 71.903121 -176.050059) (xy 71.838959 -176.037528) (xy 71.776934 -176.016873)
			(xy 71.718069 -175.988434) (xy 71.663337 -175.952683) (xy 71.63816 -175.93183) (xy 71.602346 -175.901604)
			(xy 71.586852 -175.901604) (xy 71.586852 -175.884332) (xy 71.561706 -175.85055) (xy 71.551062 -175.83612)
			(xy 71.531614 -175.805992) (xy 71.522844 -175.790352) (xy 71.51522 -175.777283) (xy 71.494882 -175.754894)
			(xy 71.469837 -175.737933) (xy 71.441499 -175.727358) (xy 71.411465 -175.723765) (xy 71.381431 -175.727358)
			(xy 71.353093 -175.737933) (xy 71.328048 -175.754894) (xy 71.30771 -175.777283) (xy 71.300086 -175.790352)
			(xy 71.291307 -175.805986) (xy 71.271857 -175.836113) (xy 71.261224 -175.85055) (xy 71.235824 -175.884332)
			(xy 71.235824 -175.901604) (xy 71.220584 -175.901604) (xy 71.18477 -175.93183) (xy 71.159593 -175.952683)
			(xy 71.104861 -175.988434) (xy 71.045996 -176.016873) (xy 70.983971 -176.037528) (xy 70.919809 -176.050059)
			(xy 70.85457 -176.054259) (xy 70.789331 -176.050059) (xy 70.725169 -176.037528) (xy 70.663144 -176.016873)
			(xy 70.604279 -175.988434) (xy 70.549547 -175.952683) (xy 70.52437 -175.93183) (xy 70.488556 -175.901604)
			(xy 70.473316 -175.901604) (xy 70.473316 -175.884332) (xy 70.447916 -175.85055) (xy 70.435477 -175.833662)
			(xy 70.413097 -175.798184) (xy 70.403212 -175.779684) (xy 70.39574 -175.766172) (xy 70.375385 -175.742966)
			(xy 70.350043 -175.725341) (xy 70.321204 -175.714334) (xy 70.290563 -175.710591) (xy 70.259922 -175.714334)
			(xy 70.231083 -175.725341) (xy 70.205741 -175.742966) (xy 70.185386 -175.766172) (xy 70.177914 -175.779684)
			(xy 70.168039 -175.798189) (xy 70.145659 -175.833669) (xy 70.13321 -175.85055) (xy 70.108064 -175.884332)
			(xy 70.108064 -175.901604) (xy 70.09257 -175.901604) (xy 70.056756 -175.93183) (xy 70.031579 -175.952683)
			(xy 69.976847 -175.988434) (xy 69.917982 -176.016873) (xy 69.855957 -176.037528) (xy 69.791795 -176.050059)
			(xy 69.726556 -176.054259) (xy 69.661317 -176.050059) (xy 69.597155 -176.037528) (xy 69.53513 -176.016873)
			(xy 69.476265 -175.988434) (xy 69.421533 -175.952683) (xy 69.396356 -175.93183) (xy 69.360542 -175.901604)
			(xy 69.345048 -175.901604) (xy 69.345048 -175.884332) (xy 69.319902 -175.85055) (xy 69.308648 -175.83523)
			(xy 69.288179 -175.803193) (xy 69.279008 -175.786542) (xy 69.271415 -175.773327) (xy 69.251054 -175.750659)
			(xy 69.225893 -175.733473) (xy 69.197372 -175.722752) (xy 69.167121 -175.719109) (xy 69.13687 -175.722752)
			(xy 69.108349 -175.733473) (xy 69.083188 -175.750659) (xy 69.062827 -175.773327) (xy 69.055234 -175.786542)
			(xy 69.046083 -175.803205) (xy 69.025611 -175.835241) (xy 69.01434 -175.85055) (xy 68.98894 -175.884332)
			(xy 68.98894 -175.901604) (xy 68.9737 -175.901604) (xy 68.937886 -175.93183) (xy 68.912709 -175.952683)
			(xy 68.857977 -175.988434) (xy 68.799112 -176.016873) (xy 68.737087 -176.037528) (xy 68.672925 -176.050059)
			(xy 68.607686 -176.054259) (xy 68.542447 -176.050059) (xy 68.478285 -176.037528) (xy 68.41626 -176.016873)
			(xy 68.357395 -175.988434) (xy 68.302663 -175.952683) (xy 68.277486 -175.93183) (xy 68.241672 -175.901604)
			(xy 68.226432 -175.901604) (xy 68.226432 -175.884332) (xy 68.201032 -175.85055) (xy 68.181811 -175.824056)
			(xy 68.149581 -175.767085) (xy 68.124939 -175.706445) (xy 68.108294 -175.643142) (xy 68.099922 -175.578224)
			(xy 68.099432 -175.545496) (xy 27.89936 -175.545496) (xy 27.89936 -177.347626) (xy 27.899906 -177.364274)
			(xy 27.908528 -177.396435) (xy 27.925177 -177.425269) (xy 27.948719 -177.448815) (xy 27.977552 -177.465467)
			(xy 28.009712 -177.474092) (xy 28.02636 -177.474626) (xy 37.475668 -177.474626) (xy 39.50335 -179.502308)
			(xy 39.50335 -181.794912) (xy 39.51732 -181.794912) (xy 39.51732 -184.71007) (xy 39.818317 -184.71007)
			(xy 39.822324 -184.594046) (xy 39.834326 -184.478574) (xy 39.854266 -184.364206) (xy 39.882049 -184.251486)
			(xy 39.917543 -184.140952) (xy 39.960578 -184.033129) (xy 40.010949 -183.928532) (xy 40.068416 -183.82766)
			(xy 40.132706 -183.730993) (xy 40.203511 -183.638992) (xy 40.280495 -183.552095) (xy 40.363291 -183.470716)
			(xy 40.451504 -183.395243) (xy 40.544714 -183.326036) (xy 40.642477 -183.263424) (xy 40.744326 -183.207707)
			(xy 40.849776 -183.159149) (xy 40.958325 -183.117981) (xy 41.069456 -183.084401) (xy 41.182639 -183.058568)
			(xy 41.297334 -183.040605) (xy 41.412996 -183.030597) (xy 41.529072 -183.028594) (xy 41.64501 -183.034603)
			(xy 41.760257 -183.048596) (xy 41.874263 -183.070507) (xy 41.986487 -183.100232) (xy 42.096393 -183.137628)
			(xy 42.203456 -183.182517) (xy 42.307168 -183.234686) (xy 42.407033 -183.293886) (xy 42.502576 -183.359835)
			(xy 42.502858 -183.36006) (xy 43.327831 -183.36006) (xy 43.331866 -183.284356) (xy 43.343925 -183.209511)
			(xy 43.363871 -183.13637) (xy 43.391478 -183.065765) (xy 43.426434 -182.998494) (xy 43.468342 -182.935319)
			(xy 43.516728 -182.876957) (xy 43.571044 -182.824069) (xy 43.630673 -182.777254) (xy 43.694941 -182.737042)
			(xy 43.763118 -182.70389) (xy 43.834434 -182.678172) (xy 43.908079 -182.66018) (xy 43.983219 -182.650118)
			(xy 44.059003 -182.648099) (xy 44.134573 -182.654148) (xy 44.209071 -182.668195) (xy 44.281654 -182.690081)
			(xy 44.3515 -182.719558) (xy 44.417817 -182.756293) (xy 44.479853 -182.799868) (xy 44.536906 -182.84979)
			(xy 44.58833 -182.905494) (xy 44.633541 -182.966349) (xy 44.672028 -183.031664) (xy 44.703354 -183.1007)
			(xy 44.727164 -183.172675) (xy 44.743189 -183.246773) (xy 44.751248 -183.322154) (xy 44.751752 -183.36006)
			(xy 45.867831 -183.36006) (xy 45.871866 -183.284356) (xy 45.883925 -183.209511) (xy 45.903871 -183.13637)
			(xy 45.931478 -183.065765) (xy 45.966434 -182.998494) (xy 46.008342 -182.935319) (xy 46.056728 -182.876957)
			(xy 46.111044 -182.824069) (xy 46.170673 -182.777254) (xy 46.234941 -182.737042) (xy 46.303118 -182.70389)
			(xy 46.374434 -182.678172) (xy 46.448079 -182.66018) (xy 46.523219 -182.650118) (xy 46.599003 -182.648099)
			(xy 46.674573 -182.654148) (xy 46.749071 -182.668195) (xy 46.821654 -182.690081) (xy 46.8915 -182.719558)
			(xy 46.957817 -182.756293) (xy 47.019853 -182.799868) (xy 47.076906 -182.84979) (xy 47.12833 -182.905494)
			(xy 47.173541 -182.966349) (xy 47.212028 -183.031664) (xy 47.243354 -183.1007) (xy 47.267164 -183.172675)
			(xy 47.283189 -183.246773) (xy 47.291248 -183.322154) (xy 47.291752 -183.36006) (xy 48.407831 -183.36006)
			(xy 48.411866 -183.284356) (xy 48.423925 -183.209511) (xy 48.443871 -183.13637) (xy 48.471478 -183.065765)
			(xy 48.506434 -182.998494) (xy 48.548342 -182.935319) (xy 48.596728 -182.876957) (xy 48.651044 -182.824069)
			(xy 48.710673 -182.777254) (xy 48.774941 -182.737042) (xy 48.843118 -182.70389) (xy 48.914434 -182.678172)
			(xy 48.988079 -182.66018) (xy 49.063219 -182.650118) (xy 49.139003 -182.648099) (xy 49.214573 -182.654148)
			(xy 49.289071 -182.668195) (xy 49.361654 -182.690081) (xy 49.4315 -182.719558) (xy 49.497817 -182.756293)
			(xy 49.559853 -182.799868) (xy 49.616906 -182.84979) (xy 49.66833 -182.905494) (xy 49.713541 -182.966349)
			(xy 49.752028 -183.031664) (xy 49.783354 -183.1007) (xy 49.807164 -183.172675) (xy 49.823189 -183.246773)
			(xy 49.831248 -183.322154) (xy 49.831752 -183.36006) (xy 50.947831 -183.36006) (xy 50.951866 -183.284356)
			(xy 50.963925 -183.209511) (xy 50.983871 -183.13637) (xy 51.011478 -183.065765) (xy 51.046434 -182.998494)
			(xy 51.088342 -182.935319) (xy 51.136728 -182.876957) (xy 51.191044 -182.824069) (xy 51.250673 -182.777254)
			(xy 51.314941 -182.737042) (xy 51.383118 -182.70389) (xy 51.454434 -182.678172) (xy 51.528079 -182.66018)
			(xy 51.603219 -182.650118) (xy 51.679003 -182.648099) (xy 51.754573 -182.654148) (xy 51.829071 -182.668195)
			(xy 51.901654 -182.690081) (xy 51.9715 -182.719558) (xy 52.037817 -182.756293) (xy 52.099853 -182.799868)
			(xy 52.156906 -182.84979) (xy 52.20833 -182.905494) (xy 52.253541 -182.966349) (xy 52.292028 -183.031664)
			(xy 52.323354 -183.1007) (xy 52.347164 -183.172675) (xy 52.363189 -183.246773) (xy 52.371248 -183.322154)
			(xy 52.371752 -183.36006) (xy 53.487831 -183.36006) (xy 53.491866 -183.284356) (xy 53.503925 -183.209511)
			(xy 53.523871 -183.13637) (xy 53.551478 -183.065765) (xy 53.586434 -182.998494) (xy 53.628342 -182.935319)
			(xy 53.676728 -182.876957) (xy 53.731044 -182.824069) (xy 53.790673 -182.777254) (xy 53.854941 -182.737042)
			(xy 53.923118 -182.70389) (xy 53.994434 -182.678172) (xy 54.068079 -182.66018) (xy 54.143219 -182.650118)
			(xy 54.219003 -182.648099) (xy 54.294573 -182.654148) (xy 54.369071 -182.668195) (xy 54.441654 -182.690081)
			(xy 54.5115 -182.719558) (xy 54.577817 -182.756293) (xy 54.639853 -182.799868) (xy 54.696906 -182.84979)
			(xy 54.74833 -182.905494) (xy 54.793541 -182.966349) (xy 54.832028 -183.031664) (xy 54.863354 -183.1007)
			(xy 54.887164 -183.172675) (xy 54.903189 -183.246773) (xy 54.911248 -183.322154) (xy 54.911752 -183.36006)
			(xy 56.027831 -183.36006) (xy 56.031866 -183.284356) (xy 56.043925 -183.209511) (xy 56.063871 -183.13637)
			(xy 56.091478 -183.065765) (xy 56.126434 -182.998494) (xy 56.168342 -182.935319) (xy 56.216728 -182.876957)
			(xy 56.271044 -182.824069) (xy 56.330673 -182.777254) (xy 56.394941 -182.737042) (xy 56.463118 -182.70389)
			(xy 56.534434 -182.678172) (xy 56.608079 -182.66018) (xy 56.683219 -182.650118) (xy 56.759003 -182.648099)
			(xy 56.834573 -182.654148) (xy 56.909071 -182.668195) (xy 56.981654 -182.690081) (xy 57.0515 -182.719558)
			(xy 57.117817 -182.756293) (xy 57.179853 -182.799868) (xy 57.236906 -182.84979) (xy 57.28833 -182.905494)
			(xy 57.333541 -182.966349) (xy 57.372028 -183.031664) (xy 57.403354 -183.1007) (xy 57.427164 -183.172675)
			(xy 57.443189 -183.246773) (xy 57.451248 -183.322154) (xy 57.451752 -183.36006) (xy 58.567831 -183.36006)
			(xy 58.571866 -183.284356) (xy 58.583925 -183.209511) (xy 58.603871 -183.13637) (xy 58.631478 -183.065765)
			(xy 58.666434 -182.998494) (xy 58.708342 -182.935319) (xy 58.756728 -182.876957) (xy 58.811044 -182.824069)
			(xy 58.870673 -182.777254) (xy 58.934941 -182.737042) (xy 59.003118 -182.70389) (xy 59.074434 -182.678172)
			(xy 59.148079 -182.66018) (xy 59.223219 -182.650118) (xy 59.299003 -182.648099) (xy 59.374573 -182.654148)
			(xy 59.449071 -182.668195) (xy 59.521654 -182.690081) (xy 59.5915 -182.719558) (xy 59.657817 -182.756293)
			(xy 59.719853 -182.799868) (xy 59.776906 -182.84979) (xy 59.82833 -182.905494) (xy 59.873541 -182.966349)
			(xy 59.912028 -183.031664) (xy 59.943354 -183.1007) (xy 59.967164 -183.172675) (xy 59.983189 -183.246773)
			(xy 59.991248 -183.322154) (xy 59.991752 -183.36006) (xy 61.107831 -183.36006) (xy 61.111866 -183.284356)
			(xy 61.123925 -183.209511) (xy 61.143871 -183.13637) (xy 61.171478 -183.065765) (xy 61.206434 -182.998494)
			(xy 61.248342 -182.935319) (xy 61.296728 -182.876957) (xy 61.351044 -182.824069) (xy 61.410673 -182.777254)
			(xy 61.474941 -182.737042) (xy 61.543118 -182.70389) (xy 61.614434 -182.678172) (xy 61.688079 -182.66018)
			(xy 61.763219 -182.650118) (xy 61.839003 -182.648099) (xy 61.914573 -182.654148) (xy 61.989071 -182.668195)
			(xy 62.061654 -182.690081) (xy 62.1315 -182.719558) (xy 62.197817 -182.756293) (xy 62.259853 -182.799868)
			(xy 62.265798 -182.80507) (xy 86.197951 -182.80507) (xy 86.201986 -182.729366) (xy 86.214045 -182.654521)
			(xy 86.233991 -182.58138) (xy 86.261598 -182.510775) (xy 86.296554 -182.443504) (xy 86.338462 -182.380329)
			(xy 86.386848 -182.321967) (xy 86.441164 -182.269079) (xy 86.500793 -182.222264) (xy 86.565061 -182.182052)
			(xy 86.633238 -182.1489) (xy 86.704554 -182.123182) (xy 86.778199 -182.10519) (xy 86.853339 -182.095128)
			(xy 86.929123 -182.093109) (xy 87.004693 -182.099158) (xy 87.079191 -182.113205) (xy 87.151774 -182.135091)
			(xy 87.22162 -182.164568) (xy 87.287937 -182.201303) (xy 87.349973 -182.244878) (xy 87.407026 -182.2948)
			(xy 87.45845 -182.350504) (xy 87.503661 -182.411359) (xy 87.542148 -182.476674) (xy 87.573474 -182.54571)
			(xy 87.597284 -182.617685) (xy 87.613309 -182.691783) (xy 87.621368 -182.767164) (xy 87.621872 -182.80507)
			(xy 88.737951 -182.80507) (xy 88.741986 -182.729366) (xy 88.754045 -182.654521) (xy 88.773991 -182.58138)
			(xy 88.801598 -182.510775) (xy 88.836554 -182.443504) (xy 88.878462 -182.380329) (xy 88.926848 -182.321967)
			(xy 88.981164 -182.269079) (xy 89.040793 -182.222264) (xy 89.105061 -182.182052) (xy 89.173238 -182.1489)
			(xy 89.244554 -182.123182) (xy 89.318199 -182.10519) (xy 89.393339 -182.095128) (xy 89.469123 -182.093109)
			(xy 89.544693 -182.099158) (xy 89.619191 -182.113205) (xy 89.691774 -182.135091) (xy 89.76162 -182.164568)
			(xy 89.827937 -182.201303) (xy 89.889973 -182.244878) (xy 89.947026 -182.2948) (xy 89.99845 -182.350504)
			(xy 90.043661 -182.411359) (xy 90.082148 -182.476674) (xy 90.113474 -182.54571) (xy 90.137284 -182.617685)
			(xy 90.153309 -182.691783) (xy 90.161368 -182.767164) (xy 90.161872 -182.80507) (xy 91.277951 -182.80507)
			(xy 91.281986 -182.729366) (xy 91.294045 -182.654521) (xy 91.313991 -182.58138) (xy 91.341598 -182.510775)
			(xy 91.376554 -182.443504) (xy 91.418462 -182.380329) (xy 91.466848 -182.321967) (xy 91.521164 -182.269079)
			(xy 91.580793 -182.222264) (xy 91.645061 -182.182052) (xy 91.713238 -182.1489) (xy 91.784554 -182.123182)
			(xy 91.858199 -182.10519) (xy 91.933339 -182.095128) (xy 92.009123 -182.093109) (xy 92.084693 -182.099158)
			(xy 92.159191 -182.113205) (xy 92.231774 -182.135091) (xy 92.30162 -182.164568) (xy 92.367937 -182.201303)
			(xy 92.429973 -182.244878) (xy 92.487026 -182.2948) (xy 92.53845 -182.350504) (xy 92.583661 -182.411359)
			(xy 92.622148 -182.476674) (xy 92.653474 -182.54571) (xy 92.677284 -182.617685) (xy 92.693309 -182.691783)
			(xy 92.701368 -182.767164) (xy 92.701872 -182.80507) (xy 92.701368 -182.842976) (xy 92.693309 -182.918357)
			(xy 92.677284 -182.992455) (xy 92.653474 -183.06443) (xy 92.622148 -183.133466) (xy 92.583661 -183.198781)
			(xy 92.53845 -183.259636) (xy 92.487026 -183.31534) (xy 92.429973 -183.365262) (xy 92.367937 -183.408837)
			(xy 92.30162 -183.445572) (xy 92.231774 -183.475049) (xy 92.159191 -183.496935) (xy 92.084693 -183.510982)
			(xy 92.009123 -183.517031) (xy 91.933339 -183.515012) (xy 91.858199 -183.50495) (xy 91.784554 -183.486958)
			(xy 91.713238 -183.46124) (xy 91.645061 -183.428088) (xy 91.580793 -183.387876) (xy 91.521164 -183.341061)
			(xy 91.466848 -183.288173) (xy 91.418462 -183.229811) (xy 91.376554 -183.166636) (xy 91.341598 -183.099365)
			(xy 91.313991 -183.02876) (xy 91.294045 -182.955619) (xy 91.281986 -182.880774) (xy 91.277951 -182.80507)
			(xy 90.161872 -182.80507) (xy 90.161368 -182.842976) (xy 90.153309 -182.918357) (xy 90.137284 -182.992455)
			(xy 90.113474 -183.06443) (xy 90.082148 -183.133466) (xy 90.043661 -183.198781) (xy 89.99845 -183.259636)
			(xy 89.947026 -183.31534) (xy 89.889973 -183.365262) (xy 89.827937 -183.408837) (xy 89.76162 -183.445572)
			(xy 89.691774 -183.475049) (xy 89.619191 -183.496935) (xy 89.544693 -183.510982) (xy 89.469123 -183.517031)
			(xy 89.393339 -183.515012) (xy 89.318199 -183.50495) (xy 89.244554 -183.486958) (xy 89.173238 -183.46124)
			(xy 89.105061 -183.428088) (xy 89.040793 -183.387876) (xy 88.981164 -183.341061) (xy 88.926848 -183.288173)
			(xy 88.878462 -183.229811) (xy 88.836554 -183.166636) (xy 88.801598 -183.099365) (xy 88.773991 -183.02876)
			(xy 88.754045 -182.955619) (xy 88.741986 -182.880774) (xy 88.737951 -182.80507) (xy 87.621872 -182.80507)
			(xy 87.621368 -182.842976) (xy 87.613309 -182.918357) (xy 87.597284 -182.992455) (xy 87.573474 -183.06443)
			(xy 87.542148 -183.133466) (xy 87.503661 -183.198781) (xy 87.45845 -183.259636) (xy 87.407026 -183.31534)
			(xy 87.349973 -183.365262) (xy 87.287937 -183.408837) (xy 87.22162 -183.445572) (xy 87.151774 -183.475049)
			(xy 87.079191 -183.496935) (xy 87.004693 -183.510982) (xy 86.929123 -183.517031) (xy 86.853339 -183.515012)
			(xy 86.778199 -183.50495) (xy 86.704554 -183.486958) (xy 86.633238 -183.46124) (xy 86.565061 -183.428088)
			(xy 86.500793 -183.387876) (xy 86.441164 -183.341061) (xy 86.386848 -183.288173) (xy 86.338462 -183.229811)
			(xy 86.296554 -183.166636) (xy 86.261598 -183.099365) (xy 86.233991 -183.02876) (xy 86.214045 -182.955619)
			(xy 86.201986 -182.880774) (xy 86.197951 -182.80507) (xy 62.265798 -182.80507) (xy 62.316906 -182.84979)
			(xy 62.36833 -182.905494) (xy 62.413541 -182.966349) (xy 62.452028 -183.031664) (xy 62.483354 -183.1007)
			(xy 62.507164 -183.172675) (xy 62.523189 -183.246773) (xy 62.531248 -183.322154) (xy 62.531752 -183.36006)
			(xy 62.531248 -183.397966) (xy 62.523189 -183.473347) (xy 62.507164 -183.547445) (xy 62.483354 -183.61942)
			(xy 62.452028 -183.688456) (xy 62.413541 -183.753771) (xy 62.36833 -183.814626) (xy 62.316906 -183.87033)
			(xy 62.259853 -183.920252) (xy 62.197817 -183.963827) (xy 62.1315 -184.000562) (xy 62.061654 -184.030039)
			(xy 61.989071 -184.051925) (xy 61.914573 -184.065972) (xy 61.839003 -184.072021) (xy 61.763219 -184.070002)
			(xy 61.688079 -184.05994) (xy 61.614434 -184.041948) (xy 61.543118 -184.01623) (xy 61.474941 -183.983078)
			(xy 61.410673 -183.942866) (xy 61.351044 -183.896051) (xy 61.296728 -183.843163) (xy 61.248342 -183.784801)
			(xy 61.206434 -183.721626) (xy 61.171478 -183.654355) (xy 61.143871 -183.58375) (xy 61.123925 -183.510609)
			(xy 61.111866 -183.435764) (xy 61.107831 -183.36006) (xy 59.991752 -183.36006) (xy 59.991248 -183.397966)
			(xy 59.983189 -183.473347) (xy 59.967164 -183.547445) (xy 59.943354 -183.61942) (xy 59.912028 -183.688456)
			(xy 59.873541 -183.753771) (xy 59.82833 -183.814626) (xy 59.776906 -183.87033) (xy 59.719853 -183.920252)
			(xy 59.657817 -183.963827) (xy 59.5915 -184.000562) (xy 59.521654 -184.030039) (xy 59.449071 -184.051925)
			(xy 59.374573 -184.065972) (xy 59.299003 -184.072021) (xy 59.223219 -184.070002) (xy 59.148079 -184.05994)
			(xy 59.074434 -184.041948) (xy 59.003118 -184.01623) (xy 58.934941 -183.983078) (xy 58.870673 -183.942866)
			(xy 58.811044 -183.896051) (xy 58.756728 -183.843163) (xy 58.708342 -183.784801) (xy 58.666434 -183.721626)
			(xy 58.631478 -183.654355) (xy 58.603871 -183.58375) (xy 58.583925 -183.510609) (xy 58.571866 -183.435764)
			(xy 58.567831 -183.36006) (xy 57.451752 -183.36006) (xy 57.451248 -183.397966) (xy 57.443189 -183.473347)
			(xy 57.427164 -183.547445) (xy 57.403354 -183.61942) (xy 57.372028 -183.688456) (xy 57.333541 -183.753771)
			(xy 57.28833 -183.814626) (xy 57.236906 -183.87033) (xy 57.179853 -183.920252) (xy 57.117817 -183.963827)
			(xy 57.0515 -184.000562) (xy 56.981654 -184.030039) (xy 56.909071 -184.051925) (xy 56.834573 -184.065972)
			(xy 56.759003 -184.072021) (xy 56.683219 -184.070002) (xy 56.608079 -184.05994) (xy 56.534434 -184.041948)
			(xy 56.463118 -184.01623) (xy 56.394941 -183.983078) (xy 56.330673 -183.942866) (xy 56.271044 -183.896051)
			(xy 56.216728 -183.843163) (xy 56.168342 -183.784801) (xy 56.126434 -183.721626) (xy 56.091478 -183.654355)
			(xy 56.063871 -183.58375) (xy 56.043925 -183.510609) (xy 56.031866 -183.435764) (xy 56.027831 -183.36006)
			(xy 54.911752 -183.36006) (xy 54.911248 -183.397966) (xy 54.903189 -183.473347) (xy 54.887164 -183.547445)
			(xy 54.863354 -183.61942) (xy 54.832028 -183.688456) (xy 54.793541 -183.753771) (xy 54.74833 -183.814626)
			(xy 54.696906 -183.87033) (xy 54.639853 -183.920252) (xy 54.577817 -183.963827) (xy 54.5115 -184.000562)
			(xy 54.441654 -184.030039) (xy 54.369071 -184.051925) (xy 54.294573 -184.065972) (xy 54.219003 -184.072021)
			(xy 54.143219 -184.070002) (xy 54.068079 -184.05994) (xy 53.994434 -184.041948) (xy 53.923118 -184.01623)
			(xy 53.854941 -183.983078) (xy 53.790673 -183.942866) (xy 53.731044 -183.896051) (xy 53.676728 -183.843163)
			(xy 53.628342 -183.784801) (xy 53.586434 -183.721626) (xy 53.551478 -183.654355) (xy 53.523871 -183.58375)
			(xy 53.503925 -183.510609) (xy 53.491866 -183.435764) (xy 53.487831 -183.36006) (xy 52.371752 -183.36006)
			(xy 52.371248 -183.397966) (xy 52.363189 -183.473347) (xy 52.347164 -183.547445) (xy 52.323354 -183.61942)
			(xy 52.292028 -183.688456) (xy 52.253541 -183.753771) (xy 52.20833 -183.814626) (xy 52.156906 -183.87033)
			(xy 52.099853 -183.920252) (xy 52.037817 -183.963827) (xy 51.9715 -184.000562) (xy 51.901654 -184.030039)
			(xy 51.829071 -184.051925) (xy 51.754573 -184.065972) (xy 51.679003 -184.072021) (xy 51.603219 -184.070002)
			(xy 51.528079 -184.05994) (xy 51.454434 -184.041948) (xy 51.383118 -184.01623) (xy 51.314941 -183.983078)
			(xy 51.250673 -183.942866) (xy 51.191044 -183.896051) (xy 51.136728 -183.843163) (xy 51.088342 -183.784801)
			(xy 51.046434 -183.721626) (xy 51.011478 -183.654355) (xy 50.983871 -183.58375) (xy 50.963925 -183.510609)
			(xy 50.951866 -183.435764) (xy 50.947831 -183.36006) (xy 49.831752 -183.36006) (xy 49.831248 -183.397966)
			(xy 49.823189 -183.473347) (xy 49.807164 -183.547445) (xy 49.783354 -183.61942) (xy 49.752028 -183.688456)
			(xy 49.713541 -183.753771) (xy 49.66833 -183.814626) (xy 49.616906 -183.87033) (xy 49.559853 -183.920252)
			(xy 49.497817 -183.963827) (xy 49.4315 -184.000562) (xy 49.361654 -184.030039) (xy 49.289071 -184.051925)
			(xy 49.214573 -184.065972) (xy 49.139003 -184.072021) (xy 49.063219 -184.070002) (xy 48.988079 -184.05994)
			(xy 48.914434 -184.041948) (xy 48.843118 -184.01623) (xy 48.774941 -183.983078) (xy 48.710673 -183.942866)
			(xy 48.651044 -183.896051) (xy 48.596728 -183.843163) (xy 48.548342 -183.784801) (xy 48.506434 -183.721626)
			(xy 48.471478 -183.654355) (xy 48.443871 -183.58375) (xy 48.423925 -183.510609) (xy 48.411866 -183.435764)
			(xy 48.407831 -183.36006) (xy 47.291752 -183.36006) (xy 47.291248 -183.397966) (xy 47.283189 -183.473347)
			(xy 47.267164 -183.547445) (xy 47.243354 -183.61942) (xy 47.212028 -183.688456) (xy 47.173541 -183.753771)
			(xy 47.12833 -183.814626) (xy 47.076906 -183.87033) (xy 47.019853 -183.920252) (xy 46.957817 -183.963827)
			(xy 46.8915 -184.000562) (xy 46.821654 -184.030039) (xy 46.749071 -184.051925) (xy 46.674573 -184.065972)
			(xy 46.599003 -184.072021) (xy 46.523219 -184.070002) (xy 46.448079 -184.05994) (xy 46.374434 -184.041948)
			(xy 46.303118 -184.01623) (xy 46.234941 -183.983078) (xy 46.170673 -183.942866) (xy 46.111044 -183.896051)
			(xy 46.056728 -183.843163) (xy 46.008342 -183.784801) (xy 45.966434 -183.721626) (xy 45.931478 -183.654355)
			(xy 45.903871 -183.58375) (xy 45.883925 -183.510609) (xy 45.871866 -183.435764) (xy 45.867831 -183.36006)
			(xy 44.751752 -183.36006) (xy 44.751248 -183.397966) (xy 44.743189 -183.473347) (xy 44.727164 -183.547445)
			(xy 44.703354 -183.61942) (xy 44.672028 -183.688456) (xy 44.633541 -183.753771) (xy 44.58833 -183.814626)
			(xy 44.536906 -183.87033) (xy 44.479853 -183.920252) (xy 44.417817 -183.963827) (xy 44.3515 -184.000562)
			(xy 44.281654 -184.030039) (xy 44.209071 -184.051925) (xy 44.134573 -184.065972) (xy 44.059003 -184.072021)
			(xy 43.983219 -184.070002) (xy 43.908079 -184.05994) (xy 43.834434 -184.041948) (xy 43.763118 -184.01623)
			(xy 43.694941 -183.983078) (xy 43.630673 -183.942866) (xy 43.571044 -183.896051) (xy 43.516728 -183.843163)
			(xy 43.468342 -183.784801) (xy 43.426434 -183.721626) (xy 43.391478 -183.654355) (xy 43.363871 -183.58375)
			(xy 43.343925 -183.510609) (xy 43.331866 -183.435764) (xy 43.327831 -183.36006) (xy 42.502858 -183.36006)
			(xy 42.593342 -183.432218) (xy 42.678897 -183.510691) (xy 42.758835 -183.594879) (xy 42.832774 -183.684381)
			(xy 42.900362 -183.778772) (xy 42.961276 -183.8776) (xy 43.015228 -183.980396) (xy 43.056858 -184.07507)
			(xy 84.927951 -184.07507) (xy 84.931986 -183.999366) (xy 84.944045 -183.924521) (xy 84.963991 -183.85138)
			(xy 84.991598 -183.780775) (xy 85.026554 -183.713504) (xy 85.068462 -183.650329) (xy 85.116848 -183.591967)
			(xy 85.171164 -183.539079) (xy 85.230793 -183.492264) (xy 85.295061 -183.452052) (xy 85.363238 -183.4189)
			(xy 85.434554 -183.393182) (xy 85.508199 -183.37519) (xy 85.583339 -183.365128) (xy 85.659123 -183.363109)
			(xy 85.734693 -183.369158) (xy 85.809191 -183.383205) (xy 85.881774 -183.405091) (xy 85.95162 -183.434568)
			(xy 86.017937 -183.471303) (xy 86.079973 -183.514878) (xy 86.137026 -183.5648) (xy 86.18845 -183.620504)
			(xy 86.233661 -183.681359) (xy 86.272148 -183.746674) (xy 86.303474 -183.81571) (xy 86.327284 -183.887685)
			(xy 86.343309 -183.961783) (xy 86.351368 -184.037164) (xy 86.351872 -184.07507) (xy 87.467951 -184.07507)
			(xy 87.471986 -183.999366) (xy 87.484045 -183.924521) (xy 87.503991 -183.85138) (xy 87.531598 -183.780775)
			(xy 87.566554 -183.713504) (xy 87.608462 -183.650329) (xy 87.656848 -183.591967) (xy 87.711164 -183.539079)
			(xy 87.770793 -183.492264) (xy 87.835061 -183.452052) (xy 87.903238 -183.4189) (xy 87.974554 -183.393182)
			(xy 88.048199 -183.37519) (xy 88.123339 -183.365128) (xy 88.199123 -183.363109) (xy 88.274693 -183.369158)
			(xy 88.349191 -183.383205) (xy 88.421774 -183.405091) (xy 88.49162 -183.434568) (xy 88.557937 -183.471303)
			(xy 88.619973 -183.514878) (xy 88.677026 -183.5648) (xy 88.72845 -183.620504) (xy 88.773661 -183.681359)
			(xy 88.812148 -183.746674) (xy 88.843474 -183.81571) (xy 88.867284 -183.887685) (xy 88.883309 -183.961783)
			(xy 88.891368 -184.037164) (xy 88.891872 -184.07507) (xy 90.007951 -184.07507) (xy 90.011986 -183.999366)
			(xy 90.024045 -183.924521) (xy 90.043991 -183.85138) (xy 90.071598 -183.780775) (xy 90.106554 -183.713504)
			(xy 90.148462 -183.650329) (xy 90.196848 -183.591967) (xy 90.251164 -183.539079) (xy 90.310793 -183.492264)
			(xy 90.375061 -183.452052) (xy 90.443238 -183.4189) (xy 90.514554 -183.393182) (xy 90.588199 -183.37519)
			(xy 90.663339 -183.365128) (xy 90.739123 -183.363109) (xy 90.814693 -183.369158) (xy 90.889191 -183.383205)
			(xy 90.961774 -183.405091) (xy 91.03162 -183.434568) (xy 91.097937 -183.471303) (xy 91.159973 -183.514878)
			(xy 91.217026 -183.5648) (xy 91.26845 -183.620504) (xy 91.313661 -183.681359) (xy 91.352148 -183.746674)
			(xy 91.383474 -183.81571) (xy 91.407284 -183.887685) (xy 91.423309 -183.961783) (xy 91.431368 -184.037164)
			(xy 91.431872 -184.07507) (xy 91.431368 -184.112976) (xy 91.423309 -184.188357) (xy 91.407284 -184.262455)
			(xy 91.383474 -184.33443) (xy 91.352148 -184.403466) (xy 91.313661 -184.468781) (xy 91.26845 -184.529636)
			(xy 91.217026 -184.58534) (xy 91.159973 -184.635262) (xy 91.097937 -184.678837) (xy 91.03162 -184.715572)
			(xy 90.961774 -184.745049) (xy 90.889191 -184.766935) (xy 90.814693 -184.780982) (xy 90.739123 -184.787031)
			(xy 90.663339 -184.785012) (xy 90.588199 -184.77495) (xy 90.514554 -184.756958) (xy 90.443238 -184.73124)
			(xy 90.375061 -184.698088) (xy 90.310793 -184.657876) (xy 90.251164 -184.611061) (xy 90.196848 -184.558173)
			(xy 90.148462 -184.499811) (xy 90.106554 -184.436636) (xy 90.071598 -184.369365) (xy 90.043991 -184.29876)
			(xy 90.024045 -184.225619) (xy 90.011986 -184.150774) (xy 90.007951 -184.07507) (xy 88.891872 -184.07507)
			(xy 88.891368 -184.112976) (xy 88.883309 -184.188357) (xy 88.867284 -184.262455) (xy 88.843474 -184.33443)
			(xy 88.812148 -184.403466) (xy 88.773661 -184.468781) (xy 88.72845 -184.529636) (xy 88.677026 -184.58534)
			(xy 88.619973 -184.635262) (xy 88.557937 -184.678837) (xy 88.49162 -184.715572) (xy 88.421774 -184.745049)
			(xy 88.349191 -184.766935) (xy 88.274693 -184.780982) (xy 88.199123 -184.787031) (xy 88.123339 -184.785012)
			(xy 88.048199 -184.77495) (xy 87.974554 -184.756958) (xy 87.903238 -184.73124) (xy 87.835061 -184.698088)
			(xy 87.770793 -184.657876) (xy 87.711164 -184.611061) (xy 87.656848 -184.558173) (xy 87.608462 -184.499811)
			(xy 87.566554 -184.436636) (xy 87.531598 -184.369365) (xy 87.503991 -184.29876) (xy 87.484045 -184.225619)
			(xy 87.471986 -184.150774) (xy 87.467951 -184.07507) (xy 86.351872 -184.07507) (xy 86.351368 -184.112976)
			(xy 86.343309 -184.188357) (xy 86.327284 -184.262455) (xy 86.303474 -184.33443) (xy 86.272148 -184.403466)
			(xy 86.233661 -184.468781) (xy 86.18845 -184.529636) (xy 86.137026 -184.58534) (xy 86.079973 -184.635262)
			(xy 86.017937 -184.678837) (xy 85.95162 -184.715572) (xy 85.881774 -184.745049) (xy 85.809191 -184.766935)
			(xy 85.734693 -184.780982) (xy 85.659123 -184.787031) (xy 85.583339 -184.785012) (xy 85.508199 -184.77495)
			(xy 85.434554 -184.756958) (xy 85.363238 -184.73124) (xy 85.295061 -184.698088) (xy 85.230793 -184.657876)
			(xy 85.171164 -184.611061) (xy 85.116848 -184.558173) (xy 85.068462 -184.499811) (xy 85.026554 -184.436636)
			(xy 84.991598 -184.369365) (xy 84.963991 -184.29876) (xy 84.944045 -184.225619) (xy 84.931986 -184.150774)
			(xy 84.927951 -184.07507) (xy 43.056858 -184.07507) (xy 43.061958 -184.086669) (xy 43.101246 -184.195913)
			(xy 43.132903 -184.307606) (xy 43.156779 -184.421218) (xy 43.17276 -184.536206) (xy 43.180769 -184.652023)
			(xy 43.18127 -184.71007) (xy 43.180769 -184.768117) (xy 43.17276 -184.883934) (xy 43.156779 -184.998922)
			(xy 43.132903 -185.112534) (xy 43.101246 -185.224227) (xy 43.061958 -185.333471) (xy 43.056858 -185.34507)
			(xy 86.197951 -185.34507) (xy 86.201986 -185.269366) (xy 86.214045 -185.194521) (xy 86.233991 -185.12138)
			(xy 86.261598 -185.050775) (xy 86.296554 -184.983504) (xy 86.338462 -184.920329) (xy 86.386848 -184.861967)
			(xy 86.441164 -184.809079) (xy 86.500793 -184.762264) (xy 86.565061 -184.722052) (xy 86.633238 -184.6889)
			(xy 86.704554 -184.663182) (xy 86.778199 -184.64519) (xy 86.853339 -184.635128) (xy 86.929123 -184.633109)
			(xy 87.004693 -184.639158) (xy 87.079191 -184.653205) (xy 87.151774 -184.675091) (xy 87.22162 -184.704568)
			(xy 87.287937 -184.741303) (xy 87.349973 -184.784878) (xy 87.407026 -184.8348) (xy 87.45845 -184.890504)
			(xy 87.503661 -184.951359) (xy 87.542148 -185.016674) (xy 87.573474 -185.08571) (xy 87.597284 -185.157685)
			(xy 87.613309 -185.231783) (xy 87.621368 -185.307164) (xy 87.621872 -185.34507) (xy 88.737951 -185.34507)
			(xy 88.741986 -185.269366) (xy 88.754045 -185.194521) (xy 88.773991 -185.12138) (xy 88.801598 -185.050775)
			(xy 88.836554 -184.983504) (xy 88.878462 -184.920329) (xy 88.926848 -184.861967) (xy 88.981164 -184.809079)
			(xy 89.040793 -184.762264) (xy 89.105061 -184.722052) (xy 89.173238 -184.6889) (xy 89.244554 -184.663182)
			(xy 89.318199 -184.64519) (xy 89.393339 -184.635128) (xy 89.469123 -184.633109) (xy 89.544693 -184.639158)
			(xy 89.619191 -184.653205) (xy 89.691774 -184.675091) (xy 89.76162 -184.704568) (xy 89.827937 -184.741303)
			(xy 89.889973 -184.784878) (xy 89.947026 -184.8348) (xy 89.99845 -184.890504) (xy 90.043661 -184.951359)
			(xy 90.082148 -185.016674) (xy 90.113474 -185.08571) (xy 90.137284 -185.157685) (xy 90.153309 -185.231783)
			(xy 90.161368 -185.307164) (xy 90.161872 -185.34507) (xy 91.277951 -185.34507) (xy 91.281986 -185.269366)
			(xy 91.294045 -185.194521) (xy 91.313991 -185.12138) (xy 91.341598 -185.050775) (xy 91.376554 -184.983504)
			(xy 91.418462 -184.920329) (xy 91.466848 -184.861967) (xy 91.521164 -184.809079) (xy 91.580793 -184.762264)
			(xy 91.645061 -184.722052) (xy 91.713238 -184.6889) (xy 91.784554 -184.663182) (xy 91.858199 -184.64519)
			(xy 91.933339 -184.635128) (xy 92.009123 -184.633109) (xy 92.084693 -184.639158) (xy 92.159191 -184.653205)
			(xy 92.231774 -184.675091) (xy 92.30162 -184.704568) (xy 92.367937 -184.741303) (xy 92.429973 -184.784878)
			(xy 92.487026 -184.8348) (xy 92.53845 -184.890504) (xy 92.583661 -184.951359) (xy 92.622148 -185.016674)
			(xy 92.653474 -185.08571) (xy 92.677284 -185.157685) (xy 92.693309 -185.231783) (xy 92.701368 -185.307164)
			(xy 92.701872 -185.34507) (xy 92.701368 -185.382976) (xy 92.693309 -185.458357) (xy 92.677284 -185.532455)
			(xy 92.653474 -185.60443) (xy 92.622148 -185.673466) (xy 92.583661 -185.738781) (xy 92.53845 -185.799636)
			(xy 92.487026 -185.85534) (xy 92.429973 -185.905262) (xy 92.367937 -185.948837) (xy 92.30162 -185.985572)
			(xy 92.231774 -186.015049) (xy 92.159191 -186.036935) (xy 92.084693 -186.050982) (xy 92.009123 -186.057031)
			(xy 91.933339 -186.055012) (xy 91.858199 -186.04495) (xy 91.784554 -186.026958) (xy 91.713238 -186.00124)
			(xy 91.645061 -185.968088) (xy 91.580793 -185.927876) (xy 91.521164 -185.881061) (xy 91.466848 -185.828173)
			(xy 91.418462 -185.769811) (xy 91.376554 -185.706636) (xy 91.341598 -185.639365) (xy 91.313991 -185.56876)
			(xy 91.294045 -185.495619) (xy 91.281986 -185.420774) (xy 91.277951 -185.34507) (xy 90.161872 -185.34507)
			(xy 90.161368 -185.382976) (xy 90.153309 -185.458357) (xy 90.137284 -185.532455) (xy 90.113474 -185.60443)
			(xy 90.082148 -185.673466) (xy 90.043661 -185.738781) (xy 89.99845 -185.799636) (xy 89.947026 -185.85534)
			(xy 89.889973 -185.905262) (xy 89.827937 -185.948837) (xy 89.76162 -185.985572) (xy 89.691774 -186.015049)
			(xy 89.619191 -186.036935) (xy 89.544693 -186.050982) (xy 89.469123 -186.057031) (xy 89.393339 -186.055012)
			(xy 89.318199 -186.04495) (xy 89.244554 -186.026958) (xy 89.173238 -186.00124) (xy 89.105061 -185.968088)
			(xy 89.040793 -185.927876) (xy 88.981164 -185.881061) (xy 88.926848 -185.828173) (xy 88.878462 -185.769811)
			(xy 88.836554 -185.706636) (xy 88.801598 -185.639365) (xy 88.773991 -185.56876) (xy 88.754045 -185.495619)
			(xy 88.741986 -185.420774) (xy 88.737951 -185.34507) (xy 87.621872 -185.34507) (xy 87.621368 -185.382976)
			(xy 87.613309 -185.458357) (xy 87.597284 -185.532455) (xy 87.573474 -185.60443) (xy 87.542148 -185.673466)
			(xy 87.503661 -185.738781) (xy 87.45845 -185.799636) (xy 87.407026 -185.85534) (xy 87.349973 -185.905262)
			(xy 87.287937 -185.948837) (xy 87.22162 -185.985572) (xy 87.151774 -186.015049) (xy 87.079191 -186.036935)
			(xy 87.004693 -186.050982) (xy 86.929123 -186.057031) (xy 86.853339 -186.055012) (xy 86.778199 -186.04495)
			(xy 86.704554 -186.026958) (xy 86.633238 -186.00124) (xy 86.565061 -185.968088) (xy 86.500793 -185.927876)
			(xy 86.441164 -185.881061) (xy 86.386848 -185.828173) (xy 86.338462 -185.769811) (xy 86.296554 -185.706636)
			(xy 86.261598 -185.639365) (xy 86.233991 -185.56876) (xy 86.214045 -185.495619) (xy 86.201986 -185.420774)
			(xy 86.197951 -185.34507) (xy 43.056858 -185.34507) (xy 43.055406 -185.348372) (xy 43.328336 -185.348372)
			(xy 44.751752 -185.348372) (xy 44.751752 -186.06008) (xy 45.867831 -186.06008) (xy 45.871866 -185.984376)
			(xy 45.883925 -185.909531) (xy 45.903871 -185.83639) (xy 45.931478 -185.765785) (xy 45.966434 -185.698514)
			(xy 46.008342 -185.635339) (xy 46.056728 -185.576977) (xy 46.111044 -185.524089) (xy 46.170673 -185.477274)
			(xy 46.234941 -185.437062) (xy 46.303118 -185.40391) (xy 46.374434 -185.378192) (xy 46.448079 -185.3602)
			(xy 46.523219 -185.350138) (xy 46.599003 -185.348119) (xy 46.674573 -185.354168) (xy 46.749071 -185.368215)
			(xy 46.821654 -185.390101) (xy 46.8915 -185.419578) (xy 46.957817 -185.456313) (xy 47.019853 -185.499888)
			(xy 47.076906 -185.54981) (xy 47.12833 -185.605514) (xy 47.173541 -185.666369) (xy 47.212028 -185.731684)
			(xy 47.243354 -185.80072) (xy 47.267164 -185.872695) (xy 47.283189 -185.946793) (xy 47.291248 -186.022174)
			(xy 47.291752 -186.06008) (xy 48.407831 -186.06008) (xy 48.411866 -185.984376) (xy 48.423925 -185.909531)
			(xy 48.443871 -185.83639) (xy 48.471478 -185.765785) (xy 48.506434 -185.698514) (xy 48.548342 -185.635339)
			(xy 48.596728 -185.576977) (xy 48.651044 -185.524089) (xy 48.710673 -185.477274) (xy 48.774941 -185.437062)
			(xy 48.843118 -185.40391) (xy 48.914434 -185.378192) (xy 48.988079 -185.3602) (xy 49.063219 -185.350138)
			(xy 49.139003 -185.348119) (xy 49.214573 -185.354168) (xy 49.289071 -185.368215) (xy 49.361654 -185.390101)
			(xy 49.4315 -185.419578) (xy 49.497817 -185.456313) (xy 49.559853 -185.499888) (xy 49.616906 -185.54981)
			(xy 49.66833 -185.605514) (xy 49.713541 -185.666369) (xy 49.752028 -185.731684) (xy 49.783354 -185.80072)
			(xy 49.807164 -185.872695) (xy 49.823189 -185.946793) (xy 49.831248 -186.022174) (xy 49.831752 -186.06008)
			(xy 50.947831 -186.06008) (xy 50.951866 -185.984376) (xy 50.963925 -185.909531) (xy 50.983871 -185.83639)
			(xy 51.011478 -185.765785) (xy 51.046434 -185.698514) (xy 51.088342 -185.635339) (xy 51.136728 -185.576977)
			(xy 51.191044 -185.524089) (xy 51.250673 -185.477274) (xy 51.314941 -185.437062) (xy 51.383118 -185.40391)
			(xy 51.454434 -185.378192) (xy 51.528079 -185.3602) (xy 51.603219 -185.350138) (xy 51.679003 -185.348119)
			(xy 51.754573 -185.354168) (xy 51.829071 -185.368215) (xy 51.901654 -185.390101) (xy 51.9715 -185.419578)
			(xy 52.037817 -185.456313) (xy 52.099853 -185.499888) (xy 52.156906 -185.54981) (xy 52.20833 -185.605514)
			(xy 52.253541 -185.666369) (xy 52.292028 -185.731684) (xy 52.323354 -185.80072) (xy 52.347164 -185.872695)
			(xy 52.363189 -185.946793) (xy 52.371248 -186.022174) (xy 52.371752 -186.06008) (xy 53.487831 -186.06008)
			(xy 53.491866 -185.984376) (xy 53.503925 -185.909531) (xy 53.523871 -185.83639) (xy 53.551478 -185.765785)
			(xy 53.586434 -185.698514) (xy 53.628342 -185.635339) (xy 53.676728 -185.576977) (xy 53.731044 -185.524089)
			(xy 53.790673 -185.477274) (xy 53.854941 -185.437062) (xy 53.923118 -185.40391) (xy 53.994434 -185.378192)
			(xy 54.068079 -185.3602) (xy 54.143219 -185.350138) (xy 54.219003 -185.348119) (xy 54.294573 -185.354168)
			(xy 54.369071 -185.368215) (xy 54.441654 -185.390101) (xy 54.5115 -185.419578) (xy 54.577817 -185.456313)
			(xy 54.639853 -185.499888) (xy 54.696906 -185.54981) (xy 54.74833 -185.605514) (xy 54.793541 -185.666369)
			(xy 54.832028 -185.731684) (xy 54.863354 -185.80072) (xy 54.887164 -185.872695) (xy 54.903189 -185.946793)
			(xy 54.911248 -186.022174) (xy 54.911752 -186.06008) (xy 56.027831 -186.06008) (xy 56.031866 -185.984376)
			(xy 56.043925 -185.909531) (xy 56.063871 -185.83639) (xy 56.091478 -185.765785) (xy 56.126434 -185.698514)
			(xy 56.168342 -185.635339) (xy 56.216728 -185.576977) (xy 56.271044 -185.524089) (xy 56.330673 -185.477274)
			(xy 56.394941 -185.437062) (xy 56.463118 -185.40391) (xy 56.534434 -185.378192) (xy 56.608079 -185.3602)
			(xy 56.683219 -185.350138) (xy 56.759003 -185.348119) (xy 56.834573 -185.354168) (xy 56.909071 -185.368215)
			(xy 56.981654 -185.390101) (xy 57.0515 -185.419578) (xy 57.117817 -185.456313) (xy 57.179853 -185.499888)
			(xy 57.236906 -185.54981) (xy 57.28833 -185.605514) (xy 57.333541 -185.666369) (xy 57.372028 -185.731684)
			(xy 57.403354 -185.80072) (xy 57.427164 -185.872695) (xy 57.443189 -185.946793) (xy 57.451248 -186.022174)
			(xy 57.451752 -186.06008) (xy 58.567831 -186.06008) (xy 58.571866 -185.984376) (xy 58.583925 -185.909531)
			(xy 58.603871 -185.83639) (xy 58.631478 -185.765785) (xy 58.666434 -185.698514) (xy 58.708342 -185.635339)
			(xy 58.756728 -185.576977) (xy 58.811044 -185.524089) (xy 58.870673 -185.477274) (xy 58.934941 -185.437062)
			(xy 59.003118 -185.40391) (xy 59.074434 -185.378192) (xy 59.148079 -185.3602) (xy 59.223219 -185.350138)
			(xy 59.299003 -185.348119) (xy 59.374573 -185.354168) (xy 59.449071 -185.368215) (xy 59.521654 -185.390101)
			(xy 59.5915 -185.419578) (xy 59.657817 -185.456313) (xy 59.719853 -185.499888) (xy 59.776906 -185.54981)
			(xy 59.82833 -185.605514) (xy 59.873541 -185.666369) (xy 59.912028 -185.731684) (xy 59.943354 -185.80072)
			(xy 59.967164 -185.872695) (xy 59.983189 -185.946793) (xy 59.991248 -186.022174) (xy 59.991752 -186.06008)
			(xy 61.107831 -186.06008) (xy 61.111866 -185.984376) (xy 61.123925 -185.909531) (xy 61.143871 -185.83639)
			(xy 61.171478 -185.765785) (xy 61.206434 -185.698514) (xy 61.248342 -185.635339) (xy 61.296728 -185.576977)
			(xy 61.351044 -185.524089) (xy 61.410673 -185.477274) (xy 61.474941 -185.437062) (xy 61.543118 -185.40391)
			(xy 61.614434 -185.378192) (xy 61.688079 -185.3602) (xy 61.763219 -185.350138) (xy 61.839003 -185.348119)
			(xy 61.914573 -185.354168) (xy 61.989071 -185.368215) (xy 62.061654 -185.390101) (xy 62.1315 -185.419578)
			(xy 62.197817 -185.456313) (xy 62.259853 -185.499888) (xy 62.316906 -185.54981) (xy 62.36833 -185.605514)
			(xy 62.413541 -185.666369) (xy 62.452028 -185.731684) (xy 62.483354 -185.80072) (xy 62.507164 -185.872695)
			(xy 62.523189 -185.946793) (xy 62.531248 -186.022174) (xy 62.531752 -186.06008) (xy 62.531248 -186.097986)
			(xy 62.523189 -186.173367) (xy 62.507164 -186.247465) (xy 62.483354 -186.31944) (xy 62.452028 -186.388476)
			(xy 62.413541 -186.453791) (xy 62.36833 -186.514646) (xy 62.316906 -186.57035) (xy 62.265798 -186.61507)
			(xy 84.927951 -186.61507) (xy 84.931986 -186.539366) (xy 84.944045 -186.464521) (xy 84.963991 -186.39138)
			(xy 84.991598 -186.320775) (xy 85.026554 -186.253504) (xy 85.068462 -186.190329) (xy 85.116848 -186.131967)
			(xy 85.171164 -186.079079) (xy 85.230793 -186.032264) (xy 85.295061 -185.992052) (xy 85.363238 -185.9589)
			(xy 85.434554 -185.933182) (xy 85.508199 -185.91519) (xy 85.583339 -185.905128) (xy 85.659123 -185.903109)
			(xy 85.734693 -185.909158) (xy 85.809191 -185.923205) (xy 85.881774 -185.945091) (xy 85.95162 -185.974568)
			(xy 86.017937 -186.011303) (xy 86.079973 -186.054878) (xy 86.137026 -186.1048) (xy 86.18845 -186.160504)
			(xy 86.233661 -186.221359) (xy 86.272148 -186.286674) (xy 86.303474 -186.35571) (xy 86.327284 -186.427685)
			(xy 86.343309 -186.501783) (xy 86.351368 -186.577164) (xy 86.351872 -186.61507) (xy 87.467951 -186.61507)
			(xy 87.471986 -186.539366) (xy 87.484045 -186.464521) (xy 87.503991 -186.39138) (xy 87.531598 -186.320775)
			(xy 87.566554 -186.253504) (xy 87.608462 -186.190329) (xy 87.656848 -186.131967) (xy 87.711164 -186.079079)
			(xy 87.770793 -186.032264) (xy 87.835061 -185.992052) (xy 87.903238 -185.9589) (xy 87.974554 -185.933182)
			(xy 88.048199 -185.91519) (xy 88.123339 -185.905128) (xy 88.199123 -185.903109) (xy 88.274693 -185.909158)
			(xy 88.349191 -185.923205) (xy 88.421774 -185.945091) (xy 88.49162 -185.974568) (xy 88.557937 -186.011303)
			(xy 88.619973 -186.054878) (xy 88.677026 -186.1048) (xy 88.72845 -186.160504) (xy 88.773661 -186.221359)
			(xy 88.812148 -186.286674) (xy 88.843474 -186.35571) (xy 88.867284 -186.427685) (xy 88.883309 -186.501783)
			(xy 88.891368 -186.577164) (xy 88.891872 -186.61507) (xy 90.007951 -186.61507) (xy 90.011986 -186.539366)
			(xy 90.024045 -186.464521) (xy 90.043991 -186.39138) (xy 90.071598 -186.320775) (xy 90.106554 -186.253504)
			(xy 90.148462 -186.190329) (xy 90.196848 -186.131967) (xy 90.251164 -186.079079) (xy 90.310793 -186.032264)
			(xy 90.375061 -185.992052) (xy 90.443238 -185.9589) (xy 90.514554 -185.933182) (xy 90.588199 -185.91519)
			(xy 90.663339 -185.905128) (xy 90.739123 -185.903109) (xy 90.814693 -185.909158) (xy 90.889191 -185.923205)
			(xy 90.961774 -185.945091) (xy 91.03162 -185.974568) (xy 91.097937 -186.011303) (xy 91.159973 -186.054878)
			(xy 91.165918 -186.06008) (xy 93.15476 -186.06008) (xy 93.158776 -185.94381) (xy 93.170803 -185.828095)
			(xy 93.190785 -185.713485) (xy 93.218627 -185.600526) (xy 93.254196 -185.489758) (xy 93.297322 -185.381707)
			(xy 93.347799 -185.276889) (xy 93.405388 -185.175804) (xy 93.469814 -185.078932) (xy 93.540769 -184.986736)
			(xy 93.617916 -184.899655) (xy 93.700887 -184.818104) (xy 93.789287 -184.742472) (xy 93.882694 -184.673118)
			(xy 93.980663 -184.610375) (xy 94.082727 -184.554539) (xy 94.188401 -184.505878) (xy 94.29718 -184.464624)
			(xy 94.408545 -184.430973) (xy 94.521968 -184.405085) (xy 94.636905 -184.387084) (xy 94.752811 -184.377055)
			(xy 94.869133 -184.375047) (xy 94.985316 -184.381069) (xy 95.100807 -184.395092) (xy 95.215055 -184.41705)
			(xy 95.327516 -184.446837) (xy 95.437654 -184.484312) (xy 95.544944 -184.529297) (xy 95.648875 -184.581576)
			(xy 95.748951 -184.640901) (xy 95.844697 -184.706989) (xy 95.935654 -184.779525) (xy 96.02139 -184.858164)
			(xy 96.101497 -184.94253) (xy 96.175593 -185.032222) (xy 96.243323 -185.126812) (xy 96.304367 -185.22585)
			(xy 96.358432 -185.328863) (xy 96.405262 -185.43536) (xy 96.444633 -185.544835) (xy 96.476357 -185.656765)
			(xy 96.500283 -185.770617) (xy 96.516297 -185.885849) (xy 96.524324 -186.001911) (xy 96.524826 -186.06008)
			(xy 96.524324 -186.118249) (xy 96.516297 -186.234311) (xy 96.500283 -186.349543) (xy 96.476357 -186.463395)
			(xy 96.444633 -186.575325) (xy 96.405262 -186.6848) (xy 96.358432 -186.791297) (xy 96.304367 -186.89431)
			(xy 96.243323 -186.993348) (xy 96.175593 -187.087938) (xy 96.101497 -187.17763) (xy 96.02139 -187.261996)
			(xy 95.935654 -187.340635) (xy 95.844697 -187.413171) (xy 95.748951 -187.479259) (xy 95.648875 -187.538584)
			(xy 95.544944 -187.590863) (xy 95.437654 -187.635848) (xy 95.327516 -187.673323) (xy 95.215055 -187.70311)
			(xy 95.100807 -187.725068) (xy 94.985316 -187.739091) (xy 94.869133 -187.745113) (xy 94.752811 -187.743105)
			(xy 94.636905 -187.733076) (xy 94.521968 -187.715075) (xy 94.408545 -187.689187) (xy 94.29718 -187.655536)
			(xy 94.188401 -187.614282) (xy 94.082727 -187.565621) (xy 93.980663 -187.509785) (xy 93.882694 -187.447042)
			(xy 93.789287 -187.377688) (xy 93.700887 -187.302056) (xy 93.617916 -187.220505) (xy 93.540769 -187.133424)
			(xy 93.469814 -187.041228) (xy 93.405388 -186.944356) (xy 93.347799 -186.843271) (xy 93.297322 -186.738453)
			(xy 93.254196 -186.630402) (xy 93.218627 -186.519634) (xy 93.190785 -186.406675) (xy 93.170803 -186.292065)
			(xy 93.158776 -186.17635) (xy 93.15476 -186.06008) (xy 91.165918 -186.06008) (xy 91.217026 -186.1048)
			(xy 91.26845 -186.160504) (xy 91.313661 -186.221359) (xy 91.352148 -186.286674) (xy 91.383474 -186.35571)
			(xy 91.407284 -186.427685) (xy 91.423309 -186.501783) (xy 91.431368 -186.577164) (xy 91.431872 -186.61507)
			(xy 91.431368 -186.652976) (xy 91.423309 -186.728357) (xy 91.407284 -186.802455) (xy 91.383474 -186.87443)
			(xy 91.352148 -186.943466) (xy 91.313661 -187.008781) (xy 91.26845 -187.069636) (xy 91.217026 -187.12534)
			(xy 91.159973 -187.175262) (xy 91.097937 -187.218837) (xy 91.03162 -187.255572) (xy 90.961774 -187.285049)
			(xy 90.889191 -187.306935) (xy 90.814693 -187.320982) (xy 90.739123 -187.327031) (xy 90.663339 -187.325012)
			(xy 90.588199 -187.31495) (xy 90.514554 -187.296958) (xy 90.443238 -187.27124) (xy 90.375061 -187.238088)
			(xy 90.310793 -187.197876) (xy 90.251164 -187.151061) (xy 90.196848 -187.098173) (xy 90.148462 -187.039811)
			(xy 90.106554 -186.976636) (xy 90.071598 -186.909365) (xy 90.043991 -186.83876) (xy 90.024045 -186.765619)
			(xy 90.011986 -186.690774) (xy 90.007951 -186.61507) (xy 88.891872 -186.61507) (xy 88.891368 -186.652976)
			(xy 88.883309 -186.728357) (xy 88.867284 -186.802455) (xy 88.843474 -186.87443) (xy 88.812148 -186.943466)
			(xy 88.773661 -187.008781) (xy 88.72845 -187.069636) (xy 88.677026 -187.12534) (xy 88.619973 -187.175262)
			(xy 88.557937 -187.218837) (xy 88.49162 -187.255572) (xy 88.421774 -187.285049) (xy 88.349191 -187.306935)
			(xy 88.274693 -187.320982) (xy 88.199123 -187.327031) (xy 88.123339 -187.325012) (xy 88.048199 -187.31495)
			(xy 87.974554 -187.296958) (xy 87.903238 -187.27124) (xy 87.835061 -187.238088) (xy 87.770793 -187.197876)
			(xy 87.711164 -187.151061) (xy 87.656848 -187.098173) (xy 87.608462 -187.039811) (xy 87.566554 -186.976636)
			(xy 87.531598 -186.909365) (xy 87.503991 -186.83876) (xy 87.484045 -186.765619) (xy 87.471986 -186.690774)
			(xy 87.467951 -186.61507) (xy 86.351872 -186.61507) (xy 86.351368 -186.652976) (xy 86.343309 -186.728357)
			(xy 86.327284 -186.802455) (xy 86.303474 -186.87443) (xy 86.272148 -186.943466) (xy 86.233661 -187.008781)
			(xy 86.18845 -187.069636) (xy 86.137026 -187.12534) (xy 86.079973 -187.175262) (xy 86.017937 -187.218837)
			(xy 85.95162 -187.255572) (xy 85.881774 -187.285049) (xy 85.809191 -187.306935) (xy 85.734693 -187.320982)
			(xy 85.659123 -187.327031) (xy 85.583339 -187.325012) (xy 85.508199 -187.31495) (xy 85.434554 -187.296958)
			(xy 85.363238 -187.27124) (xy 85.295061 -187.238088) (xy 85.230793 -187.197876) (xy 85.171164 -187.151061)
			(xy 85.116848 -187.098173) (xy 85.068462 -187.039811) (xy 85.026554 -186.976636) (xy 84.991598 -186.909365)
			(xy 84.963991 -186.83876) (xy 84.944045 -186.765619) (xy 84.931986 -186.690774) (xy 84.927951 -186.61507)
			(xy 62.265798 -186.61507) (xy 62.259853 -186.620272) (xy 62.197817 -186.663847) (xy 62.1315 -186.700582)
			(xy 62.061654 -186.730059) (xy 61.989071 -186.751945) (xy 61.914573 -186.765992) (xy 61.839003 -186.772041)
			(xy 61.763219 -186.770022) (xy 61.688079 -186.75996) (xy 61.614434 -186.741968) (xy 61.543118 -186.71625)
			(xy 61.474941 -186.683098) (xy 61.410673 -186.642886) (xy 61.351044 -186.596071) (xy 61.296728 -186.543183)
			(xy 61.248342 -186.484821) (xy 61.206434 -186.421646) (xy 61.171478 -186.354375) (xy 61.143871 -186.28377)
			(xy 61.123925 -186.210629) (xy 61.111866 -186.135784) (xy 61.107831 -186.06008) (xy 59.991752 -186.06008)
			(xy 59.991248 -186.097986) (xy 59.983189 -186.173367) (xy 59.967164 -186.247465) (xy 59.943354 -186.31944)
			(xy 59.912028 -186.388476) (xy 59.873541 -186.453791) (xy 59.82833 -186.514646) (xy 59.776906 -186.57035)
			(xy 59.719853 -186.620272) (xy 59.657817 -186.663847) (xy 59.5915 -186.700582) (xy 59.521654 -186.730059)
			(xy 59.449071 -186.751945) (xy 59.374573 -186.765992) (xy 59.299003 -186.772041) (xy 59.223219 -186.770022)
			(xy 59.148079 -186.75996) (xy 59.074434 -186.741968) (xy 59.003118 -186.71625) (xy 58.934941 -186.683098)
			(xy 58.870673 -186.642886) (xy 58.811044 -186.596071) (xy 58.756728 -186.543183) (xy 58.708342 -186.484821)
			(xy 58.666434 -186.421646) (xy 58.631478 -186.354375) (xy 58.603871 -186.28377) (xy 58.583925 -186.210629)
			(xy 58.571866 -186.135784) (xy 58.567831 -186.06008) (xy 57.451752 -186.06008) (xy 57.451248 -186.097986)
			(xy 57.443189 -186.173367) (xy 57.427164 -186.247465) (xy 57.403354 -186.31944) (xy 57.372028 -186.388476)
			(xy 57.333541 -186.453791) (xy 57.28833 -186.514646) (xy 57.236906 -186.57035) (xy 57.179853 -186.620272)
			(xy 57.117817 -186.663847) (xy 57.0515 -186.700582) (xy 56.981654 -186.730059) (xy 56.909071 -186.751945)
			(xy 56.834573 -186.765992) (xy 56.759003 -186.772041) (xy 56.683219 -186.770022) (xy 56.608079 -186.75996)
			(xy 56.534434 -186.741968) (xy 56.463118 -186.71625) (xy 56.394941 -186.683098) (xy 56.330673 -186.642886)
			(xy 56.271044 -186.596071) (xy 56.216728 -186.543183) (xy 56.168342 -186.484821) (xy 56.126434 -186.421646)
			(xy 56.091478 -186.354375) (xy 56.063871 -186.28377) (xy 56.043925 -186.210629) (xy 56.031866 -186.135784)
			(xy 56.027831 -186.06008) (xy 54.911752 -186.06008) (xy 54.911248 -186.097986) (xy 54.903189 -186.173367)
			(xy 54.887164 -186.247465) (xy 54.863354 -186.31944) (xy 54.832028 -186.388476) (xy 54.793541 -186.453791)
			(xy 54.74833 -186.514646) (xy 54.696906 -186.57035) (xy 54.639853 -186.620272) (xy 54.577817 -186.663847)
			(xy 54.5115 -186.700582) (xy 54.441654 -186.730059) (xy 54.369071 -186.751945) (xy 54.294573 -186.765992)
			(xy 54.219003 -186.772041) (xy 54.143219 -186.770022) (xy 54.068079 -186.75996) (xy 53.994434 -186.741968)
			(xy 53.923118 -186.71625) (xy 53.854941 -186.683098) (xy 53.790673 -186.642886) (xy 53.731044 -186.596071)
			(xy 53.676728 -186.543183) (xy 53.628342 -186.484821) (xy 53.586434 -186.421646) (xy 53.551478 -186.354375)
			(xy 53.523871 -186.28377) (xy 53.503925 -186.210629) (xy 53.491866 -186.135784) (xy 53.487831 -186.06008)
			(xy 52.371752 -186.06008) (xy 52.371248 -186.097986) (xy 52.363189 -186.173367) (xy 52.347164 -186.247465)
			(xy 52.323354 -186.31944) (xy 52.292028 -186.388476) (xy 52.253541 -186.453791) (xy 52.20833 -186.514646)
			(xy 52.156906 -186.57035) (xy 52.099853 -186.620272) (xy 52.037817 -186.663847) (xy 51.9715 -186.700582)
			(xy 51.901654 -186.730059) (xy 51.829071 -186.751945) (xy 51.754573 -186.765992) (xy 51.679003 -186.772041)
			(xy 51.603219 -186.770022) (xy 51.528079 -186.75996) (xy 51.454434 -186.741968) (xy 51.383118 -186.71625)
			(xy 51.314941 -186.683098) (xy 51.250673 -186.642886) (xy 51.191044 -186.596071) (xy 51.136728 -186.543183)
			(xy 51.088342 -186.484821) (xy 51.046434 -186.421646) (xy 51.011478 -186.354375) (xy 50.983871 -186.28377)
			(xy 50.963925 -186.210629) (xy 50.951866 -186.135784) (xy 50.947831 -186.06008) (xy 49.831752 -186.06008)
			(xy 49.831248 -186.097986) (xy 49.823189 -186.173367) (xy 49.807164 -186.247465) (xy 49.783354 -186.31944)
			(xy 49.752028 -186.388476) (xy 49.713541 -186.453791) (xy 49.66833 -186.514646) (xy 49.616906 -186.57035)
			(xy 49.559853 -186.620272) (xy 49.497817 -186.663847) (xy 49.4315 -186.700582) (xy 49.361654 -186.730059)
			(xy 49.289071 -186.751945) (xy 49.214573 -186.765992) (xy 49.139003 -186.772041) (xy 49.063219 -186.770022)
			(xy 48.988079 -186.75996) (xy 48.914434 -186.741968) (xy 48.843118 -186.71625) (xy 48.774941 -186.683098)
			(xy 48.710673 -186.642886) (xy 48.651044 -186.596071) (xy 48.596728 -186.543183) (xy 48.548342 -186.484821)
			(xy 48.506434 -186.421646) (xy 48.471478 -186.354375) (xy 48.443871 -186.28377) (xy 48.423925 -186.210629)
			(xy 48.411866 -186.135784) (xy 48.407831 -186.06008) (xy 47.291752 -186.06008) (xy 47.291248 -186.097986)
			(xy 47.283189 -186.173367) (xy 47.267164 -186.247465) (xy 47.243354 -186.31944) (xy 47.212028 -186.388476)
			(xy 47.173541 -186.453791) (xy 47.12833 -186.514646) (xy 47.076906 -186.57035) (xy 47.019853 -186.620272)
			(xy 46.957817 -186.663847) (xy 46.8915 -186.700582) (xy 46.821654 -186.730059) (xy 46.749071 -186.751945)
			(xy 46.674573 -186.765992) (xy 46.599003 -186.772041) (xy 46.523219 -186.770022) (xy 46.448079 -186.75996)
			(xy 46.374434 -186.741968) (xy 46.303118 -186.71625) (xy 46.234941 -186.683098) (xy 46.170673 -186.642886)
			(xy 46.111044 -186.596071) (xy 46.056728 -186.543183) (xy 46.008342 -186.484821) (xy 45.966434 -186.421646)
			(xy 45.931478 -186.354375) (xy 45.903871 -186.28377) (xy 45.883925 -186.210629) (xy 45.871866 -186.135784)
			(xy 45.867831 -186.06008) (xy 44.751752 -186.06008) (xy 44.751752 -186.771788) (xy 43.328336 -186.771788)
			(xy 43.328336 -185.348372) (xy 43.055406 -185.348372) (xy 43.015228 -185.439744) (xy 42.961276 -185.54254)
			(xy 42.900362 -185.641368) (xy 42.832774 -185.735759) (xy 42.758835 -185.825261) (xy 42.678897 -185.909449)
			(xy 42.593342 -185.987922) (xy 42.502576 -186.060305) (xy 42.407033 -186.126254) (xy 42.307168 -186.185454)
			(xy 42.203456 -186.237623) (xy 42.096393 -186.282512) (xy 41.986487 -186.319908) (xy 41.874263 -186.349633)
			(xy 41.760257 -186.371544) (xy 41.64501 -186.385537) (xy 41.529072 -186.391546) (xy 41.412996 -186.389543)
			(xy 41.297334 -186.379535) (xy 41.182639 -186.361572) (xy 41.069456 -186.335739) (xy 40.958325 -186.302159)
			(xy 40.849776 -186.260991) (xy 40.744326 -186.212433) (xy 40.642477 -186.156716) (xy 40.544714 -186.094104)
			(xy 40.451504 -186.024897) (xy 40.363291 -185.949424) (xy 40.280495 -185.868045) (xy 40.203511 -185.781148)
			(xy 40.132706 -185.689147) (xy 40.068416 -185.59248) (xy 40.010949 -185.491608) (xy 39.960578 -185.387011)
			(xy 39.917543 -185.279188) (xy 39.882049 -185.168654) (xy 39.854266 -185.055934) (xy 39.834326 -184.941566)
			(xy 39.822324 -184.826094) (xy 39.818317 -184.71007) (xy 39.51732 -184.71007) (xy 39.51732 -186.354974)
			(xy 39.517857 -186.371592) (xy 39.526446 -186.4037) (xy 39.543045 -186.432494) (xy 39.554404 -186.444636)
			(xy 42.980864 -189.870842) (xy 42.980864 -191.253618) (xy 83.836254 -191.253618) (xy 83.840325 -191.197996)
			(xy 83.852451 -191.143559) (xy 83.872374 -191.091468) (xy 83.89967 -191.042833) (xy 83.933756 -190.99869)
			(xy 83.973905 -190.959981) (xy 84.019263 -190.92753) (xy 84.068863 -190.902029) (xy 84.121647 -190.884022)
			(xy 84.17649 -190.873892) (xy 84.232224 -190.871855) (xy 84.287661 -190.877955) (xy 84.341618 -190.892061)
			(xy 84.392947 -190.913873) (xy 84.440553 -190.942927) (xy 84.483421 -190.978602) (xy 84.520638 -191.020139)
			(xy 84.551411 -191.066652) (xy 84.575083 -191.117149) (xy 84.591151 -191.170556) (xy 84.599271 -191.225732)
			(xy 84.599279 -191.226186) (xy 85.72703 -191.226186) (xy 85.731101 -191.170564) (xy 85.743227 -191.116127)
			(xy 85.76315 -191.064036) (xy 85.790446 -191.015401) (xy 85.824532 -190.971258) (xy 85.864681 -190.932549)
			(xy 85.910039 -190.900098) (xy 85.959639 -190.874597) (xy 86.012423 -190.85659) (xy 86.067266 -190.84646)
			(xy 86.123 -190.844423) (xy 86.178437 -190.850523) (xy 86.232394 -190.864629) (xy 86.283723 -190.886441)
			(xy 86.331329 -190.915495) (xy 86.374197 -190.95117) (xy 86.381648 -190.959486) (xy 87.021668 -190.959486)
			(xy 87.025739 -190.903864) (xy 87.037865 -190.849427) (xy 87.057788 -190.797336) (xy 87.085084 -190.748701)
			(xy 87.11917 -190.704558) (xy 87.159319 -190.665849) (xy 87.204677 -190.633398) (xy 87.254277 -190.607897)
			(xy 87.307061 -190.58989) (xy 87.361904 -190.57976) (xy 87.417638 -190.577723) (xy 87.473075 -190.583823)
			(xy 87.527032 -190.597929) (xy 87.578361 -190.619741) (xy 87.625967 -190.648795) (xy 87.668835 -190.68447)
			(xy 87.706052 -190.726007) (xy 87.736825 -190.77252) (xy 87.760497 -190.823017) (xy 87.776565 -190.876424)
			(xy 87.784685 -190.9316) (xy 87.785194 -190.959486) (xy 87.784685 -190.987372) (xy 87.776565 -191.042548)
			(xy 87.760497 -191.095955) (xy 87.736825 -191.146452) (xy 87.706052 -191.192965) (xy 87.693582 -191.206882)
			(xy 91.71254 -191.206882) (xy 91.716611 -191.15126) (xy 91.728737 -191.096823) (xy 91.74866 -191.044732)
			(xy 91.775956 -190.996097) (xy 91.810042 -190.951954) (xy 91.850191 -190.913245) (xy 91.895549 -190.880794)
			(xy 91.945149 -190.855293) (xy 91.997933 -190.837286) (xy 92.052776 -190.827156) (xy 92.10851 -190.825119)
			(xy 92.163947 -190.831219) (xy 92.217904 -190.845325) (xy 92.269233 -190.867137) (xy 92.316839 -190.896191)
			(xy 92.359707 -190.931866) (xy 92.396924 -190.973403) (xy 92.427697 -191.019916) (xy 92.451369 -191.070413)
			(xy 92.467437 -191.12382) (xy 92.475557 -191.178996) (xy 92.476066 -191.206882) (xy 92.475557 -191.234768)
			(xy 92.467437 -191.289944) (xy 92.451369 -191.343351) (xy 92.427697 -191.393848) (xy 92.396924 -191.440361)
			(xy 92.359707 -191.481898) (xy 92.316839 -191.517573) (xy 92.269233 -191.546627) (xy 92.217904 -191.568439)
			(xy 92.163947 -191.582545) (xy 92.10851 -191.588645) (xy 92.052776 -191.586608) (xy 91.997933 -191.576478)
			(xy 91.945149 -191.558471) (xy 91.895549 -191.53297) (xy 91.850191 -191.500519) (xy 91.810042 -191.46181)
			(xy 91.775956 -191.417667) (xy 91.74866 -191.369032) (xy 91.728737 -191.316941) (xy 91.716611 -191.262504)
			(xy 91.71254 -191.206882) (xy 87.693582 -191.206882) (xy 87.668835 -191.234502) (xy 87.625967 -191.270177)
			(xy 87.578361 -191.299231) (xy 87.527032 -191.321043) (xy 87.473075 -191.335149) (xy 87.417638 -191.341249)
			(xy 87.361904 -191.339212) (xy 87.307061 -191.329082) (xy 87.254277 -191.311075) (xy 87.204677 -191.285574)
			(xy 87.159319 -191.253123) (xy 87.11917 -191.214414) (xy 87.085084 -191.170271) (xy 87.057788 -191.121636)
			(xy 87.037865 -191.069545) (xy 87.025739 -191.015108) (xy 87.021668 -190.959486) (xy 86.381648 -190.959486)
			(xy 86.411414 -190.992707) (xy 86.442187 -191.03922) (xy 86.465859 -191.089717) (xy 86.481927 -191.143124)
			(xy 86.490047 -191.1983) (xy 86.490556 -191.226186) (xy 86.490047 -191.254072) (xy 86.481927 -191.309248)
			(xy 86.465859 -191.362655) (xy 86.442187 -191.413152) (xy 86.411414 -191.459665) (xy 86.374197 -191.501202)
			(xy 86.331329 -191.536877) (xy 86.283723 -191.565931) (xy 86.232394 -191.587743) (xy 86.178437 -191.601849)
			(xy 86.123 -191.607949) (xy 86.067266 -191.605912) (xy 86.012423 -191.595782) (xy 85.959639 -191.577775)
			(xy 85.910039 -191.552274) (xy 85.864681 -191.519823) (xy 85.824532 -191.481114) (xy 85.790446 -191.436971)
			(xy 85.76315 -191.388336) (xy 85.743227 -191.336245) (xy 85.731101 -191.281808) (xy 85.72703 -191.226186)
			(xy 84.599279 -191.226186) (xy 84.59978 -191.253618) (xy 84.599271 -191.281504) (xy 84.591151 -191.33668)
			(xy 84.575083 -191.390087) (xy 84.551411 -191.440584) (xy 84.520638 -191.487097) (xy 84.483421 -191.528634)
			(xy 84.440553 -191.564309) (xy 84.392947 -191.593363) (xy 84.341618 -191.615175) (xy 84.287661 -191.629281)
			(xy 84.232224 -191.635381) (xy 84.17649 -191.633344) (xy 84.121647 -191.623214) (xy 84.068863 -191.605207)
			(xy 84.019263 -191.579706) (xy 83.973905 -191.547255) (xy 83.933756 -191.508546) (xy 83.89967 -191.464403)
			(xy 83.872374 -191.415768) (xy 83.852451 -191.363677) (xy 83.840325 -191.30924) (xy 83.836254 -191.253618)
			(xy 42.980864 -191.253618) (xy 42.980864 -191.705992) (xy 95.288098 -191.705992) (xy 95.292169 -191.65037)
			(xy 95.304295 -191.595933) (xy 95.324218 -191.543842) (xy 95.351514 -191.495207) (xy 95.3856 -191.451064)
			(xy 95.425749 -191.412355) (xy 95.471107 -191.379904) (xy 95.520707 -191.354403) (xy 95.573491 -191.336396)
			(xy 95.628334 -191.326266) (xy 95.684068 -191.324229) (xy 95.739505 -191.330329) (xy 95.793462 -191.344435)
			(xy 95.844791 -191.366247) (xy 95.892397 -191.395301) (xy 95.935265 -191.430976) (xy 95.972482 -191.472513)
			(xy 96.003255 -191.519026) (xy 96.026927 -191.569523) (xy 96.042995 -191.62293) (xy 96.051115 -191.678106)
			(xy 96.051624 -191.705992) (xy 96.051115 -191.733878) (xy 96.042995 -191.789054) (xy 96.026927 -191.842461)
			(xy 96.003255 -191.892958) (xy 95.972482 -191.939471) (xy 95.935265 -191.981008) (xy 95.892397 -192.016683)
			(xy 95.844791 -192.045737) (xy 95.793462 -192.067549) (xy 95.739505 -192.081655) (xy 95.684068 -192.087755)
			(xy 95.628334 -192.085718) (xy 95.573491 -192.075588) (xy 95.520707 -192.057581) (xy 95.471107 -192.03208)
			(xy 95.425749 -191.999629) (xy 95.3856 -191.96092) (xy 95.351514 -191.916777) (xy 95.324218 -191.868142)
			(xy 95.304295 -191.816051) (xy 95.292169 -191.761614) (xy 95.288098 -191.705992) (xy 42.980864 -191.705992)
			(xy 42.980864 -192.53708) (xy 82.809078 -192.53708) (xy 82.813149 -192.481458) (xy 82.825275 -192.427021)
			(xy 82.845198 -192.37493) (xy 82.872494 -192.326295) (xy 82.90658 -192.282152) (xy 82.946729 -192.243443)
			(xy 82.992087 -192.210992) (xy 83.041687 -192.185491) (xy 83.094471 -192.167484) (xy 83.149314 -192.157354)
			(xy 83.205048 -192.155317) (xy 83.260485 -192.161417) (xy 83.314442 -192.175523) (xy 83.365771 -192.197335)
			(xy 83.413377 -192.226389) (xy 83.456245 -192.262064) (xy 83.493462 -192.303601) (xy 83.524235 -192.350114)
			(xy 83.547907 -192.400611) (xy 83.563975 -192.454018) (xy 83.572095 -192.509194) (xy 83.572604 -192.53708)
			(xy 83.572095 -192.564966) (xy 83.563975 -192.620142) (xy 83.547907 -192.673549) (xy 83.544249 -192.681352)
			(xy 84.456522 -192.681352) (xy 84.460593 -192.62573) (xy 84.472719 -192.571293) (xy 84.492642 -192.519202)
			(xy 84.519938 -192.470567) (xy 84.554024 -192.426424) (xy 84.594173 -192.387715) (xy 84.639531 -192.355264)
			(xy 84.689131 -192.329763) (xy 84.741915 -192.311756) (xy 84.796758 -192.301626) (xy 84.852492 -192.299589)
			(xy 84.907929 -192.305689) (xy 84.961886 -192.319795) (xy 85.013215 -192.341607) (xy 85.060821 -192.370661)
			(xy 85.103689 -192.406336) (xy 85.140906 -192.447873) (xy 85.171679 -192.494386) (xy 85.195351 -192.544883)
			(xy 85.211419 -192.59829) (xy 85.219539 -192.653466) (xy 85.220048 -192.681352) (xy 85.219539 -192.709238)
			(xy 85.211419 -192.764414) (xy 85.195351 -192.817821) (xy 85.171679 -192.868318) (xy 85.140906 -192.914831)
			(xy 85.103689 -192.956368) (xy 85.060821 -192.992043) (xy 85.013215 -193.021097) (xy 84.961886 -193.042909)
			(xy 84.907929 -193.057015) (xy 84.852492 -193.063115) (xy 84.796758 -193.061078) (xy 84.741915 -193.050948)
			(xy 84.689131 -193.032941) (xy 84.639531 -193.00744) (xy 84.594173 -192.974989) (xy 84.554024 -192.93628)
			(xy 84.519938 -192.892137) (xy 84.492642 -192.843502) (xy 84.472719 -192.791411) (xy 84.460593 -192.736974)
			(xy 84.456522 -192.681352) (xy 83.544249 -192.681352) (xy 83.524235 -192.724046) (xy 83.493462 -192.770559)
			(xy 83.456245 -192.812096) (xy 83.413377 -192.847771) (xy 83.365771 -192.876825) (xy 83.314442 -192.898637)
			(xy 83.260485 -192.912743) (xy 83.205048 -192.918843) (xy 83.149314 -192.916806) (xy 83.094471 -192.906676)
			(xy 83.041687 -192.888669) (xy 82.992087 -192.863168) (xy 82.946729 -192.830717) (xy 82.90658 -192.792008)
			(xy 82.872494 -192.747865) (xy 82.845198 -192.69923) (xy 82.825275 -192.647139) (xy 82.813149 -192.592702)
			(xy 82.809078 -192.53708) (xy 42.980864 -192.53708) (xy 42.980864 -193.733674) (xy 43.73753 -194.49034)
			(xy 43.73753 -195.825872) (xy 68.862448 -195.825872) (xy 68.862448 -194.827144) (xy 68.863141 -194.791078)
			(xy 68.873462 -194.719687) (xy 68.883022 -194.684904) (xy 68.887848 -194.667378) (xy 68.887848 -194.293236)
			(xy 69.854064 -194.293236) (xy 69.854064 -194.667378) (xy 69.85889 -194.684904) (xy 69.868427 -194.719692)
			(xy 69.878757 -194.79108) (xy 69.879464 -194.827144) (xy 69.879464 -194.981322) (xy 70.150228 -194.981322)
			(xy 70.150228 -193.982594) (xy 70.150771 -193.94986) (xy 70.159201 -193.884936) (xy 70.175894 -193.821631)
			(xy 70.200575 -193.760992) (xy 70.232836 -193.704024) (xy 70.252082 -193.67754) (xy 70.277228 -193.643758)
			(xy 70.277228 -193.62674) (xy 70.292722 -193.62674) (xy 70.328536 -193.59626) (xy 70.353713 -193.575407)
			(xy 70.408445 -193.539656) (xy 70.46731 -193.511217) (xy 70.529335 -193.490562) (xy 70.593497 -193.478031)
			(xy 70.658736 -193.473831) (xy 70.723975 -193.478031) (xy 70.788137 -193.490562) (xy 70.850162 -193.511217)
			(xy 70.909027 -193.539656) (xy 70.963759 -193.575407) (xy 70.988936 -193.59626) (xy 71.02475 -193.62674)
			(xy 71.040244 -193.62674) (xy 71.040244 -193.643758) (xy 71.06539 -193.67754) (xy 71.08156 -193.699724)
			(xy 71.109562 -193.746944) (xy 71.12127 -193.771774) (xy 71.128419 -193.78629) (xy 71.148807 -193.811404)
			(xy 71.174851 -193.830589) (xy 71.20488 -193.842616) (xy 71.236967 -193.846713) (xy 71.269054 -193.842616)
			(xy 71.299083 -193.830589) (xy 71.325127 -193.811404) (xy 71.345515 -193.78629) (xy 71.352664 -193.771774)
			(xy 71.364376 -193.746946) (xy 71.392376 -193.699725) (xy 71.408544 -193.67754) (xy 71.433944 -193.643758)
			(xy 71.433944 -193.62674) (xy 71.449184 -193.62674) (xy 71.484998 -193.59626) (xy 71.510175 -193.575407)
			(xy 71.564907 -193.539656) (xy 71.623772 -193.511217) (xy 71.685797 -193.490562) (xy 71.749959 -193.478031)
			(xy 71.815198 -193.473831) (xy 71.880437 -193.478031) (xy 71.944599 -193.490562) (xy 72.006624 -193.511217)
			(xy 72.065489 -193.539656) (xy 72.120221 -193.575407) (xy 72.145398 -193.59626) (xy 72.181212 -193.62674)
			(xy 72.196452 -193.62674) (xy 72.196452 -193.643758) (xy 72.221852 -193.67754) (xy 72.241066 -193.704039)
			(xy 72.252372 -193.724022) (xy 83.269326 -193.724022) (xy 83.273397 -193.6684) (xy 83.285523 -193.613963)
			(xy 83.305446 -193.561872) (xy 83.332742 -193.513237) (xy 83.366828 -193.469094) (xy 83.406977 -193.430385)
			(xy 83.452335 -193.397934) (xy 83.501935 -193.372433) (xy 83.554719 -193.354426) (xy 83.609562 -193.344296)
			(xy 83.665296 -193.342259) (xy 83.720733 -193.348359) (xy 83.77469 -193.362465) (xy 83.826019 -193.384277)
			(xy 83.873625 -193.413331) (xy 83.916493 -193.449006) (xy 83.95371 -193.490543) (xy 83.984483 -193.537056)
			(xy 84.008155 -193.587553) (xy 84.024223 -193.64096) (xy 84.032343 -193.696136) (xy 84.032852 -193.724022)
			(xy 84.032343 -193.751908) (xy 84.024223 -193.807084) (xy 84.008155 -193.860491) (xy 83.984483 -193.910988)
			(xy 83.95371 -193.957501) (xy 83.916493 -193.999038) (xy 83.873625 -194.034713) (xy 83.826019 -194.063767)
			(xy 83.77469 -194.085579) (xy 83.720733 -194.099685) (xy 83.665296 -194.105785) (xy 83.609562 -194.103748)
			(xy 83.554719 -194.093618) (xy 83.501935 -194.075611) (xy 83.452335 -194.05011) (xy 83.406977 -194.017659)
			(xy 83.366828 -193.97895) (xy 83.332742 -193.934807) (xy 83.305446 -193.886172) (xy 83.285523 -193.834081)
			(xy 83.273397 -193.779644) (xy 83.269326 -193.724022) (xy 72.252372 -193.724022) (xy 72.273297 -193.761008)
			(xy 72.297941 -193.821647) (xy 72.314587 -193.884949) (xy 72.322961 -193.949866) (xy 72.323452 -193.982594)
			(xy 72.323452 -194.981322) (xy 72.322938 -195.013863) (xy 72.314639 -195.078415) (xy 72.298168 -195.141379)
			(xy 72.273794 -195.201725) (xy 72.241915 -195.258466) (xy 72.203054 -195.310673) (xy 72.157846 -195.357492)
			(xy 72.107031 -195.398157) (xy 72.05144 -195.432002) (xy 71.991984 -195.458473) (xy 71.929635 -195.477138)
			(xy 71.865414 -195.487691) (xy 71.80037 -195.489958) (xy 71.73557 -195.483904) (xy 71.672072 -195.469627)
			(xy 71.610917 -195.447361) (xy 71.553104 -195.41747) (xy 71.49958 -195.380443) (xy 71.451221 -195.336887)
			(xy 71.429626 -195.312538) (xy 71.415024 -195.296226) (xy 71.381241 -195.268386) (xy 71.343185 -195.24675)
			(xy 71.301983 -195.231961) (xy 71.258855 -195.224455) (xy 71.215079 -195.224455) (xy 71.171951 -195.231961)
			(xy 71.130749 -195.24675) (xy 71.092693 -195.268386) (xy 71.05891 -195.296226) (xy 71.044308 -195.312538)
			(xy 71.022725 -195.33691) (xy 70.974358 -195.380488) (xy 70.920823 -195.417535) (xy 70.862997 -195.447443)
			(xy 70.801826 -195.469725) (xy 70.738311 -195.484014) (xy 70.673491 -195.490078) (xy 70.608427 -195.487816)
			(xy 70.544185 -195.477267) (xy 70.481815 -195.458602) (xy 70.422338 -195.432127) (xy 70.366728 -195.398276)
			(xy 70.315895 -195.357602) (xy 70.27067 -195.310771) (xy 70.231795 -195.25855) (xy 70.199904 -195.201792)
			(xy 70.175521 -195.141428) (xy 70.159043 -195.078445) (xy 70.150742 -195.013874) (xy 70.150228 -194.981322)
			(xy 69.879464 -194.981322) (xy 69.879464 -195.825872) (xy 69.878962 -195.857833) (xy 69.870951 -195.921251)
			(xy 69.855054 -195.983165) (xy 69.831522 -196.042598) (xy 69.800728 -196.098613) (xy 69.763155 -196.150328)
			(xy 69.719398 -196.196925) (xy 69.670145 -196.23767) (xy 69.616174 -196.271921) (xy 69.558335 -196.299138)
			(xy 69.497542 -196.318891) (xy 69.434752 -196.330869) (xy 69.370956 -196.334883) (xy 69.30716 -196.330869)
			(xy 69.24437 -196.318891) (xy 69.183577 -196.299138) (xy 69.125738 -196.271921) (xy 69.071767 -196.23767)
			(xy 69.022514 -196.196925) (xy 68.978757 -196.150328) (xy 68.941184 -196.098613) (xy 68.91039 -196.042598)
			(xy 68.886858 -195.983165) (xy 68.870961 -195.921251) (xy 68.86295 -195.857833) (xy 68.862448 -195.825872)
			(xy 43.73753 -195.825872) (xy 43.73753 -196.064378) (xy 43.031749 -196.770159) (xy 47.903374 -196.770159)
			(xy 47.903374 -196.689049) (xy 47.911324 -196.60833) (xy 47.927147 -196.528779) (xy 47.950692 -196.451163)
			(xy 47.981731 -196.376227) (xy 48.019966 -196.304695) (xy 48.065028 -196.237255) (xy 48.116483 -196.174556)
			(xy 48.173836 -196.117203) (xy 48.236535 -196.065748) (xy 48.303975 -196.020686) (xy 48.375507 -195.982451)
			(xy 48.450443 -195.951412) (xy 48.528059 -195.927867) (xy 48.60761 -195.912044) (xy 48.688329 -195.904094)
			(xy 48.769439 -195.904094) (xy 48.850158 -195.912044) (xy 48.929709 -195.927867) (xy 49.007325 -195.951412)
			(xy 49.082261 -195.982451) (xy 49.153793 -196.020686) (xy 49.221233 -196.065748) (xy 49.283932 -196.117203)
			(xy 49.341285 -196.174556) (xy 49.39274 -196.237255) (xy 49.437802 -196.304695) (xy 49.476037 -196.376227)
			(xy 49.507076 -196.451163) (xy 49.530621 -196.528779) (xy 49.546444 -196.60833) (xy 49.554394 -196.689049)
			(xy 49.554892 -196.729604) (xy 49.554394 -196.770159) (xy 49.546444 -196.850878) (xy 49.530621 -196.930429)
			(xy 49.507076 -197.008045) (xy 49.476037 -197.082981) (xy 49.437802 -197.154513) (xy 49.39274 -197.221953)
			(xy 49.341285 -197.284652) (xy 49.283932 -197.342005) (xy 49.221233 -197.39346) (xy 49.153793 -197.438522)
			(xy 49.082261 -197.476757) (xy 49.007325 -197.507796) (xy 48.929709 -197.531341) (xy 48.850158 -197.547164)
			(xy 48.769439 -197.555114) (xy 48.688329 -197.555114) (xy 48.60761 -197.547164) (xy 48.528059 -197.531341)
			(xy 48.450443 -197.507796) (xy 48.375507 -197.476757) (xy 48.303975 -197.438522) (xy 48.236535 -197.39346)
			(xy 48.173836 -197.342005) (xy 48.116483 -197.284652) (xy 48.065028 -197.221953) (xy 48.019966 -197.154513)
			(xy 47.981731 -197.082981) (xy 47.950692 -197.008045) (xy 47.927147 -196.930429) (xy 47.911324 -196.850878)
			(xy 47.903374 -196.770159) (xy 43.031749 -196.770159) (xy 41.991788 -197.81012) (xy 86.39887 -197.81012)
			(xy 86.402874 -197.610022) (xy 86.414881 -197.410244) (xy 86.434872 -197.211107) (xy 86.462814 -197.012929)
			(xy 86.498662 -196.816027) (xy 86.54236 -196.620718) (xy 86.593837 -196.427313) (xy 86.653011 -196.236123)
			(xy 86.719787 -196.047453) (xy 86.794059 -195.861606) (xy 86.875706 -195.678879) (xy 86.964599 -195.499566)
			(xy 87.060595 -195.323952) (xy 87.16354 -195.15232) (xy 87.27327 -194.984944) (xy 87.389608 -194.822093)
			(xy 87.512369 -194.664026) (xy 87.641356 -194.510998) (xy 87.776363 -194.363253) (xy 87.917172 -194.221027)
			(xy 88.063559 -194.08455) (xy 88.215289 -193.954038) (xy 88.37212 -193.829702) (xy 88.533799 -193.71174)
			(xy 88.700069 -193.600341) (xy 88.870662 -193.495684) (xy 89.045306 -193.397936) (xy 89.223722 -193.307253)
			(xy 89.405622 -193.223782) (xy 89.590717 -193.147655) (xy 89.778709 -193.078995) (xy 89.969298 -193.017911)
			(xy 90.162178 -192.964501) (xy 90.35704 -192.918852) (xy 90.553573 -192.881035) (xy 90.751462 -192.851111)
			(xy 90.950389 -192.829129) (xy 91.150037 -192.815124) (xy 91.350085 -192.809118) (xy 91.550213 -192.81112)
			(xy 91.750101 -192.821128) (xy 91.949428 -192.839125) (xy 92.147876 -192.865083) (xy 92.345126 -192.89896)
			(xy 92.540863 -192.940702) (xy 92.734773 -192.990241) (xy 92.926546 -193.047499) (xy 93.115875 -193.112384)
			(xy 93.302455 -193.184792) (xy 93.48599 -193.264608) (xy 93.666184 -193.351702) (xy 93.842749 -193.445936)
			(xy 93.905061 -193.482468) (xy 96.185226 -193.482468) (xy 96.189297 -193.426846) (xy 96.201423 -193.372409)
			(xy 96.221346 -193.320318) (xy 96.248642 -193.271683) (xy 96.282728 -193.22754) (xy 96.322877 -193.188831)
			(xy 96.368235 -193.15638) (xy 96.417835 -193.130879) (xy 96.470619 -193.112872) (xy 96.525462 -193.102742)
			(xy 96.581196 -193.100705) (xy 96.636633 -193.106805) (xy 96.69059 -193.120911) (xy 96.741919 -193.142723)
			(xy 96.789525 -193.171777) (xy 96.832393 -193.207452) (xy 96.86961 -193.248989) (xy 96.900383 -193.295502)
			(xy 96.924055 -193.345999) (xy 96.940123 -193.399406) (xy 96.948243 -193.454582) (xy 96.948752 -193.482468)
			(xy 96.948243 -193.510354) (xy 96.940123 -193.56553) (xy 96.924055 -193.618937) (xy 96.900383 -193.669434)
			(xy 96.86961 -193.715947) (xy 96.832393 -193.757484) (xy 96.789525 -193.793159) (xy 96.741919 -193.822213)
			(xy 96.69059 -193.844025) (xy 96.636633 -193.858131) (xy 96.581196 -193.864231) (xy 96.525462 -193.862194)
			(xy 96.470619 -193.852064) (xy 96.417835 -193.834057) (xy 96.368235 -193.808556) (xy 96.322877 -193.776105)
			(xy 96.282728 -193.737396) (xy 96.248642 -193.693253) (xy 96.221346 -193.644618) (xy 96.201423 -193.592527)
			(xy 96.189297 -193.53809) (xy 96.185226 -193.482468) (xy 93.905061 -193.482468) (xy 94.015402 -193.547159)
			(xy 94.183867 -193.655209) (xy 94.347875 -193.769912) (xy 94.507162 -193.891086) (xy 94.661473 -194.018535)
			(xy 94.810561 -194.152056) (xy 94.954188 -194.291436) (xy 95.092124 -194.43645) (xy 95.180445 -194.537076)
			(xy 99.002594 -194.537076) (xy 99.006665 -194.481454) (xy 99.018791 -194.427017) (xy 99.038714 -194.374926)
			(xy 99.06601 -194.326291) (xy 99.100096 -194.282148) (xy 99.140245 -194.243439) (xy 99.185603 -194.210988)
			(xy 99.235203 -194.185487) (xy 99.287987 -194.16748) (xy 99.34283 -194.15735) (xy 99.398564 -194.155313)
			(xy 99.454001 -194.161413) (xy 99.507958 -194.175519) (xy 99.559287 -194.197331) (xy 99.606893 -194.226385)
			(xy 99.649761 -194.26206) (xy 99.686978 -194.303597) (xy 99.717751 -194.35011) (xy 99.741423 -194.400607)
			(xy 99.757491 -194.454014) (xy 99.765611 -194.50919) (xy 99.76612 -194.537076) (xy 99.765611 -194.564962)
			(xy 99.757491 -194.620138) (xy 99.741423 -194.673545) (xy 99.717751 -194.724042) (xy 99.686978 -194.770555)
			(xy 99.649761 -194.812092) (xy 99.606893 -194.847767) (xy 99.559287 -194.876821) (xy 99.507958 -194.898633)
			(xy 99.454001 -194.912739) (xy 99.398564 -194.918839) (xy 99.34283 -194.916802) (xy 99.287987 -194.906672)
			(xy 99.235203 -194.888665) (xy 99.185603 -194.863164) (xy 99.140245 -194.830713) (xy 99.100096 -194.792004)
			(xy 99.06601 -194.747861) (xy 99.038714 -194.699226) (xy 99.018791 -194.647135) (xy 99.006665 -194.592698)
			(xy 99.002594 -194.537076) (xy 95.180445 -194.537076) (xy 95.224147 -194.586867) (xy 95.350046 -194.742445)
			(xy 95.46962 -194.902937) (xy 95.534931 -194.99834) (xy 96.87255 -194.99834) (xy 96.876621 -194.942718)
			(xy 96.888747 -194.888281) (xy 96.90867 -194.83619) (xy 96.935966 -194.787555) (xy 96.970052 -194.743412)
			(xy 97.010201 -194.704703) (xy 97.055559 -194.672252) (xy 97.105159 -194.646751) (xy 97.157943 -194.628744)
			(xy 97.212786 -194.618614) (xy 97.26852 -194.616577) (xy 97.323957 -194.622677) (xy 97.377914 -194.636783)
			(xy 97.429243 -194.658595) (xy 97.476849 -194.687649) (xy 97.519717 -194.723324) (xy 97.556934 -194.764861)
			(xy 97.587707 -194.811374) (xy 97.611379 -194.861871) (xy 97.627447 -194.915278) (xy 97.635567 -194.970454)
			(xy 97.636076 -194.99834) (xy 97.635567 -195.026226) (xy 97.627447 -195.081402) (xy 97.611379 -195.134809)
			(xy 97.587707 -195.185306) (xy 97.556934 -195.231819) (xy 97.519717 -195.273356) (xy 97.476849 -195.309031)
			(xy 97.429243 -195.338085) (xy 97.377914 -195.359897) (xy 97.323957 -195.374003) (xy 97.26852 -195.380103)
			(xy 97.212786 -195.378066) (xy 97.157943 -195.367936) (xy 97.105159 -195.349929) (xy 97.055559 -195.324428)
			(xy 97.010201 -195.291977) (xy 96.970052 -195.253268) (xy 96.935966 -195.209125) (xy 96.90867 -195.16049)
			(xy 96.888747 -195.108399) (xy 96.876621 -195.053962) (xy 96.87255 -194.99834) (xy 95.534931 -194.99834)
			(xy 95.582676 -195.068083) (xy 95.689035 -195.237621) (xy 95.788526 -195.411279) (xy 95.880989 -195.588778)
			(xy 95.966276 -195.769834) (xy 96.044251 -195.954158) (xy 96.114788 -196.141454) (xy 96.177776 -196.331422)
			(xy 96.233113 -196.523758) (xy 96.271822 -196.681852) (xy 97.862642 -196.681852) (xy 97.866713 -196.62623)
			(xy 97.878839 -196.571793) (xy 97.898762 -196.519702) (xy 97.926058 -196.471067) (xy 97.960144 -196.426924)
			(xy 98.000293 -196.388215) (xy 98.045651 -196.355764) (xy 98.095251 -196.330263) (xy 98.148035 -196.312256)
			(xy 98.202878 -196.302126) (xy 98.258612 -196.300089) (xy 98.314049 -196.306189) (xy 98.368006 -196.320295)
			(xy 98.419335 -196.342107) (xy 98.466941 -196.371161) (xy 98.509809 -196.406836) (xy 98.547026 -196.448373)
			(xy 98.577799 -196.494886) (xy 98.601471 -196.545383) (xy 98.617539 -196.59879) (xy 98.625659 -196.653966)
			(xy 98.626168 -196.681852) (xy 98.625659 -196.709738) (xy 98.617539 -196.764914) (xy 98.601471 -196.818321)
			(xy 98.577799 -196.868818) (xy 98.547026 -196.915331) (xy 98.509809 -196.956868) (xy 98.466941 -196.992543)
			(xy 98.419335 -197.021597) (xy 98.368006 -197.043409) (xy 98.314049 -197.057515) (xy 98.258612 -197.063615)
			(xy 98.202878 -197.061578) (xy 98.148035 -197.051448) (xy 98.095251 -197.033441) (xy 98.045651 -197.00794)
			(xy 98.000293 -196.975489) (xy 97.960144 -196.93678) (xy 97.926058 -196.892637) (xy 97.898762 -196.844002)
			(xy 97.878839 -196.791911) (xy 97.866713 -196.737474) (xy 97.862642 -196.681852) (xy 96.271822 -196.681852)
			(xy 96.28071 -196.718154) (xy 96.320491 -196.914299) (xy 96.352393 -197.111878) (xy 96.376364 -197.310575)
			(xy 96.392366 -197.510073) (xy 96.400373 -197.710051) (xy 96.400874 -197.81012) (xy 96.400373 -197.910189)
			(xy 96.392366 -198.110167) (xy 96.376364 -198.309665) (xy 96.352393 -198.508362) (xy 96.320491 -198.705941)
			(xy 96.28071 -198.902086) (xy 96.233113 -199.096482) (xy 96.177776 -199.288818) (xy 96.114788 -199.478786)
			(xy 96.044251 -199.666082) (xy 95.966276 -199.850406) (xy 95.880989 -200.031462) (xy 95.788526 -200.208961)
			(xy 95.689035 -200.382619) (xy 95.582676 -200.552157) (xy 95.46962 -200.717303) (xy 95.350046 -200.877795)
			(xy 95.224147 -201.033373) (xy 95.092124 -201.18379) (xy 94.954188 -201.328804) (xy 94.810561 -201.468184)
			(xy 94.661473 -201.601705) (xy 94.507162 -201.729154) (xy 94.347875 -201.850328) (xy 94.183867 -201.965031)
			(xy 94.015402 -202.073081) (xy 93.842749 -202.174304) (xy 93.666184 -202.268538) (xy 93.48599 -202.355632)
			(xy 93.302455 -202.435448) (xy 93.115875 -202.507856) (xy 92.926546 -202.572741) (xy 92.734773 -202.629999)
			(xy 92.540863 -202.679538) (xy 92.345126 -202.72128) (xy 92.147876 -202.755157) (xy 91.949428 -202.781115)
			(xy 91.750101 -202.799112) (xy 91.550213 -202.80912) (xy 91.350085 -202.811122) (xy 91.150037 -202.805116)
			(xy 90.950389 -202.791111) (xy 90.751462 -202.769129) (xy 90.553573 -202.739205) (xy 90.35704 -202.701388)
			(xy 90.162178 -202.655739) (xy 89.969298 -202.602329) (xy 89.778709 -202.541245) (xy 89.590717 -202.472585)
			(xy 89.405622 -202.396458) (xy 89.223722 -202.312987) (xy 89.045306 -202.222304) (xy 88.870662 -202.124556)
			(xy 88.700069 -202.019899) (xy 88.533799 -201.9085) (xy 88.37212 -201.790538) (xy 88.215289 -201.666202)
			(xy 88.063559 -201.53569) (xy 87.917172 -201.399213) (xy 87.776363 -201.256987) (xy 87.641356 -201.109242)
			(xy 87.512369 -200.956214) (xy 87.389608 -200.798147) (xy 87.27327 -200.635296) (xy 87.16354 -200.46792)
			(xy 87.060595 -200.296288) (xy 86.964599 -200.120674) (xy 86.875706 -199.941361) (xy 86.794059 -199.758634)
			(xy 86.719787 -199.572787) (xy 86.653011 -199.384117) (xy 86.593837 -199.192927) (xy 86.54236 -198.999522)
			(xy 86.498662 -198.804213) (xy 86.462814 -198.607311) (xy 86.434872 -198.409133) (xy 86.414881 -198.209996)
			(xy 86.402874 -198.010218) (xy 86.39887 -197.81012) (xy 41.991788 -197.81012) (xy 40.864536 -198.937372)
			(xy 40.215058 -198.937372) (xy 40.081708 -199.070722) (xy 40.081708 -199.347074) (xy 40.082171 -199.363804)
			(xy 40.090792 -199.396132) (xy 40.107528 -199.425103) (xy 40.119046 -199.437244) (xy 40.168068 -199.486012)
			(xy 40.399462 -199.486012) (xy 40.410784 -199.486119) (xy 40.433399 -199.487261) (xy 40.444674 -199.488298)
			(xy 40.450516 -199.488806) (xy 40.917876 -199.488806) (xy 41.358312 -199.929242) (xy 41.358312 -200.631552)
			(xy 40.96258 -201.027284) (xy 38.507416 -201.027284) (xy 38.080696 -200.600564) (xy 36.373054 -200.600564)
			(xy 36.349894 -200.601071) (xy 36.304341 -200.609457) (xy 36.261062 -200.625961) (xy 36.221491 -200.650037)
			(xy 36.18694 -200.680886) (xy 36.158553 -200.717487) (xy 36.137271 -200.758627) (xy 36.123797 -200.802943)
			(xy 36.11858 -200.848967) (xy 36.121792 -200.895175) (xy 36.133325 -200.940035) (xy 36.152799 -200.982061)
			(xy 36.179569 -201.019861) (xy 36.195762 -201.036428) (xy 36.226715 -201.067271) (xy 36.283389 -201.133789)
			(xy 36.333647 -201.205278) (xy 36.377055 -201.281122) (xy 36.413239 -201.360666) (xy 36.441887 -201.443225)
			(xy 36.46275 -201.528085) (xy 36.47565 -201.614515) (xy 36.480476 -201.701769) (xy 36.477184 -201.789095)
			(xy 36.465805 -201.875738) (xy 36.446436 -201.960952) (xy 36.419243 -202.044001) (xy 36.384463 -202.124169)
			(xy 36.342394 -202.200764) (xy 36.293401 -202.273126) (xy 36.237904 -202.340629) (xy 36.176384 -202.402692)
			(xy 36.109371 -202.45878) (xy 36.037442 -202.508408) (xy 35.96122 -202.551148) (xy 35.881361 -202.586631)
			(xy 35.798554 -202.614552) (xy 35.713513 -202.634669) (xy 35.626973 -202.64681) (xy 35.53968 -202.650868)
			(xy 35.452387 -202.64681) (xy 35.365847 -202.634669) (xy 35.280806 -202.614552) (xy 35.197999 -202.586631)
			(xy 35.11814 -202.551148) (xy 35.041918 -202.508408) (xy 34.969989 -202.45878) (xy 34.902976 -202.402692)
			(xy 34.841456 -202.340629) (xy 34.785959 -202.273126) (xy 34.736966 -202.200764) (xy 34.694897 -202.124169)
			(xy 34.660117 -202.044001) (xy 34.632924 -201.960952) (xy 34.613555 -201.875738) (xy 34.602176 -201.789095)
			(xy 34.598884 -201.701769) (xy 34.60371 -201.614515) (xy 34.61661 -201.528085) (xy 34.637473 -201.443225)
			(xy 34.666121 -201.360666) (xy 34.702305 -201.281122) (xy 34.745713 -201.205278) (xy 34.795971 -201.133789)
			(xy 34.852645 -201.067271) (xy 34.883598 -201.036428) (xy 34.899819 -201.019896) (xy 34.926568 -200.982093)
			(xy 34.946025 -200.940068) (xy 34.957543 -200.895213) (xy 34.960743 -200.849013) (xy 34.955519 -200.802999)
			(xy 34.942042 -200.758693) (xy 34.92076 -200.717562) (xy 34.892378 -200.680969) (xy 34.857834 -200.650125)
			(xy 34.818273 -200.626051) (xy 34.775004 -200.609544) (xy 34.729461 -200.601151) (xy 34.706306 -200.600564)
			(xy 33.25876 -200.600564) (xy 31.738316 -202.121008) (xy 30.982666 -202.876912) (xy 29.667708 -202.876912)
			(xy 28.753816 -203.790804) (xy 28.753816 -204.293486) (xy 29.519874 -204.293486) (xy 29.519874 -204.206586)
			(xy 29.527892 -204.120057) (xy 29.54386 -204.034637) (xy 29.567641 -203.951055) (xy 29.599033 -203.870023)
			(xy 29.637767 -203.792234) (xy 29.683514 -203.71835) (xy 29.735883 -203.649003) (xy 29.794427 -203.584783)
			(xy 29.858647 -203.526239) (xy 29.927994 -203.47387) (xy 30.001878 -203.428123) (xy 30.079667 -203.389389)
			(xy 30.160699 -203.357997) (xy 30.244281 -203.334216) (xy 30.329701 -203.318248) (xy 30.41623 -203.31023)
			(xy 30.50313 -203.31023) (xy 30.589659 -203.318248) (xy 30.675079 -203.334216) (xy 30.758661 -203.357997)
			(xy 30.839693 -203.389389) (xy 30.917482 -203.428123) (xy 30.991366 -203.47387) (xy 31.060713 -203.526239)
			(xy 31.124933 -203.584783) (xy 31.183477 -203.649003) (xy 31.235846 -203.71835) (xy 31.281593 -203.792234)
			(xy 31.320327 -203.870023) (xy 31.351719 -203.951055) (xy 31.3755 -204.034637) (xy 31.391468 -204.120057)
			(xy 31.399486 -204.206586) (xy 31.399988 -204.250036) (xy 31.399486 -204.293486) (xy 34.599874 -204.293486)
			(xy 34.599874 -204.206586) (xy 34.607892 -204.120057) (xy 34.62386 -204.034637) (xy 34.647641 -203.951055)
			(xy 34.679033 -203.870023) (xy 34.717767 -203.792234) (xy 34.763514 -203.71835) (xy 34.815883 -203.649003)
			(xy 34.874427 -203.584783) (xy 34.938647 -203.526239) (xy 35.007994 -203.47387) (xy 35.081878 -203.428123)
			(xy 35.159667 -203.389389) (xy 35.240699 -203.357997) (xy 35.324281 -203.334216) (xy 35.409701 -203.318248)
			(xy 35.49623 -203.31023) (xy 35.58313 -203.31023) (xy 35.669659 -203.318248) (xy 35.755079 -203.334216)
			(xy 35.838661 -203.357997) (xy 35.919693 -203.389389) (xy 35.997482 -203.428123) (xy 36.071366 -203.47387)
			(xy 36.140713 -203.526239) (xy 36.204933 -203.584783) (xy 36.263477 -203.649003) (xy 36.315846 -203.71835)
			(xy 36.361593 -203.792234) (xy 36.400327 -203.870023) (xy 36.431719 -203.951055) (xy 36.4555 -204.034637)
			(xy 36.471468 -204.120057) (xy 36.479486 -204.206586) (xy 36.479988 -204.250036) (xy 36.479486 -204.293486)
			(xy 36.471468 -204.380015) (xy 36.4555 -204.465435) (xy 36.431719 -204.549017) (xy 36.400327 -204.630049)
			(xy 36.361593 -204.707838) (xy 36.315846 -204.781722) (xy 36.263477 -204.851069) (xy 36.204933 -204.915289)
			(xy 36.140713 -204.973833) (xy 36.071366 -205.026202) (xy 35.997482 -205.071949) (xy 35.919693 -205.110683)
			(xy 35.838661 -205.142075) (xy 35.755079 -205.165856) (xy 35.669659 -205.181824) (xy 35.58313 -205.189842)
			(xy 35.49623 -205.189842) (xy 35.409701 -205.181824) (xy 35.324281 -205.165856) (xy 35.240699 -205.142075)
			(xy 35.159667 -205.110683) (xy 35.081878 -205.071949) (xy 35.007994 -205.026202) (xy 34.938647 -204.973833)
			(xy 34.874427 -204.915289) (xy 34.815883 -204.851069) (xy 34.763514 -204.781722) (xy 34.717767 -204.707838)
			(xy 34.679033 -204.630049) (xy 34.647641 -204.549017) (xy 34.62386 -204.465435) (xy 34.607892 -204.380015)
			(xy 34.599874 -204.293486) (xy 31.399486 -204.293486) (xy 31.391468 -204.380015) (xy 31.3755 -204.465435)
			(xy 31.351719 -204.549017) (xy 31.320327 -204.630049) (xy 31.281593 -204.707838) (xy 31.235846 -204.781722)
			(xy 31.183477 -204.851069) (xy 31.124933 -204.915289) (xy 31.060713 -204.973833) (xy 30.991366 -205.026202)
			(xy 30.917482 -205.071949) (xy 30.839693 -205.110683) (xy 30.758661 -205.142075) (xy 30.675079 -205.165856)
			(xy 30.589659 -205.181824) (xy 30.50313 -205.189842) (xy 30.41623 -205.189842) (xy 30.329701 -205.181824)
			(xy 30.244281 -205.165856) (xy 30.160699 -205.142075) (xy 30.079667 -205.110683) (xy 30.001878 -205.071949)
			(xy 29.927994 -205.026202) (xy 29.858647 -204.973833) (xy 29.794427 -204.915289) (xy 29.735883 -204.851069)
			(xy 29.683514 -204.781722) (xy 29.637767 -204.707838) (xy 29.599033 -204.630049) (xy 29.567641 -204.549017)
			(xy 29.54386 -204.465435) (xy 29.527892 -204.380015) (xy 29.519874 -204.293486) (xy 28.753816 -204.293486)
			(xy 28.753816 -206.833486) (xy 29.519874 -206.833486) (xy 29.519874 -206.746586) (xy 29.527892 -206.660057)
			(xy 29.54386 -206.574637) (xy 29.567641 -206.491055) (xy 29.599033 -206.410023) (xy 29.637767 -206.332234)
			(xy 29.683514 -206.25835) (xy 29.735883 -206.189003) (xy 29.794427 -206.124783) (xy 29.858647 -206.066239)
			(xy 29.927994 -206.01387) (xy 30.001878 -205.968123) (xy 30.079667 -205.929389) (xy 30.160699 -205.897997)
			(xy 30.244281 -205.874216) (xy 30.329701 -205.858248) (xy 30.41623 -205.85023) (xy 30.50313 -205.85023)
			(xy 30.589659 -205.858248) (xy 30.675079 -205.874216) (xy 30.758661 -205.897997) (xy 30.839693 -205.929389)
			(xy 30.917482 -205.968123) (xy 30.991366 -206.01387) (xy 31.060713 -206.066239) (xy 31.124933 -206.124783)
			(xy 31.183477 -206.189003) (xy 31.235846 -206.25835) (xy 31.281593 -206.332234) (xy 31.320327 -206.410023)
			(xy 31.351719 -206.491055) (xy 31.3755 -206.574637) (xy 31.391468 -206.660057) (xy 31.399486 -206.746586)
			(xy 31.399988 -206.790036) (xy 31.399486 -206.833486) (xy 34.599874 -206.833486) (xy 34.599874 -206.746586)
			(xy 34.607892 -206.660057) (xy 34.62386 -206.574637) (xy 34.647641 -206.491055) (xy 34.679033 -206.410023)
			(xy 34.717767 -206.332234) (xy 34.763514 -206.25835) (xy 34.815883 -206.189003) (xy 34.874427 -206.124783)
			(xy 34.938647 -206.066239) (xy 35.007994 -206.01387) (xy 35.081878 -205.968123) (xy 35.159667 -205.929389)
			(xy 35.240699 -205.897997) (xy 35.324281 -205.874216) (xy 35.409701 -205.858248) (xy 35.49623 -205.85023)
			(xy 35.58313 -205.85023) (xy 35.669659 -205.858248) (xy 35.755079 -205.874216) (xy 35.838661 -205.897997)
			(xy 35.919693 -205.929389) (xy 35.997482 -205.968123) (xy 36.071366 -206.01387) (xy 36.140713 -206.066239)
			(xy 36.204933 -206.124783) (xy 36.263477 -206.189003) (xy 36.315846 -206.25835) (xy 36.35924 -206.328433)
			(xy 64.461877 -206.328433) (xy 64.461877 -206.265167) (xy 64.470135 -206.202443) (xy 64.486509 -206.141333)
			(xy 64.51072 -206.082884) (xy 64.542352 -206.028094) (xy 64.580866 -205.977902) (xy 64.625601 -205.933167)
			(xy 64.675793 -205.894653) (xy 64.730582 -205.863021) (xy 64.789032 -205.83881) (xy 64.850141 -205.822435)
			(xy 64.912865 -205.814177) (xy 64.944498 -205.81366) (xy 66.26733 -205.81366) (xy 66.275712 -205.812644)
			(xy 66.304515 -205.80915) (xy 66.362531 -205.808276) (xy 66.420235 -205.814353) (xy 66.476796 -205.827295)
			(xy 66.531401 -205.846914) (xy 66.583265 -205.872929) (xy 66.60769 -205.88859) (xy 66.639694 -205.909672)
			(xy 66.842386 -205.909672) (xy 66.87439 -205.88859) (xy 66.898176 -205.873307) (xy 66.94861 -205.847753)
			(xy 67.001684 -205.828268) (xy 67.056673 -205.81512) (xy 67.112821 -205.808488) (xy 67.14109 -205.808072)
			(xy 68.792344 -205.808072) (xy 68.93941 -205.955138) (xy 68.961488 -205.977869) (xy 69.000036 -206.028167)
			(xy 69.031678 -206.083073) (xy 69.05587 -206.141644) (xy 69.072196 -206.202875) (xy 69.080377 -206.265715)
			(xy 69.080272 -206.329085) (xy 69.071883 -206.391898) (xy 69.055353 -206.453075) (xy 69.030967 -206.511565)
			(xy 68.999144 -206.566366) (xy 68.960429 -206.616535) (xy 68.915487 -206.661212) (xy 68.86509 -206.69963)
			(xy 68.810103 -206.73113) (xy 68.751469 -206.755169) (xy 68.690196 -206.771337) (xy 68.627335 -206.779355)
			(xy 68.563965 -206.779086) (xy 68.532502 -206.775304) (xy 68.52412 -206.774288) (xy 67.14109 -206.774288)
			(xy 67.112823 -206.77385) (xy 67.05668 -206.7672) (xy 67.001695 -206.75405) (xy 66.948618 -206.734579)
			(xy 66.898174 -206.709053) (xy 66.87439 -206.69377) (xy 66.842386 -206.672688) (xy 66.695066 -206.672688)
			(xy 66.678385 -206.673217) (xy 66.646165 -206.681868) (xy 66.617285 -206.69857) (xy 66.60515 -206.710026)
			(xy 66.535554 -206.779876) (xy 64.944498 -206.779876) (xy 64.912865 -206.779423) (xy 64.850141 -206.771165)
			(xy 64.789032 -206.75479) (xy 64.730582 -206.730579) (xy 64.675793 -206.698947) (xy 64.625601 -206.660433)
			(xy 64.580866 -206.615698) (xy 64.542352 -206.565506) (xy 64.51072 -206.510716) (xy 64.486509 -206.452267)
			(xy 64.470135 -206.391157) (xy 64.461877 -206.328433) (xy 36.35924 -206.328433) (xy 36.361593 -206.332234)
			(xy 36.400327 -206.410023) (xy 36.431719 -206.491055) (xy 36.4555 -206.574637) (xy 36.471468 -206.660057)
			(xy 36.479486 -206.746586) (xy 36.479988 -206.790036) (xy 36.479486 -206.833486) (xy 36.471468 -206.920015)
			(xy 36.4555 -207.005435) (xy 36.431719 -207.089017) (xy 36.400327 -207.170049) (xy 36.361593 -207.247838)
			(xy 36.315846 -207.321722) (xy 36.263477 -207.391069) (xy 36.204933 -207.455289) (xy 36.140713 -207.513833)
			(xy 36.071366 -207.566202) (xy 35.997482 -207.611949) (xy 35.919693 -207.650683) (xy 35.838661 -207.682075)
			(xy 35.755079 -207.705856) (xy 35.669659 -207.721824) (xy 35.58313 -207.729842) (xy 35.49623 -207.729842)
			(xy 35.409701 -207.721824) (xy 35.324281 -207.705856) (xy 35.240699 -207.682075) (xy 35.159667 -207.650683)
			(xy 35.081878 -207.611949) (xy 35.007994 -207.566202) (xy 34.938647 -207.513833) (xy 34.874427 -207.455289)
			(xy 34.815883 -207.391069) (xy 34.763514 -207.321722) (xy 34.717767 -207.247838) (xy 34.679033 -207.170049)
			(xy 34.647641 -207.089017) (xy 34.62386 -207.005435) (xy 34.607892 -206.920015) (xy 34.599874 -206.833486)
			(xy 31.399486 -206.833486) (xy 31.391468 -206.920015) (xy 31.3755 -207.005435) (xy 31.351719 -207.089017)
			(xy 31.320327 -207.170049) (xy 31.281593 -207.247838) (xy 31.235846 -207.321722) (xy 31.183477 -207.391069)
			(xy 31.124933 -207.455289) (xy 31.060713 -207.513833) (xy 30.991366 -207.566202) (xy 30.917482 -207.611949)
			(xy 30.839693 -207.650683) (xy 30.758661 -207.682075) (xy 30.675079 -207.705856) (xy 30.589659 -207.721824)
			(xy 30.50313 -207.729842) (xy 30.41623 -207.729842) (xy 30.329701 -207.721824) (xy 30.244281 -207.705856)
			(xy 30.160699 -207.682075) (xy 30.079667 -207.650683) (xy 30.001878 -207.611949) (xy 29.927994 -207.566202)
			(xy 29.858647 -207.513833) (xy 29.794427 -207.455289) (xy 29.735883 -207.391069) (xy 29.683514 -207.321722)
			(xy 29.637767 -207.247838) (xy 29.599033 -207.170049) (xy 29.567641 -207.089017) (xy 29.54386 -207.005435)
			(xy 29.527892 -206.920015) (xy 29.519874 -206.833486) (xy 28.753816 -206.833486) (xy 28.753816 -209.373486)
			(xy 29.519874 -209.373486) (xy 29.519874 -209.286586) (xy 29.527892 -209.200057) (xy 29.54386 -209.114637)
			(xy 29.567641 -209.031055) (xy 29.599033 -208.950023) (xy 29.637767 -208.872234) (xy 29.683514 -208.79835)
			(xy 29.735883 -208.729003) (xy 29.794427 -208.664783) (xy 29.858647 -208.606239) (xy 29.927994 -208.55387)
			(xy 30.001878 -208.508123) (xy 30.079667 -208.469389) (xy 30.160699 -208.437997) (xy 30.244281 -208.414216)
			(xy 30.329701 -208.398248) (xy 30.41623 -208.39023) (xy 30.50313 -208.39023) (xy 30.589659 -208.398248)
			(xy 30.675079 -208.414216) (xy 30.758661 -208.437997) (xy 30.839693 -208.469389) (xy 30.917482 -208.508123)
			(xy 30.991366 -208.55387) (xy 31.060713 -208.606239) (xy 31.124933 -208.664783) (xy 31.183477 -208.729003)
			(xy 31.235846 -208.79835) (xy 31.281593 -208.872234) (xy 31.320327 -208.950023) (xy 31.351719 -209.031055)
			(xy 31.3755 -209.114637) (xy 31.391468 -209.200057) (xy 31.399486 -209.286586) (xy 31.399988 -209.330036)
			(xy 31.399486 -209.373486) (xy 34.599874 -209.373486) (xy 34.599874 -209.286586) (xy 34.607892 -209.200057)
			(xy 34.62386 -209.114637) (xy 34.647641 -209.031055) (xy 34.679033 -208.950023) (xy 34.717767 -208.872234)
			(xy 34.763514 -208.79835) (xy 34.815883 -208.729003) (xy 34.874427 -208.664783) (xy 34.938647 -208.606239)
			(xy 35.007994 -208.55387) (xy 35.081878 -208.508123) (xy 35.159667 -208.469389) (xy 35.240699 -208.437997)
			(xy 35.324281 -208.414216) (xy 35.409701 -208.398248) (xy 35.49623 -208.39023) (xy 35.58313 -208.39023)
			(xy 35.669659 -208.398248) (xy 35.755079 -208.414216) (xy 35.838661 -208.437997) (xy 35.919693 -208.469389)
			(xy 35.997482 -208.508123) (xy 36.071366 -208.55387) (xy 36.140713 -208.606239) (xy 36.204933 -208.664783)
			(xy 36.263477 -208.729003) (xy 36.315846 -208.79835) (xy 36.361593 -208.872234) (xy 36.400327 -208.950023)
			(xy 36.422714 -209.007811) (xy 38.847768 -209.007811) (xy 38.847768 -208.936489) (xy 38.855754 -208.865615)
			(xy 38.871624 -208.79608) (xy 38.895181 -208.72876) (xy 38.926126 -208.664501) (xy 38.964072 -208.60411)
			(xy 39.008541 -208.548348) (xy 39.058974 -208.497915) (xy 39.114736 -208.453446) (xy 39.175127 -208.4155)
			(xy 39.239386 -208.384555) (xy 39.306706 -208.360998) (xy 39.376241 -208.345128) (xy 39.447115 -208.337142)
			(xy 39.518437 -208.337142) (xy 39.589311 -208.345128) (xy 39.658846 -208.360998) (xy 39.726166 -208.384555)
			(xy 39.790425 -208.4155) (xy 39.850816 -208.453446) (xy 39.906578 -208.497915) (xy 39.957011 -208.548348)
			(xy 40.00148 -208.60411) (xy 40.039426 -208.664501) (xy 40.070371 -208.72876) (xy 40.093928 -208.79608)
			(xy 40.109798 -208.865615) (xy 40.117784 -208.936489) (xy 40.118284 -208.97215) (xy 40.117784 -209.007811)
			(xy 40.73448 -209.007811) (xy 40.73448 -208.936489) (xy 40.742466 -208.865615) (xy 40.758336 -208.79608)
			(xy 40.781893 -208.72876) (xy 40.812838 -208.664501) (xy 40.850784 -208.60411) (xy 40.895253 -208.548348)
			(xy 40.945686 -208.497915) (xy 41.001448 -208.453446) (xy 41.061839 -208.4155) (xy 41.126098 -208.384555)
			(xy 41.193418 -208.360998) (xy 41.262953 -208.345128) (xy 41.333827 -208.337142) (xy 41.405149 -208.337142)
			(xy 41.476023 -208.345128) (xy 41.545558 -208.360998) (xy 41.612878 -208.384555) (xy 41.677137 -208.4155)
			(xy 41.737528 -208.453446) (xy 41.79329 -208.497915) (xy 41.843723 -208.548348) (xy 41.888192 -208.60411)
			(xy 41.926138 -208.664501) (xy 41.957083 -208.72876) (xy 41.98064 -208.79608) (xy 41.99651 -208.865615)
			(xy 42.004496 -208.936489) (xy 42.004996 -208.97215) (xy 42.004496 -209.007811) (xy 42.975522 -209.007811)
			(xy 42.975522 -208.936489) (xy 42.983508 -208.865615) (xy 42.999378 -208.79608) (xy 43.022935 -208.72876)
			(xy 43.05388 -208.664501) (xy 43.091826 -208.60411) (xy 43.136295 -208.548348) (xy 43.186728 -208.497915)
			(xy 43.24249 -208.453446) (xy 43.302881 -208.4155) (xy 43.36714 -208.384555) (xy 43.43446 -208.360998)
			(xy 43.503995 -208.345128) (xy 43.574869 -208.337142) (xy 43.646191 -208.337142) (xy 43.717065 -208.345128)
			(xy 43.7866 -208.360998) (xy 43.85392 -208.384555) (xy 43.918179 -208.4155) (xy 43.97857 -208.453446)
			(xy 44.034332 -208.497915) (xy 44.084765 -208.548348) (xy 44.129234 -208.60411) (xy 44.16718 -208.664501)
			(xy 44.198125 -208.72876) (xy 44.221682 -208.79608) (xy 44.237552 -208.865615) (xy 44.245538 -208.936489)
			(xy 44.246038 -208.97215) (xy 44.245538 -209.007811) (xy 44.879506 -209.007811) (xy 44.879506 -208.936489)
			(xy 44.887492 -208.865615) (xy 44.903362 -208.79608) (xy 44.926919 -208.72876) (xy 44.957864 -208.664501)
			(xy 44.99581 -208.60411) (xy 45.040279 -208.548348) (xy 45.090712 -208.497915) (xy 45.146474 -208.453446)
			(xy 45.206865 -208.4155) (xy 45.271124 -208.384555) (xy 45.338444 -208.360998) (xy 45.407979 -208.345128)
			(xy 45.478853 -208.337142) (xy 45.550175 -208.337142) (xy 45.621049 -208.345128) (xy 45.690584 -208.360998)
			(xy 45.757904 -208.384555) (xy 45.822163 -208.4155) (xy 45.882554 -208.453446) (xy 45.938316 -208.497915)
			(xy 45.988749 -208.548348) (xy 46.033218 -208.60411) (xy 46.071164 -208.664501) (xy 46.102109 -208.72876)
			(xy 46.125666 -208.79608) (xy 46.141536 -208.865615) (xy 46.149522 -208.936489) (xy 46.150022 -208.97215)
			(xy 46.149522 -209.007811) (xy 46.141536 -209.078685) (xy 46.125666 -209.14822) (xy 46.102109 -209.21554)
			(xy 46.093879 -209.23263) (xy 64.500013 -209.23263) (xy 64.500013 -209.16937) (xy 64.50827 -209.10665)
			(xy 64.524643 -209.045545) (xy 64.548852 -208.9871) (xy 64.580482 -208.932314) (xy 64.618993 -208.882126)
			(xy 64.663725 -208.837394) (xy 64.713913 -208.798883) (xy 64.768698 -208.767253) (xy 64.827143 -208.743044)
			(xy 64.888248 -208.726671) (xy 64.950968 -208.718413) (xy 64.982598 -208.717896) (xy 66.22669 -208.717896)
			(xy 66.235072 -208.71688) (xy 66.263896 -208.713352) (xy 66.321961 -208.712427) (xy 66.379716 -208.71848)
			(xy 66.436328 -208.731423) (xy 66.490976 -208.751069) (xy 66.54287 -208.777134) (xy 66.567304 -208.792826)
			(xy 66.599054 -208.813908) (xy 66.656204 -208.813908) (xy 66.656204 -208.869026) (xy 66.676084 -208.891334)
			(xy 66.710728 -208.940021) (xy 66.739101 -208.992611) (xy 66.760769 -209.048299) (xy 66.7754 -209.106235)
			(xy 66.782771 -209.165534) (xy 66.782769 -209.225289) (xy 66.775395 -209.284588) (xy 66.760761 -209.342523)
			(xy 66.739091 -209.398211) (xy 66.710716 -209.450799) (xy 66.676069 -209.499485) (xy 66.656204 -209.521806)
			(xy 66.656204 -209.576924) (xy 66.602102 -209.576924) (xy 66.494914 -209.684112) (xy 64.982598 -209.684112)
			(xy 64.950968 -209.683587) (xy 64.888248 -209.675329) (xy 64.827143 -209.658956) (xy 64.768698 -209.634747)
			(xy 64.713913 -209.603117) (xy 64.663725 -209.564606) (xy 64.618993 -209.519874) (xy 64.580482 -209.469686)
			(xy 64.548852 -209.4149) (xy 64.524643 -209.356455) (xy 64.50827 -209.29535) (xy 64.500013 -209.23263)
			(xy 46.093879 -209.23263) (xy 46.071164 -209.279799) (xy 46.033218 -209.34019) (xy 45.988749 -209.395952)
			(xy 45.938316 -209.446385) (xy 45.882554 -209.490854) (xy 45.822163 -209.5288) (xy 45.757904 -209.559745)
			(xy 45.690584 -209.583302) (xy 45.621049 -209.599172) (xy 45.550175 -209.607158) (xy 45.478853 -209.607158)
			(xy 45.407979 -209.599172) (xy 45.338444 -209.583302) (xy 45.271124 -209.559745) (xy 45.206865 -209.5288)
			(xy 45.146474 -209.490854) (xy 45.090712 -209.446385) (xy 45.040279 -209.395952) (xy 44.99581 -209.34019)
			(xy 44.957864 -209.279799) (xy 44.926919 -209.21554) (xy 44.903362 -209.14822) (xy 44.887492 -209.078685)
			(xy 44.879506 -209.007811) (xy 44.245538 -209.007811) (xy 44.237552 -209.078685) (xy 44.221682 -209.14822)
			(xy 44.198125 -209.21554) (xy 44.16718 -209.279799) (xy 44.129234 -209.34019) (xy 44.084765 -209.395952)
			(xy 44.034332 -209.446385) (xy 43.97857 -209.490854) (xy 43.918179 -209.5288) (xy 43.85392 -209.559745)
			(xy 43.7866 -209.583302) (xy 43.717065 -209.599172) (xy 43.646191 -209.607158) (xy 43.574869 -209.607158)
			(xy 43.503995 -209.599172) (xy 43.43446 -209.583302) (xy 43.36714 -209.559745) (xy 43.302881 -209.5288)
			(xy 43.24249 -209.490854) (xy 43.186728 -209.446385) (xy 43.136295 -209.395952) (xy 43.091826 -209.34019)
			(xy 43.05388 -209.279799) (xy 43.022935 -209.21554) (xy 42.999378 -209.14822) (xy 42.983508 -209.078685)
			(xy 42.975522 -209.007811) (xy 42.004496 -209.007811) (xy 41.99651 -209.078685) (xy 41.98064 -209.14822)
			(xy 41.957083 -209.21554) (xy 41.926138 -209.279799) (xy 41.888192 -209.34019) (xy 41.843723 -209.395952)
			(xy 41.79329 -209.446385) (xy 41.737528 -209.490854) (xy 41.677137 -209.5288) (xy 41.612878 -209.559745)
			(xy 41.545558 -209.583302) (xy 41.476023 -209.599172) (xy 41.405149 -209.607158) (xy 41.333827 -209.607158)
			(xy 41.262953 -209.599172) (xy 41.193418 -209.583302) (xy 41.126098 -209.559745) (xy 41.061839 -209.5288)
			(xy 41.001448 -209.490854) (xy 40.945686 -209.446385) (xy 40.895253 -209.395952) (xy 40.850784 -209.34019)
			(xy 40.812838 -209.279799) (xy 40.781893 -209.21554) (xy 40.758336 -209.14822) (xy 40.742466 -209.078685)
			(xy 40.73448 -209.007811) (xy 40.117784 -209.007811) (xy 40.109798 -209.078685) (xy 40.093928 -209.14822)
			(xy 40.070371 -209.21554) (xy 40.039426 -209.279799) (xy 40.00148 -209.34019) (xy 39.957011 -209.395952)
			(xy 39.906578 -209.446385) (xy 39.850816 -209.490854) (xy 39.790425 -209.5288) (xy 39.726166 -209.559745)
			(xy 39.658846 -209.583302) (xy 39.589311 -209.599172) (xy 39.518437 -209.607158) (xy 39.447115 -209.607158)
			(xy 39.376241 -209.599172) (xy 39.306706 -209.583302) (xy 39.239386 -209.559745) (xy 39.175127 -209.5288)
			(xy 39.114736 -209.490854) (xy 39.058974 -209.446385) (xy 39.008541 -209.395952) (xy 38.964072 -209.34019)
			(xy 38.926126 -209.279799) (xy 38.895181 -209.21554) (xy 38.871624 -209.14822) (xy 38.855754 -209.078685)
			(xy 38.847768 -209.007811) (xy 36.422714 -209.007811) (xy 36.431719 -209.031055) (xy 36.4555 -209.114637)
			(xy 36.471468 -209.200057) (xy 36.479486 -209.286586) (xy 36.479988 -209.330036) (xy 36.479486 -209.373486)
			(xy 36.471468 -209.460015) (xy 36.4555 -209.545435) (xy 36.431719 -209.629017) (xy 36.400327 -209.710049)
			(xy 36.361593 -209.787838) (xy 36.315846 -209.861722) (xy 36.263477 -209.931069) (xy 36.204933 -209.995289)
			(xy 36.140713 -210.053833) (xy 36.079698 -210.09991) (xy 69.997584 -210.09991) (xy 70.001572 -209.84729)
			(xy 70.013533 -209.594922) (xy 70.033455 -209.343058) (xy 70.061319 -209.091948) (xy 70.097095 -208.841842)
			(xy 70.140749 -208.592991) (xy 70.192238 -208.345642) (xy 70.251509 -208.100041) (xy 70.318504 -207.856434)
			(xy 70.393155 -207.615064) (xy 70.47539 -207.37617) (xy 70.565124 -207.139992) (xy 70.66227 -206.906764)
			(xy 70.76673 -206.676718) (xy 70.878401 -206.450086) (xy 70.99717 -206.227091) (xy 71.122919 -206.007957)
			(xy 71.255524 -205.792902) (xy 71.394851 -205.58214) (xy 71.540763 -205.375882) (xy 71.693113 -205.174333)
			(xy 71.851749 -204.977693) (xy 72.016514 -204.78616) (xy 72.187244 -204.599923) (xy 72.363768 -204.419169)
			(xy 72.54591 -204.244078) (xy 72.733488 -204.074824) (xy 72.926316 -203.911575) (xy 73.124201 -203.754496)
			(xy 73.326947 -203.603741) (xy 73.534351 -203.459463) (xy 73.746206 -203.321803) (xy 73.962301 -203.1909)
			(xy 74.182421 -203.066884) (xy 74.406346 -202.949879) (xy 74.633853 -202.840001) (xy 74.864715 -202.73736)
			(xy 75.098703 -202.642058) (xy 75.335582 -202.554191) (xy 75.575118 -202.473844) (xy 75.81707 -202.4011)
			(xy 76.061198 -202.33603) (xy 76.307259 -202.2787) (xy 76.555007 -202.229166) (xy 76.804195 -202.187477)
			(xy 77.054575 -202.153676) (xy 77.305897 -202.127795) (xy 77.557911 -202.109862) (xy 77.810365 -202.099893)
			(xy 78.063009 -202.097899) (xy 78.315589 -202.103881) (xy 78.567855 -202.117834) (xy 78.819554 -202.139744)
			(xy 79.070437 -202.169588) (xy 79.320252 -202.207338) (xy 79.568751 -202.252955) (xy 79.815686 -202.306394)
			(xy 80.060811 -202.367602) (xy 80.303881 -202.436517) (xy 80.544655 -202.513072) (xy 80.782892 -202.597189)
			(xy 81.018355 -202.688786) (xy 81.250809 -202.78777) (xy 81.480023 -202.894042) (xy 81.705767 -203.007498)
			(xy 81.927817 -203.128023) (xy 82.145951 -203.255499) (xy 82.359953 -203.389797) (xy 82.569609 -203.530783)
			(xy 82.774709 -203.678318) (xy 82.975049 -203.832254) (xy 83.17043 -203.992438) (xy 83.360657 -204.15871)
			(xy 83.54554 -204.330905) (xy 83.724896 -204.508849) (xy 83.898544 -204.692368) (xy 84.066312 -204.881276)
			(xy 84.228033 -205.075387) (xy 84.383546 -205.274506) (xy 84.532695 -205.478435) (xy 84.675332 -205.686971)
			(xy 84.811315 -205.899906) (xy 84.940508 -206.117028) (xy 85.062783 -206.33812) (xy 85.178017 -206.562961)
			(xy 85.286096 -206.791329) (xy 85.386911 -207.022994) (xy 85.480363 -207.257727) (xy 85.566358 -207.495292)
			(xy 85.644811 -207.735454) (xy 85.715643 -207.977973) (xy 85.778784 -208.222608) (xy 85.834171 -208.469113)
			(xy 85.881748 -208.717244) (xy 85.921468 -208.966754) (xy 85.953292 -209.217393) (xy 85.977188 -209.468911)
			(xy 85.993132 -209.721059) (xy 86.001107 -209.973584) (xy 86.001606 -210.09991) (xy 86.001107 -210.226236)
			(xy 85.993132 -210.478761) (xy 85.977188 -210.730909) (xy 85.953292 -210.982427) (xy 85.921468 -211.233066)
			(xy 85.881748 -211.482576) (xy 85.834171 -211.730707) (xy 85.778784 -211.977212) (xy 85.715643 -212.221847)
			(xy 85.644811 -212.464366) (xy 85.566358 -212.704528) (xy 85.480363 -212.942093) (xy 85.386911 -213.176826)
			(xy 85.286096 -213.408491) (xy 85.178017 -213.636859) (xy 85.062783 -213.8617) (xy 84.940508 -214.082792)
			(xy 84.811315 -214.299914) (xy 84.675332 -214.512849) (xy 84.532695 -214.721385) (xy 84.383546 -214.925314)
			(xy 84.228033 -215.124433) (xy 84.066312 -215.318544) (xy 83.898544 -215.507452) (xy 83.724896 -215.690971)
			(xy 83.54554 -215.868915) (xy 83.360657 -216.04111) (xy 83.17043 -216.207382) (xy 82.975049 -216.367566)
			(xy 82.774709 -216.521502) (xy 82.569609 -216.669037) (xy 82.359953 -216.810023) (xy 82.145951 -216.944321)
			(xy 81.927817 -217.071797) (xy 81.705767 -217.192322) (xy 81.480023 -217.305778) (xy 81.250809 -217.41205)
			(xy 81.018355 -217.511034) (xy 80.782892 -217.602631) (xy 80.544655 -217.686748) (xy 80.303881 -217.763303)
			(xy 80.060811 -217.832218) (xy 79.815686 -217.893426) (xy 79.568751 -217.946865) (xy 79.320252 -217.992482)
			(xy 79.070437 -218.030232) (xy 78.819554 -218.060076) (xy 78.567855 -218.081986) (xy 78.315589 -218.095939)
			(xy 78.063009 -218.101921) (xy 77.810365 -218.099927) (xy 77.557911 -218.089958) (xy 77.305897 -218.072025)
			(xy 77.054575 -218.046144) (xy 76.804195 -218.012343) (xy 76.555007 -217.970654) (xy 76.307259 -217.92112)
			(xy 76.061198 -217.86379) (xy 75.81707 -217.79872) (xy 75.575118 -217.725976) (xy 75.335582 -217.645629)
			(xy 75.098703 -217.557762) (xy 74.864715 -217.46246) (xy 74.633853 -217.359819) (xy 74.406346 -217.249941)
			(xy 74.182421 -217.132936) (xy 73.962301 -217.00892) (xy 73.746206 -216.878017) (xy 73.534351 -216.740357)
			(xy 73.326947 -216.596079) (xy 73.124201 -216.445324) (xy 72.926316 -216.288245) (xy 72.733488 -216.124996)
			(xy 72.54591 -215.955742) (xy 72.363768 -215.780651) (xy 72.187244 -215.599897) (xy 72.016514 -215.41366)
			(xy 71.851749 -215.222127) (xy 71.693113 -215.025487) (xy 71.540763 -214.823938) (xy 71.394851 -214.61768)
			(xy 71.255524 -214.406918) (xy 71.122919 -214.191863) (xy 70.99717 -213.972729) (xy 70.878401 -213.749734)
			(xy 70.76673 -213.523102) (xy 70.66227 -213.293056) (xy 70.565124 -213.059828) (xy 70.47539 -212.82365)
			(xy 70.393155 -212.584756) (xy 70.318504 -212.343386) (xy 70.251509 -212.099779) (xy 70.192238 -211.854178)
			(xy 70.140749 -211.606829) (xy 70.097095 -211.357978) (xy 70.061319 -211.107872) (xy 70.033455 -210.856762)
			(xy 70.013533 -210.604898) (xy 70.001572 -210.35253) (xy 69.997584 -210.09991) (xy 36.079698 -210.09991)
			(xy 36.071366 -210.106202) (xy 35.997482 -210.151949) (xy 35.919693 -210.190683) (xy 35.838661 -210.222075)
			(xy 35.755079 -210.245856) (xy 35.669659 -210.261824) (xy 35.58313 -210.269842) (xy 35.49623 -210.269842)
			(xy 35.409701 -210.261824) (xy 35.324281 -210.245856) (xy 35.240699 -210.222075) (xy 35.159667 -210.190683)
			(xy 35.081878 -210.151949) (xy 35.007994 -210.106202) (xy 34.938647 -210.053833) (xy 34.874427 -209.995289)
			(xy 34.815883 -209.931069) (xy 34.763514 -209.861722) (xy 34.717767 -209.787838) (xy 34.679033 -209.710049)
			(xy 34.647641 -209.629017) (xy 34.62386 -209.545435) (xy 34.607892 -209.460015) (xy 34.599874 -209.373486)
			(xy 31.399486 -209.373486) (xy 31.391468 -209.460015) (xy 31.3755 -209.545435) (xy 31.351719 -209.629017)
			(xy 31.320327 -209.710049) (xy 31.281593 -209.787838) (xy 31.235846 -209.861722) (xy 31.183477 -209.931069)
			(xy 31.124933 -209.995289) (xy 31.060713 -210.053833) (xy 30.991366 -210.106202) (xy 30.917482 -210.151949)
			(xy 30.839693 -210.190683) (xy 30.758661 -210.222075) (xy 30.675079 -210.245856) (xy 30.589659 -210.261824)
			(xy 30.50313 -210.269842) (xy 30.41623 -210.269842) (xy 30.329701 -210.261824) (xy 30.244281 -210.245856)
			(xy 30.160699 -210.222075) (xy 30.079667 -210.190683) (xy 30.001878 -210.151949) (xy 29.927994 -210.106202)
			(xy 29.858647 -210.053833) (xy 29.794427 -209.995289) (xy 29.735883 -209.931069) (xy 29.683514 -209.861722)
			(xy 29.637767 -209.787838) (xy 29.599033 -209.710049) (xy 29.567641 -209.629017) (xy 29.54386 -209.545435)
			(xy 29.527892 -209.460015) (xy 29.519874 -209.373486) (xy 28.753816 -209.373486) (xy 28.753816 -210.908747)
			(xy 38.847768 -210.908747) (xy 38.847768 -210.837425) (xy 38.855754 -210.766551) (xy 38.871624 -210.697016)
			(xy 38.895181 -210.629696) (xy 38.926126 -210.565437) (xy 38.964072 -210.505046) (xy 39.008541 -210.449284)
			(xy 39.058974 -210.398851) (xy 39.114736 -210.354382) (xy 39.175127 -210.316436) (xy 39.239386 -210.285491)
			(xy 39.306706 -210.261934) (xy 39.376241 -210.246064) (xy 39.447115 -210.238078) (xy 39.518437 -210.238078)
			(xy 39.589311 -210.246064) (xy 39.658846 -210.261934) (xy 39.726166 -210.285491) (xy 39.790425 -210.316436)
			(xy 39.850816 -210.354382) (xy 39.906578 -210.398851) (xy 39.957011 -210.449284) (xy 40.00148 -210.505046)
			(xy 40.039426 -210.565437) (xy 40.070371 -210.629696) (xy 40.093928 -210.697016) (xy 40.109798 -210.766551)
			(xy 40.117784 -210.837425) (xy 40.118284 -210.873086) (xy 40.117784 -210.908747) (xy 40.73448 -210.908747)
			(xy 40.73448 -210.837425) (xy 40.742466 -210.766551) (xy 40.758336 -210.697016) (xy 40.781893 -210.629696)
			(xy 40.812838 -210.565437) (xy 40.850784 -210.505046) (xy 40.895253 -210.449284) (xy 40.945686 -210.398851)
			(xy 41.001448 -210.354382) (xy 41.061839 -210.316436) (xy 41.126098 -210.285491) (xy 41.193418 -210.261934)
			(xy 41.262953 -210.246064) (xy 41.333827 -210.238078) (xy 41.405149 -210.238078) (xy 41.476023 -210.246064)
			(xy 41.545558 -210.261934) (xy 41.612878 -210.285491) (xy 41.677137 -210.316436) (xy 41.737528 -210.354382)
			(xy 41.79329 -210.398851) (xy 41.843723 -210.449284) (xy 41.888192 -210.505046) (xy 41.926138 -210.565437)
			(xy 41.957083 -210.629696) (xy 41.98064 -210.697016) (xy 41.99651 -210.766551) (xy 42.004496 -210.837425)
			(xy 42.004996 -210.873086) (xy 42.004496 -210.908747) (xy 42.975522 -210.908747) (xy 42.975522 -210.837425)
			(xy 42.983508 -210.766551) (xy 42.999378 -210.697016) (xy 43.022935 -210.629696) (xy 43.05388 -210.565437)
			(xy 43.091826 -210.505046) (xy 43.136295 -210.449284) (xy 43.186728 -210.398851) (xy 43.24249 -210.354382)
			(xy 43.302881 -210.316436) (xy 43.36714 -210.285491) (xy 43.43446 -210.261934) (xy 43.503995 -210.246064)
			(xy 43.574869 -210.238078) (xy 43.646191 -210.238078) (xy 43.717065 -210.246064) (xy 43.7866 -210.261934)
			(xy 43.85392 -210.285491) (xy 43.918179 -210.316436) (xy 43.97857 -210.354382) (xy 44.034332 -210.398851)
			(xy 44.084765 -210.449284) (xy 44.129234 -210.505046) (xy 44.16718 -210.565437) (xy 44.198125 -210.629696)
			(xy 44.221682 -210.697016) (xy 44.237552 -210.766551) (xy 44.245538 -210.837425) (xy 44.246038 -210.873086)
			(xy 44.245538 -210.908747) (xy 44.879506 -210.908747) (xy 44.879506 -210.837425) (xy 44.887492 -210.766551)
			(xy 44.903362 -210.697016) (xy 44.926919 -210.629696) (xy 44.957864 -210.565437) (xy 44.99581 -210.505046)
			(xy 45.040279 -210.449284) (xy 45.090712 -210.398851) (xy 45.146474 -210.354382) (xy 45.206865 -210.316436)
			(xy 45.271124 -210.285491) (xy 45.338444 -210.261934) (xy 45.407979 -210.246064) (xy 45.478853 -210.238078)
			(xy 45.550175 -210.238078) (xy 45.621049 -210.246064) (xy 45.690584 -210.261934) (xy 45.757904 -210.285491)
			(xy 45.822163 -210.316436) (xy 45.882554 -210.354382) (xy 45.938316 -210.398851) (xy 45.988749 -210.449284)
			(xy 46.033218 -210.505046) (xy 46.071164 -210.565437) (xy 46.102109 -210.629696) (xy 46.125666 -210.697016)
			(xy 46.141536 -210.766551) (xy 46.149522 -210.837425) (xy 46.150022 -210.873086) (xy 46.149522 -210.908747)
			(xy 46.141536 -210.979621) (xy 46.125666 -211.049156) (xy 46.102109 -211.116476) (xy 46.071164 -211.180735)
			(xy 46.033218 -211.241126) (xy 45.988749 -211.296888) (xy 45.938316 -211.347321) (xy 45.882554 -211.39179)
			(xy 45.822163 -211.429736) (xy 45.757904 -211.460681) (xy 45.690584 -211.484238) (xy 45.621049 -211.500108)
			(xy 45.550175 -211.508094) (xy 45.478853 -211.508094) (xy 45.407979 -211.500108) (xy 45.338444 -211.484238)
			(xy 45.271124 -211.460681) (xy 45.206865 -211.429736) (xy 45.146474 -211.39179) (xy 45.090712 -211.347321)
			(xy 45.040279 -211.296888) (xy 44.99581 -211.241126) (xy 44.957864 -211.180735) (xy 44.926919 -211.116476)
			(xy 44.903362 -211.049156) (xy 44.887492 -210.979621) (xy 44.879506 -210.908747) (xy 44.245538 -210.908747)
			(xy 44.237552 -210.979621) (xy 44.221682 -211.049156) (xy 44.198125 -211.116476) (xy 44.16718 -211.180735)
			(xy 44.129234 -211.241126) (xy 44.084765 -211.296888) (xy 44.034332 -211.347321) (xy 43.97857 -211.39179)
			(xy 43.918179 -211.429736) (xy 43.85392 -211.460681) (xy 43.7866 -211.484238) (xy 43.717065 -211.500108)
			(xy 43.646191 -211.508094) (xy 43.574869 -211.508094) (xy 43.503995 -211.500108) (xy 43.43446 -211.484238)
			(xy 43.36714 -211.460681) (xy 43.302881 -211.429736) (xy 43.24249 -211.39179) (xy 43.186728 -211.347321)
			(xy 43.136295 -211.296888) (xy 43.091826 -211.241126) (xy 43.05388 -211.180735) (xy 43.022935 -211.116476)
			(xy 42.999378 -211.049156) (xy 42.983508 -210.979621) (xy 42.975522 -210.908747) (xy 42.004496 -210.908747)
			(xy 41.99651 -210.979621) (xy 41.98064 -211.049156) (xy 41.957083 -211.116476) (xy 41.926138 -211.180735)
			(xy 41.888192 -211.241126) (xy 41.843723 -211.296888) (xy 41.79329 -211.347321) (xy 41.737528 -211.39179)
			(xy 41.677137 -211.429736) (xy 41.612878 -211.460681) (xy 41.545558 -211.484238) (xy 41.476023 -211.500108)
			(xy 41.405149 -211.508094) (xy 41.333827 -211.508094) (xy 41.262953 -211.500108) (xy 41.193418 -211.484238)
			(xy 41.126098 -211.460681) (xy 41.061839 -211.429736) (xy 41.001448 -211.39179) (xy 40.945686 -211.347321)
			(xy 40.895253 -211.296888) (xy 40.850784 -211.241126) (xy 40.812838 -211.180735) (xy 40.781893 -211.116476)
			(xy 40.758336 -211.049156) (xy 40.742466 -210.979621) (xy 40.73448 -210.908747) (xy 40.117784 -210.908747)
			(xy 40.109798 -210.979621) (xy 40.093928 -211.049156) (xy 40.070371 -211.116476) (xy 40.039426 -211.180735)
			(xy 40.00148 -211.241126) (xy 39.957011 -211.296888) (xy 39.906578 -211.347321) (xy 39.850816 -211.39179)
			(xy 39.790425 -211.429736) (xy 39.726166 -211.460681) (xy 39.658846 -211.484238) (xy 39.589311 -211.500108)
			(xy 39.518437 -211.508094) (xy 39.447115 -211.508094) (xy 39.376241 -211.500108) (xy 39.306706 -211.484238)
			(xy 39.239386 -211.460681) (xy 39.175127 -211.429736) (xy 39.114736 -211.39179) (xy 39.058974 -211.347321)
			(xy 39.008541 -211.296888) (xy 38.964072 -211.241126) (xy 38.926126 -211.180735) (xy 38.895181 -211.116476)
			(xy 38.871624 -211.049156) (xy 38.855754 -210.979621) (xy 38.847768 -210.908747) (xy 28.753816 -210.908747)
			(xy 28.753816 -211.913486) (xy 29.519874 -211.913486) (xy 29.519874 -211.826586) (xy 29.527892 -211.740057)
			(xy 29.54386 -211.654637) (xy 29.567641 -211.571055) (xy 29.599033 -211.490023) (xy 29.637767 -211.412234)
			(xy 29.683514 -211.33835) (xy 29.735883 -211.269003) (xy 29.794427 -211.204783) (xy 29.858647 -211.146239)
			(xy 29.927994 -211.09387) (xy 30.001878 -211.048123) (xy 30.079667 -211.009389) (xy 30.160699 -210.977997)
			(xy 30.244281 -210.954216) (xy 30.329701 -210.938248) (xy 30.41623 -210.93023) (xy 30.50313 -210.93023)
			(xy 30.589659 -210.938248) (xy 30.675079 -210.954216) (xy 30.758661 -210.977997) (xy 30.839693 -211.009389)
			(xy 30.917482 -211.048123) (xy 30.991366 -211.09387) (xy 31.060713 -211.146239) (xy 31.124933 -211.204783)
			(xy 31.183477 -211.269003) (xy 31.235846 -211.33835) (xy 31.281593 -211.412234) (xy 31.320327 -211.490023)
			(xy 31.351719 -211.571055) (xy 31.3755 -211.654637) (xy 31.391468 -211.740057) (xy 31.399486 -211.826586)
			(xy 31.399988 -211.870036) (xy 31.399486 -211.913486) (xy 34.599874 -211.913486) (xy 34.599874 -211.826586)
			(xy 34.607892 -211.740057) (xy 34.62386 -211.654637) (xy 34.647641 -211.571055) (xy 34.679033 -211.490023)
			(xy 34.717767 -211.412234) (xy 34.763514 -211.33835) (xy 34.815883 -211.269003) (xy 34.874427 -211.204783)
			(xy 34.938647 -211.146239) (xy 35.007994 -211.09387) (xy 35.081878 -211.048123) (xy 35.159667 -211.009389)
			(xy 35.240699 -210.977997) (xy 35.324281 -210.954216) (xy 35.409701 -210.938248) (xy 35.49623 -210.93023)
			(xy 35.58313 -210.93023) (xy 35.669659 -210.938248) (xy 35.755079 -210.954216) (xy 35.838661 -210.977997)
			(xy 35.919693 -211.009389) (xy 35.997482 -211.048123) (xy 36.071366 -211.09387) (xy 36.140713 -211.146239)
			(xy 36.204933 -211.204783) (xy 36.263477 -211.269003) (xy 36.315846 -211.33835) (xy 36.361593 -211.412234)
			(xy 36.400327 -211.490023) (xy 36.431719 -211.571055) (xy 36.4555 -211.654637) (xy 36.471468 -211.740057)
			(xy 36.479486 -211.826586) (xy 36.479988 -211.870036) (xy 36.479486 -211.913486) (xy 36.471468 -212.000015)
			(xy 36.4555 -212.085435) (xy 36.431719 -212.169017) (xy 36.400327 -212.250049) (xy 36.361593 -212.327838)
			(xy 36.315846 -212.401722) (xy 36.263477 -212.471069) (xy 36.204933 -212.535289) (xy 36.151634 -212.583877)
			(xy 38.847768 -212.583877) (xy 38.847768 -212.512555) (xy 38.855754 -212.441681) (xy 38.871624 -212.372146)
			(xy 38.895181 -212.304826) (xy 38.926126 -212.240567) (xy 38.964072 -212.180176) (xy 39.008541 -212.124414)
			(xy 39.058974 -212.073981) (xy 39.114736 -212.029512) (xy 39.175127 -211.991566) (xy 39.239386 -211.960621)
			(xy 39.306706 -211.937064) (xy 39.376241 -211.921194) (xy 39.447115 -211.913208) (xy 39.518437 -211.913208)
			(xy 39.589311 -211.921194) (xy 39.658846 -211.937064) (xy 39.726166 -211.960621) (xy 39.790425 -211.991566)
			(xy 39.850816 -212.029512) (xy 39.906578 -212.073981) (xy 39.957011 -212.124414) (xy 40.00148 -212.180176)
			(xy 40.039426 -212.240567) (xy 40.070371 -212.304826) (xy 40.093928 -212.372146) (xy 40.109798 -212.441681)
			(xy 40.117784 -212.512555) (xy 40.118284 -212.548216) (xy 40.117784 -212.583877) (xy 40.73448 -212.583877)
			(xy 40.73448 -212.512555) (xy 40.742466 -212.441681) (xy 40.758336 -212.372146) (xy 40.781893 -212.304826)
			(xy 40.812838 -212.240567) (xy 40.850784 -212.180176) (xy 40.895253 -212.124414) (xy 40.945686 -212.073981)
			(xy 41.001448 -212.029512) (xy 41.061839 -211.991566) (xy 41.126098 -211.960621) (xy 41.193418 -211.937064)
			(xy 41.262953 -211.921194) (xy 41.333827 -211.913208) (xy 41.405149 -211.913208) (xy 41.476023 -211.921194)
			(xy 41.545558 -211.937064) (xy 41.612878 -211.960621) (xy 41.677137 -211.991566) (xy 41.737528 -212.029512)
			(xy 41.79329 -212.073981) (xy 41.843723 -212.124414) (xy 41.888192 -212.180176) (xy 41.926138 -212.240567)
			(xy 41.957083 -212.304826) (xy 41.98064 -212.372146) (xy 41.99651 -212.441681) (xy 42.004496 -212.512555)
			(xy 42.004996 -212.548216) (xy 42.004496 -212.583877) (xy 42.975522 -212.583877) (xy 42.975522 -212.512555)
			(xy 42.983508 -212.441681) (xy 42.999378 -212.372146) (xy 43.022935 -212.304826) (xy 43.05388 -212.240567)
			(xy 43.091826 -212.180176) (xy 43.136295 -212.124414) (xy 43.186728 -212.073981) (xy 43.24249 -212.029512)
			(xy 43.302881 -211.991566) (xy 43.36714 -211.960621) (xy 43.43446 -211.937064) (xy 43.503995 -211.921194)
			(xy 43.574869 -211.913208) (xy 43.646191 -211.913208) (xy 43.717065 -211.921194) (xy 43.7866 -211.937064)
			(xy 43.85392 -211.960621) (xy 43.918179 -211.991566) (xy 43.97857 -212.029512) (xy 44.034332 -212.073981)
			(xy 44.084765 -212.124414) (xy 44.129234 -212.180176) (xy 44.16718 -212.240567) (xy 44.198125 -212.304826)
			(xy 44.221682 -212.372146) (xy 44.237552 -212.441681) (xy 44.245538 -212.512555) (xy 44.246038 -212.548216)
			(xy 44.245538 -212.583877) (xy 44.879506 -212.583877) (xy 44.879506 -212.512555) (xy 44.887492 -212.441681)
			(xy 44.903362 -212.372146) (xy 44.926919 -212.304826) (xy 44.957864 -212.240567) (xy 44.99581 -212.180176)
			(xy 45.040279 -212.124414) (xy 45.090712 -212.073981) (xy 45.146474 -212.029512) (xy 45.206865 -211.991566)
			(xy 45.271124 -211.960621) (xy 45.338444 -211.937064) (xy 45.407979 -211.921194) (xy 45.478853 -211.913208)
			(xy 45.550175 -211.913208) (xy 45.621049 -211.921194) (xy 45.690584 -211.937064) (xy 45.757904 -211.960621)
			(xy 45.822163 -211.991566) (xy 45.882554 -212.029512) (xy 45.938316 -212.073981) (xy 45.988749 -212.124414)
			(xy 46.033218 -212.180176) (xy 46.071164 -212.240567) (xy 46.102109 -212.304826) (xy 46.125666 -212.372146)
			(xy 46.141536 -212.441681) (xy 46.149522 -212.512555) (xy 46.150022 -212.548216) (xy 46.149522 -212.583877)
			(xy 46.141536 -212.654751) (xy 46.125666 -212.724286) (xy 46.102109 -212.791606) (xy 46.071164 -212.855865)
			(xy 46.033218 -212.916256) (xy 45.988749 -212.972018) (xy 45.938316 -213.022451) (xy 45.882554 -213.06692)
			(xy 45.822163 -213.104866) (xy 45.757904 -213.135811) (xy 45.690584 -213.159368) (xy 45.621049 -213.175238)
			(xy 45.550175 -213.183224) (xy 45.478853 -213.183224) (xy 45.407979 -213.175238) (xy 45.338444 -213.159368)
			(xy 45.271124 -213.135811) (xy 45.206865 -213.104866) (xy 45.146474 -213.06692) (xy 45.090712 -213.022451)
			(xy 45.040279 -212.972018) (xy 44.99581 -212.916256) (xy 44.957864 -212.855865) (xy 44.926919 -212.791606)
			(xy 44.903362 -212.724286) (xy 44.887492 -212.654751) (xy 44.879506 -212.583877) (xy 44.245538 -212.583877)
			(xy 44.237552 -212.654751) (xy 44.221682 -212.724286) (xy 44.198125 -212.791606) (xy 44.16718 -212.855865)
			(xy 44.129234 -212.916256) (xy 44.084765 -212.972018) (xy 44.034332 -213.022451) (xy 43.97857 -213.06692)
			(xy 43.918179 -213.104866) (xy 43.85392 -213.135811) (xy 43.7866 -213.159368) (xy 43.717065 -213.175238)
			(xy 43.646191 -213.183224) (xy 43.574869 -213.183224) (xy 43.503995 -213.175238) (xy 43.43446 -213.159368)
			(xy 43.36714 -213.135811) (xy 43.302881 -213.104866) (xy 43.24249 -213.06692) (xy 43.186728 -213.022451)
			(xy 43.136295 -212.972018) (xy 43.091826 -212.916256) (xy 43.05388 -212.855865) (xy 43.022935 -212.791606)
			(xy 42.999378 -212.724286) (xy 42.983508 -212.654751) (xy 42.975522 -212.583877) (xy 42.004496 -212.583877)
			(xy 41.99651 -212.654751) (xy 41.98064 -212.724286) (xy 41.957083 -212.791606) (xy 41.926138 -212.855865)
			(xy 41.888192 -212.916256) (xy 41.843723 -212.972018) (xy 41.79329 -213.022451) (xy 41.737528 -213.06692)
			(xy 41.677137 -213.104866) (xy 41.612878 -213.135811) (xy 41.545558 -213.159368) (xy 41.476023 -213.175238)
			(xy 41.405149 -213.183224) (xy 41.333827 -213.183224) (xy 41.262953 -213.175238) (xy 41.193418 -213.159368)
			(xy 41.126098 -213.135811) (xy 41.061839 -213.104866) (xy 41.001448 -213.06692) (xy 40.945686 -213.022451)
			(xy 40.895253 -212.972018) (xy 40.850784 -212.916256) (xy 40.812838 -212.855865) (xy 40.781893 -212.791606)
			(xy 40.758336 -212.724286) (xy 40.742466 -212.654751) (xy 40.73448 -212.583877) (xy 40.117784 -212.583877)
			(xy 40.109798 -212.654751) (xy 40.093928 -212.724286) (xy 40.070371 -212.791606) (xy 40.039426 -212.855865)
			(xy 40.00148 -212.916256) (xy 39.957011 -212.972018) (xy 39.906578 -213.022451) (xy 39.850816 -213.06692)
			(xy 39.790425 -213.104866) (xy 39.726166 -213.135811) (xy 39.658846 -213.159368) (xy 39.589311 -213.175238)
			(xy 39.518437 -213.183224) (xy 39.447115 -213.183224) (xy 39.376241 -213.175238) (xy 39.306706 -213.159368)
			(xy 39.239386 -213.135811) (xy 39.175127 -213.104866) (xy 39.114736 -213.06692) (xy 39.058974 -213.022451)
			(xy 39.008541 -212.972018) (xy 38.964072 -212.916256) (xy 38.926126 -212.855865) (xy 38.895181 -212.791606)
			(xy 38.871624 -212.724286) (xy 38.855754 -212.654751) (xy 38.847768 -212.583877) (xy 36.151634 -212.583877)
			(xy 36.140713 -212.593833) (xy 36.071366 -212.646202) (xy 35.997482 -212.691949) (xy 35.919693 -212.730683)
			(xy 35.838661 -212.762075) (xy 35.755079 -212.785856) (xy 35.669659 -212.801824) (xy 35.58313 -212.809842)
			(xy 35.49623 -212.809842) (xy 35.409701 -212.801824) (xy 35.324281 -212.785856) (xy 35.240699 -212.762075)
			(xy 35.159667 -212.730683) (xy 35.081878 -212.691949) (xy 35.007994 -212.646202) (xy 34.938647 -212.593833)
			(xy 34.874427 -212.535289) (xy 34.815883 -212.471069) (xy 34.763514 -212.401722) (xy 34.717767 -212.327838)
			(xy 34.679033 -212.250049) (xy 34.647641 -212.169017) (xy 34.62386 -212.085435) (xy 34.607892 -212.000015)
			(xy 34.599874 -211.913486) (xy 31.399486 -211.913486) (xy 31.391468 -212.000015) (xy 31.3755 -212.085435)
			(xy 31.351719 -212.169017) (xy 31.320327 -212.250049) (xy 31.281593 -212.327838) (xy 31.235846 -212.401722)
			(xy 31.183477 -212.471069) (xy 31.124933 -212.535289) (xy 31.060713 -212.593833) (xy 30.991366 -212.646202)
			(xy 30.917482 -212.691949) (xy 30.839693 -212.730683) (xy 30.758661 -212.762075) (xy 30.675079 -212.785856)
			(xy 30.589659 -212.801824) (xy 30.50313 -212.809842) (xy 30.41623 -212.809842) (xy 30.329701 -212.801824)
			(xy 30.244281 -212.785856) (xy 30.160699 -212.762075) (xy 30.079667 -212.730683) (xy 30.001878 -212.691949)
			(xy 29.927994 -212.646202) (xy 29.858647 -212.593833) (xy 29.794427 -212.535289) (xy 29.735883 -212.471069)
			(xy 29.683514 -212.401722) (xy 29.637767 -212.327838) (xy 29.599033 -212.250049) (xy 29.567641 -212.169017)
			(xy 29.54386 -212.085435) (xy 29.527892 -212.000015) (xy 29.519874 -211.913486) (xy 28.753816 -211.913486)
			(xy 28.753816 -214.453486) (xy 29.519874 -214.453486) (xy 29.519874 -214.366586) (xy 29.527892 -214.280057)
			(xy 29.54386 -214.194637) (xy 29.567641 -214.111055) (xy 29.599033 -214.030023) (xy 29.637767 -213.952234)
			(xy 29.683514 -213.87835) (xy 29.735883 -213.809003) (xy 29.794427 -213.744783) (xy 29.858647 -213.686239)
			(xy 29.927994 -213.63387) (xy 30.001878 -213.588123) (xy 30.079667 -213.549389) (xy 30.160699 -213.517997)
			(xy 30.244281 -213.494216) (xy 30.329701 -213.478248) (xy 30.41623 -213.47023) (xy 30.50313 -213.47023)
			(xy 30.589659 -213.478248) (xy 30.675079 -213.494216) (xy 30.758661 -213.517997) (xy 30.839693 -213.549389)
			(xy 30.917482 -213.588123) (xy 30.991366 -213.63387) (xy 31.060713 -213.686239) (xy 31.124933 -213.744783)
			(xy 31.183477 -213.809003) (xy 31.235846 -213.87835) (xy 31.281593 -213.952234) (xy 31.320327 -214.030023)
			(xy 31.351719 -214.111055) (xy 31.3755 -214.194637) (xy 31.391468 -214.280057) (xy 31.399486 -214.366586)
			(xy 31.399988 -214.410036) (xy 31.399486 -214.453486) (xy 34.599874 -214.453486) (xy 34.599874 -214.366586)
			(xy 34.607892 -214.280057) (xy 34.62386 -214.194637) (xy 34.647641 -214.111055) (xy 34.679033 -214.030023)
			(xy 34.717767 -213.952234) (xy 34.763514 -213.87835) (xy 34.815883 -213.809003) (xy 34.874427 -213.744783)
			(xy 34.938647 -213.686239) (xy 35.007994 -213.63387) (xy 35.081878 -213.588123) (xy 35.159667 -213.549389)
			(xy 35.240699 -213.517997) (xy 35.324281 -213.494216) (xy 35.409701 -213.478248) (xy 35.49623 -213.47023)
			(xy 35.58313 -213.47023) (xy 35.669659 -213.478248) (xy 35.755079 -213.494216) (xy 35.838661 -213.517997)
			(xy 35.919693 -213.549389) (xy 35.997482 -213.588123) (xy 36.071366 -213.63387) (xy 36.140713 -213.686239)
			(xy 36.204933 -213.744783) (xy 36.263477 -213.809003) (xy 36.315846 -213.87835) (xy 36.361593 -213.952234)
			(xy 36.400327 -214.030023) (xy 36.431719 -214.111055) (xy 36.4555 -214.194637) (xy 36.471468 -214.280057)
			(xy 36.479486 -214.366586) (xy 36.479988 -214.410036) (xy 36.479486 -214.453486) (xy 36.471468 -214.540015)
			(xy 36.46118 -214.595049) (xy 38.804334 -214.595049) (xy 38.804334 -214.523727) (xy 38.81232 -214.452853)
			(xy 38.82819 -214.383318) (xy 38.851747 -214.315998) (xy 38.882692 -214.251739) (xy 38.920638 -214.191348)
			(xy 38.965107 -214.135586) (xy 39.01554 -214.085153) (xy 39.071302 -214.040684) (xy 39.131693 -214.002738)
			(xy 39.195952 -213.971793) (xy 39.263272 -213.948236) (xy 39.332807 -213.932366) (xy 39.403681 -213.92438)
			(xy 39.475003 -213.92438) (xy 39.545877 -213.932366) (xy 39.615412 -213.948236) (xy 39.682732 -213.971793)
			(xy 39.746991 -214.002738) (xy 39.807382 -214.040684) (xy 39.863144 -214.085153) (xy 39.913577 -214.135586)
			(xy 39.958046 -214.191348) (xy 39.995992 -214.251739) (xy 40.026937 -214.315998) (xy 40.050494 -214.383318)
			(xy 40.066364 -214.452853) (xy 40.07435 -214.523727) (xy 40.07485 -214.559388) (xy 40.07435 -214.595049)
			(xy 40.691046 -214.595049) (xy 40.691046 -214.523727) (xy 40.699032 -214.452853) (xy 40.714902 -214.383318)
			(xy 40.738459 -214.315998) (xy 40.769404 -214.251739) (xy 40.80735 -214.191348) (xy 40.851819 -214.135586)
			(xy 40.902252 -214.085153) (xy 40.958014 -214.040684) (xy 41.018405 -214.002738) (xy 41.082664 -213.971793)
			(xy 41.149984 -213.948236) (xy 41.219519 -213.932366) (xy 41.290393 -213.92438) (xy 41.361715 -213.92438)
			(xy 41.432589 -213.932366) (xy 41.502124 -213.948236) (xy 41.569444 -213.971793) (xy 41.633703 -214.002738)
			(xy 41.694094 -214.040684) (xy 41.749856 -214.085153) (xy 41.800289 -214.135586) (xy 41.844758 -214.191348)
			(xy 41.882704 -214.251739) (xy 41.913649 -214.315998) (xy 41.937206 -214.383318) (xy 41.953076 -214.452853)
			(xy 41.961062 -214.523727) (xy 41.961562 -214.559388) (xy 41.961062 -214.595049) (xy 42.932088 -214.595049)
			(xy 42.932088 -214.523727) (xy 42.940074 -214.452853) (xy 42.955944 -214.383318) (xy 42.979501 -214.315998)
			(xy 43.010446 -214.251739) (xy 43.048392 -214.191348) (xy 43.092861 -214.135586) (xy 43.143294 -214.085153)
			(xy 43.199056 -214.040684) (xy 43.259447 -214.002738) (xy 43.323706 -213.971793) (xy 43.391026 -213.948236)
			(xy 43.460561 -213.932366) (xy 43.531435 -213.92438) (xy 43.602757 -213.92438) (xy 43.673631 -213.932366)
			(xy 43.743166 -213.948236) (xy 43.810486 -213.971793) (xy 43.874745 -214.002738) (xy 43.935136 -214.040684)
			(xy 43.990898 -214.085153) (xy 44.041331 -214.135586) (xy 44.0858 -214.191348) (xy 44.123746 -214.251739)
			(xy 44.154691 -214.315998) (xy 44.178248 -214.383318) (xy 44.194118 -214.452853) (xy 44.202104 -214.523727)
			(xy 44.202604 -214.559388) (xy 44.202104 -214.595049) (xy 44.836072 -214.595049) (xy 44.836072 -214.523727)
			(xy 44.844058 -214.452853) (xy 44.859928 -214.383318) (xy 44.883485 -214.315998) (xy 44.91443 -214.251739)
			(xy 44.952376 -214.191348) (xy 44.996845 -214.135586) (xy 45.047278 -214.085153) (xy 45.10304 -214.040684)
			(xy 45.163431 -214.002738) (xy 45.22769 -213.971793) (xy 45.29501 -213.948236) (xy 45.364545 -213.932366)
			(xy 45.435419 -213.92438) (xy 45.506741 -213.92438) (xy 45.577615 -213.932366) (xy 45.64715 -213.948236)
			(xy 45.71447 -213.971793) (xy 45.778729 -214.002738) (xy 45.83912 -214.040684) (xy 45.894882 -214.085153)
			(xy 45.945315 -214.135586) (xy 45.989784 -214.191348) (xy 46.02773 -214.251739) (xy 46.058675 -214.315998)
			(xy 46.082232 -214.383318) (xy 46.098102 -214.452853) (xy 46.106088 -214.523727) (xy 46.106588 -214.559388)
			(xy 46.106088 -214.595049) (xy 46.098102 -214.665923) (xy 46.082232 -214.735458) (xy 46.058675 -214.802778)
			(xy 46.02773 -214.867037) (xy 45.989784 -214.927428) (xy 45.945315 -214.98319) (xy 45.894882 -215.033623)
			(xy 45.83912 -215.078092) (xy 45.778729 -215.116038) (xy 45.71447 -215.146983) (xy 45.64715 -215.17054)
			(xy 45.577615 -215.18641) (xy 45.506741 -215.194396) (xy 45.435419 -215.194396) (xy 45.364545 -215.18641)
			(xy 45.29501 -215.17054) (xy 45.22769 -215.146983) (xy 45.163431 -215.116038) (xy 45.10304 -215.078092)
			(xy 45.047278 -215.033623) (xy 44.996845 -214.98319) (xy 44.952376 -214.927428) (xy 44.91443 -214.867037)
			(xy 44.883485 -214.802778) (xy 44.859928 -214.735458) (xy 44.844058 -214.665923) (xy 44.836072 -214.595049)
			(xy 44.202104 -214.595049) (xy 44.194118 -214.665923) (xy 44.178248 -214.735458) (xy 44.154691 -214.802778)
			(xy 44.123746 -214.867037) (xy 44.0858 -214.927428) (xy 44.041331 -214.98319) (xy 43.990898 -215.033623)
			(xy 43.935136 -215.078092) (xy 43.874745 -215.116038) (xy 43.810486 -215.146983) (xy 43.743166 -215.17054)
			(xy 43.673631 -215.18641) (xy 43.602757 -215.194396) (xy 43.531435 -215.194396) (xy 43.460561 -215.18641)
			(xy 43.391026 -215.17054) (xy 43.323706 -215.146983) (xy 43.259447 -215.116038) (xy 43.199056 -215.078092)
			(xy 43.143294 -215.033623) (xy 43.092861 -214.98319) (xy 43.048392 -214.927428) (xy 43.010446 -214.867037)
			(xy 42.979501 -214.802778) (xy 42.955944 -214.735458) (xy 42.940074 -214.665923) (xy 42.932088 -214.595049)
			(xy 41.961062 -214.595049) (xy 41.953076 -214.665923) (xy 41.937206 -214.735458) (xy 41.913649 -214.802778)
			(xy 41.882704 -214.867037) (xy 41.844758 -214.927428) (xy 41.800289 -214.98319) (xy 41.749856 -215.033623)
			(xy 41.694094 -215.078092) (xy 41.633703 -215.116038) (xy 41.569444 -215.146983) (xy 41.502124 -215.17054)
			(xy 41.432589 -215.18641) (xy 41.361715 -215.194396) (xy 41.290393 -215.194396) (xy 41.219519 -215.18641)
			(xy 41.149984 -215.17054) (xy 41.082664 -215.146983) (xy 41.018405 -215.116038) (xy 40.958014 -215.078092)
			(xy 40.902252 -215.033623) (xy 40.851819 -214.98319) (xy 40.80735 -214.927428) (xy 40.769404 -214.867037)
			(xy 40.738459 -214.802778) (xy 40.714902 -214.735458) (xy 40.699032 -214.665923) (xy 40.691046 -214.595049)
			(xy 40.07435 -214.595049) (xy 40.066364 -214.665923) (xy 40.050494 -214.735458) (xy 40.026937 -214.802778)
			(xy 39.995992 -214.867037) (xy 39.958046 -214.927428) (xy 39.913577 -214.98319) (xy 39.863144 -215.033623)
			(xy 39.807382 -215.078092) (xy 39.746991 -215.116038) (xy 39.682732 -215.146983) (xy 39.615412 -215.17054)
			(xy 39.545877 -215.18641) (xy 39.475003 -215.194396) (xy 39.403681 -215.194396) (xy 39.332807 -215.18641)
			(xy 39.263272 -215.17054) (xy 39.195952 -215.146983) (xy 39.131693 -215.116038) (xy 39.071302 -215.078092)
			(xy 39.01554 -215.033623) (xy 38.965107 -214.98319) (xy 38.920638 -214.927428) (xy 38.882692 -214.867037)
			(xy 38.851747 -214.802778) (xy 38.82819 -214.735458) (xy 38.81232 -214.665923) (xy 38.804334 -214.595049)
			(xy 36.46118 -214.595049) (xy 36.4555 -214.625435) (xy 36.431719 -214.709017) (xy 36.400327 -214.790049)
			(xy 36.361593 -214.867838) (xy 36.315846 -214.941722) (xy 36.263477 -215.011069) (xy 36.204933 -215.075289)
			(xy 36.140713 -215.133833) (xy 36.071366 -215.186202) (xy 35.997482 -215.231949) (xy 35.919693 -215.270683)
			(xy 35.838661 -215.302075) (xy 35.755079 -215.325856) (xy 35.669659 -215.341824) (xy 35.58313 -215.349842)
			(xy 35.49623 -215.349842) (xy 35.409701 -215.341824) (xy 35.324281 -215.325856) (xy 35.240699 -215.302075)
			(xy 35.159667 -215.270683) (xy 35.081878 -215.231949) (xy 35.007994 -215.186202) (xy 34.938647 -215.133833)
			(xy 34.874427 -215.075289) (xy 34.815883 -215.011069) (xy 34.763514 -214.941722) (xy 34.717767 -214.867838)
			(xy 34.679033 -214.790049) (xy 34.647641 -214.709017) (xy 34.62386 -214.625435) (xy 34.607892 -214.540015)
			(xy 34.599874 -214.453486) (xy 31.399486 -214.453486) (xy 31.391468 -214.540015) (xy 31.3755 -214.625435)
			(xy 31.351719 -214.709017) (xy 31.320327 -214.790049) (xy 31.281593 -214.867838) (xy 31.235846 -214.941722)
			(xy 31.183477 -215.011069) (xy 31.124933 -215.075289) (xy 31.060713 -215.133833) (xy 30.991366 -215.186202)
			(xy 30.917482 -215.231949) (xy 30.839693 -215.270683) (xy 30.758661 -215.302075) (xy 30.675079 -215.325856)
			(xy 30.589659 -215.341824) (xy 30.50313 -215.349842) (xy 30.41623 -215.349842) (xy 30.329701 -215.341824)
			(xy 30.244281 -215.325856) (xy 30.160699 -215.302075) (xy 30.079667 -215.270683) (xy 30.001878 -215.231949)
			(xy 29.927994 -215.186202) (xy 29.858647 -215.133833) (xy 29.794427 -215.075289) (xy 29.735883 -215.011069)
			(xy 29.683514 -214.941722) (xy 29.637767 -214.867838) (xy 29.599033 -214.790049) (xy 29.567641 -214.709017)
			(xy 29.54386 -214.625435) (xy 29.527892 -214.540015) (xy 29.519874 -214.453486) (xy 28.753816 -214.453486)
			(xy 28.753816 -216.993486) (xy 29.519874 -216.993486) (xy 29.519874 -216.906586) (xy 29.527892 -216.820057)
			(xy 29.54386 -216.734637) (xy 29.567641 -216.651055) (xy 29.599033 -216.570023) (xy 29.637767 -216.492234)
			(xy 29.683514 -216.41835) (xy 29.735883 -216.349003) (xy 29.794427 -216.284783) (xy 29.858647 -216.226239)
			(xy 29.927994 -216.17387) (xy 30.001878 -216.128123) (xy 30.079667 -216.089389) (xy 30.160699 -216.057997)
			(xy 30.244281 -216.034216) (xy 30.329701 -216.018248) (xy 30.41623 -216.01023) (xy 30.50313 -216.01023)
			(xy 30.589659 -216.018248) (xy 30.675079 -216.034216) (xy 30.758661 -216.057997) (xy 30.839693 -216.089389)
			(xy 30.917482 -216.128123) (xy 30.991366 -216.17387) (xy 31.060713 -216.226239) (xy 31.124933 -216.284783)
			(xy 31.183477 -216.349003) (xy 31.235846 -216.41835) (xy 31.281593 -216.492234) (xy 31.320327 -216.570023)
			(xy 31.351719 -216.651055) (xy 31.3755 -216.734637) (xy 31.391468 -216.820057) (xy 31.399486 -216.906586)
			(xy 31.399988 -216.950036) (xy 31.399486 -216.993486) (xy 34.599874 -216.993486) (xy 34.599874 -216.906586)
			(xy 34.607892 -216.820057) (xy 34.62386 -216.734637) (xy 34.647641 -216.651055) (xy 34.679033 -216.570023)
			(xy 34.717767 -216.492234) (xy 34.763514 -216.41835) (xy 34.815883 -216.349003) (xy 34.874427 -216.284783)
			(xy 34.938647 -216.226239) (xy 35.007994 -216.17387) (xy 35.081878 -216.128123) (xy 35.159667 -216.089389)
			(xy 35.240699 -216.057997) (xy 35.324281 -216.034216) (xy 35.409701 -216.018248) (xy 35.49623 -216.01023)
			(xy 35.58313 -216.01023) (xy 35.669659 -216.018248) (xy 35.755079 -216.034216) (xy 35.838661 -216.057997)
			(xy 35.919693 -216.089389) (xy 35.997482 -216.128123) (xy 36.071366 -216.17387) (xy 36.140713 -216.226239)
			(xy 36.204933 -216.284783) (xy 36.263477 -216.349003) (xy 36.315846 -216.41835) (xy 36.357467 -216.485571)
			(xy 38.804334 -216.485571) (xy 38.804334 -216.414249) (xy 38.81232 -216.343375) (xy 38.82819 -216.27384)
			(xy 38.851747 -216.20652) (xy 38.882692 -216.142261) (xy 38.920638 -216.08187) (xy 38.965107 -216.026108)
			(xy 39.01554 -215.975675) (xy 39.071302 -215.931206) (xy 39.131693 -215.89326) (xy 39.195952 -215.862315)
			(xy 39.263272 -215.838758) (xy 39.332807 -215.822888) (xy 39.403681 -215.814902) (xy 39.475003 -215.814902)
			(xy 39.545877 -215.822888) (xy 39.615412 -215.838758) (xy 39.682732 -215.862315) (xy 39.746991 -215.89326)
			(xy 39.807382 -215.931206) (xy 39.863144 -215.975675) (xy 39.913577 -216.026108) (xy 39.958046 -216.08187)
			(xy 39.995992 -216.142261) (xy 40.026937 -216.20652) (xy 40.050494 -216.27384) (xy 40.066364 -216.343375)
			(xy 40.07435 -216.414249) (xy 40.07485 -216.44991) (xy 40.07435 -216.485571) (xy 40.691046 -216.485571)
			(xy 40.691046 -216.414249) (xy 40.699032 -216.343375) (xy 40.714902 -216.27384) (xy 40.738459 -216.20652)
			(xy 40.769404 -216.142261) (xy 40.80735 -216.08187) (xy 40.851819 -216.026108) (xy 40.902252 -215.975675)
			(xy 40.958014 -215.931206) (xy 41.018405 -215.89326) (xy 41.082664 -215.862315) (xy 41.149984 -215.838758)
			(xy 41.219519 -215.822888) (xy 41.290393 -215.814902) (xy 41.361715 -215.814902) (xy 41.432589 -215.822888)
			(xy 41.502124 -215.838758) (xy 41.569444 -215.862315) (xy 41.633703 -215.89326) (xy 41.694094 -215.931206)
			(xy 41.749856 -215.975675) (xy 41.800289 -216.026108) (xy 41.844758 -216.08187) (xy 41.882704 -216.142261)
			(xy 41.913649 -216.20652) (xy 41.937206 -216.27384) (xy 41.953076 -216.343375) (xy 41.961062 -216.414249)
			(xy 41.961562 -216.44991) (xy 41.961062 -216.485571) (xy 42.932088 -216.485571) (xy 42.932088 -216.414249)
			(xy 42.940074 -216.343375) (xy 42.955944 -216.27384) (xy 42.979501 -216.20652) (xy 43.010446 -216.142261)
			(xy 43.048392 -216.08187) (xy 43.092861 -216.026108) (xy 43.143294 -215.975675) (xy 43.199056 -215.931206)
			(xy 43.259447 -215.89326) (xy 43.323706 -215.862315) (xy 43.391026 -215.838758) (xy 43.460561 -215.822888)
			(xy 43.531435 -215.814902) (xy 43.602757 -215.814902) (xy 43.673631 -215.822888) (xy 43.743166 -215.838758)
			(xy 43.810486 -215.862315) (xy 43.874745 -215.89326) (xy 43.935136 -215.931206) (xy 43.990898 -215.975675)
			(xy 44.041331 -216.026108) (xy 44.0858 -216.08187) (xy 44.123746 -216.142261) (xy 44.154691 -216.20652)
			(xy 44.178248 -216.27384) (xy 44.194118 -216.343375) (xy 44.202104 -216.414249) (xy 44.202604 -216.44991)
			(xy 44.202104 -216.485571) (xy 44.836072 -216.485571) (xy 44.836072 -216.414249) (xy 44.844058 -216.343375)
			(xy 44.859928 -216.27384) (xy 44.883485 -216.20652) (xy 44.91443 -216.142261) (xy 44.952376 -216.08187)
			(xy 44.996845 -216.026108) (xy 45.047278 -215.975675) (xy 45.10304 -215.931206) (xy 45.163431 -215.89326)
			(xy 45.22769 -215.862315) (xy 45.29501 -215.838758) (xy 45.364545 -215.822888) (xy 45.435419 -215.814902)
			(xy 45.506741 -215.814902) (xy 45.577615 -215.822888) (xy 45.64715 -215.838758) (xy 45.71447 -215.862315)
			(xy 45.778729 -215.89326) (xy 45.83912 -215.931206) (xy 45.894882 -215.975675) (xy 45.945315 -216.026108)
			(xy 45.989784 -216.08187) (xy 46.02773 -216.142261) (xy 46.058675 -216.20652) (xy 46.082232 -216.27384)
			(xy 46.098102 -216.343375) (xy 46.106088 -216.414249) (xy 46.106588 -216.44991) (xy 46.106088 -216.485571)
			(xy 46.098102 -216.556445) (xy 46.082232 -216.62598) (xy 46.058675 -216.6933) (xy 46.02773 -216.757559)
			(xy 45.989784 -216.81795) (xy 45.945315 -216.873712) (xy 45.894882 -216.924145) (xy 45.83912 -216.968614)
			(xy 45.778729 -217.00656) (xy 45.71447 -217.037505) (xy 45.64715 -217.061062) (xy 45.577615 -217.076932)
			(xy 45.506741 -217.084918) (xy 45.435419 -217.084918) (xy 45.364545 -217.076932) (xy 45.29501 -217.061062)
			(xy 45.22769 -217.037505) (xy 45.163431 -217.00656) (xy 45.10304 -216.968614) (xy 45.047278 -216.924145)
			(xy 44.996845 -216.873712) (xy 44.952376 -216.81795) (xy 44.91443 -216.757559) (xy 44.883485 -216.6933)
			(xy 44.859928 -216.62598) (xy 44.844058 -216.556445) (xy 44.836072 -216.485571) (xy 44.202104 -216.485571)
			(xy 44.194118 -216.556445) (xy 44.178248 -216.62598) (xy 44.154691 -216.6933) (xy 44.123746 -216.757559)
			(xy 44.0858 -216.81795) (xy 44.041331 -216.873712) (xy 43.990898 -216.924145) (xy 43.935136 -216.968614)
			(xy 43.874745 -217.00656) (xy 43.810486 -217.037505) (xy 43.743166 -217.061062) (xy 43.673631 -217.076932)
			(xy 43.602757 -217.084918) (xy 43.531435 -217.084918) (xy 43.460561 -217.076932) (xy 43.391026 -217.061062)
			(xy 43.323706 -217.037505) (xy 43.259447 -217.00656) (xy 43.199056 -216.968614) (xy 43.143294 -216.924145)
			(xy 43.092861 -216.873712) (xy 43.048392 -216.81795) (xy 43.010446 -216.757559) (xy 42.979501 -216.6933)
			(xy 42.955944 -216.62598) (xy 42.940074 -216.556445) (xy 42.932088 -216.485571) (xy 41.961062 -216.485571)
			(xy 41.953076 -216.556445) (xy 41.937206 -216.62598) (xy 41.913649 -216.6933) (xy 41.882704 -216.757559)
			(xy 41.844758 -216.81795) (xy 41.800289 -216.873712) (xy 41.749856 -216.924145) (xy 41.694094 -216.968614)
			(xy 41.633703 -217.00656) (xy 41.569444 -217.037505) (xy 41.502124 -217.061062) (xy 41.432589 -217.076932)
			(xy 41.361715 -217.084918) (xy 41.290393 -217.084918) (xy 41.219519 -217.076932) (xy 41.149984 -217.061062)
			(xy 41.082664 -217.037505) (xy 41.018405 -217.00656) (xy 40.958014 -216.968614) (xy 40.902252 -216.924145)
			(xy 40.851819 -216.873712) (xy 40.80735 -216.81795) (xy 40.769404 -216.757559) (xy 40.738459 -216.6933)
			(xy 40.714902 -216.62598) (xy 40.699032 -216.556445) (xy 40.691046 -216.485571) (xy 40.07435 -216.485571)
			(xy 40.066364 -216.556445) (xy 40.050494 -216.62598) (xy 40.026937 -216.6933) (xy 39.995992 -216.757559)
			(xy 39.958046 -216.81795) (xy 39.913577 -216.873712) (xy 39.863144 -216.924145) (xy 39.807382 -216.968614)
			(xy 39.746991 -217.00656) (xy 39.682732 -217.037505) (xy 39.615412 -217.061062) (xy 39.545877 -217.076932)
			(xy 39.475003 -217.084918) (xy 39.403681 -217.084918) (xy 39.332807 -217.076932) (xy 39.263272 -217.061062)
			(xy 39.195952 -217.037505) (xy 39.131693 -217.00656) (xy 39.071302 -216.968614) (xy 39.01554 -216.924145)
			(xy 38.965107 -216.873712) (xy 38.920638 -216.81795) (xy 38.882692 -216.757559) (xy 38.851747 -216.6933)
			(xy 38.82819 -216.62598) (xy 38.81232 -216.556445) (xy 38.804334 -216.485571) (xy 36.357467 -216.485571)
			(xy 36.361593 -216.492234) (xy 36.400327 -216.570023) (xy 36.431719 -216.651055) (xy 36.4555 -216.734637)
			(xy 36.471468 -216.820057) (xy 36.479486 -216.906586) (xy 36.479988 -216.950036) (xy 36.479486 -216.993486)
			(xy 36.471468 -217.080015) (xy 36.4555 -217.165435) (xy 36.431719 -217.249017) (xy 36.400327 -217.330049)
			(xy 36.361593 -217.407838) (xy 36.315846 -217.481722) (xy 36.282007 -217.526531) (xy 47.842414 -217.526531)
			(xy 47.842414 -217.445421) (xy 47.850364 -217.364702) (xy 47.866187 -217.285151) (xy 47.889732 -217.207535)
			(xy 47.920771 -217.132599) (xy 47.959006 -217.061067) (xy 48.004068 -216.993627) (xy 48.055523 -216.930928)
			(xy 48.112876 -216.873575) (xy 48.175575 -216.82212) (xy 48.243015 -216.777058) (xy 48.314547 -216.738823)
			(xy 48.389483 -216.707784) (xy 48.467099 -216.684239) (xy 48.54665 -216.668416) (xy 48.627369 -216.660466)
			(xy 48.708479 -216.660466) (xy 48.789198 -216.668416) (xy 48.868749 -216.684239) (xy 48.946365 -216.707784)
			(xy 49.021301 -216.738823) (xy 49.092833 -216.777058) (xy 49.160273 -216.82212) (xy 49.222972 -216.873575)
			(xy 49.280325 -216.930928) (xy 49.33178 -216.993627) (xy 49.376842 -217.061067) (xy 49.415077 -217.132599)
			(xy 49.446116 -217.207535) (xy 49.469661 -217.285151) (xy 49.485484 -217.364702) (xy 49.493434 -217.445421)
			(xy 49.493932 -217.485976) (xy 49.493434 -217.526531) (xy 49.485484 -217.60725) (xy 49.469661 -217.686801)
			(xy 49.446116 -217.764417) (xy 49.415077 -217.839353) (xy 49.376842 -217.910885) (xy 49.33178 -217.978325)
			(xy 49.280325 -218.041024) (xy 49.222972 -218.098377) (xy 49.160273 -218.149832) (xy 49.092833 -218.194894)
			(xy 49.021301 -218.233129) (xy 48.946365 -218.264168) (xy 48.868749 -218.287713) (xy 48.789198 -218.303536)
			(xy 48.708479 -218.311486) (xy 48.627369 -218.311486) (xy 48.54665 -218.303536) (xy 48.467099 -218.287713)
			(xy 48.389483 -218.264168) (xy 48.314547 -218.233129) (xy 48.243015 -218.194894) (xy 48.175575 -218.149832)
			(xy 48.112876 -218.098377) (xy 48.055523 -218.041024) (xy 48.004068 -217.978325) (xy 47.959006 -217.910885)
			(xy 47.920771 -217.839353) (xy 47.889732 -217.764417) (xy 47.866187 -217.686801) (xy 47.850364 -217.60725)
			(xy 47.842414 -217.526531) (xy 36.282007 -217.526531) (xy 36.263477 -217.551069) (xy 36.204933 -217.615289)
			(xy 36.140713 -217.673833) (xy 36.071366 -217.726202) (xy 35.997482 -217.771949) (xy 35.919693 -217.810683)
			(xy 35.838661 -217.842075) (xy 35.755079 -217.865856) (xy 35.669659 -217.881824) (xy 35.58313 -217.889842)
			(xy 35.49623 -217.889842) (xy 35.409701 -217.881824) (xy 35.324281 -217.865856) (xy 35.240699 -217.842075)
			(xy 35.159667 -217.810683) (xy 35.081878 -217.771949) (xy 35.007994 -217.726202) (xy 34.938647 -217.673833)
			(xy 34.874427 -217.615289) (xy 34.815883 -217.551069) (xy 34.763514 -217.481722) (xy 34.717767 -217.407838)
			(xy 34.679033 -217.330049) (xy 34.647641 -217.249017) (xy 34.62386 -217.165435) (xy 34.607892 -217.080015)
			(xy 34.599874 -216.993486) (xy 31.399486 -216.993486) (xy 31.391468 -217.080015) (xy 31.3755 -217.165435)
			(xy 31.351719 -217.249017) (xy 31.320327 -217.330049) (xy 31.281593 -217.407838) (xy 31.235846 -217.481722)
			(xy 31.183477 -217.551069) (xy 31.124933 -217.615289) (xy 31.060713 -217.673833) (xy 30.991366 -217.726202)
			(xy 30.917482 -217.771949) (xy 30.839693 -217.810683) (xy 30.758661 -217.842075) (xy 30.675079 -217.865856)
			(xy 30.589659 -217.881824) (xy 30.50313 -217.889842) (xy 30.41623 -217.889842) (xy 30.329701 -217.881824)
			(xy 30.244281 -217.865856) (xy 30.160699 -217.842075) (xy 30.079667 -217.810683) (xy 30.001878 -217.771949)
			(xy 29.927994 -217.726202) (xy 29.858647 -217.673833) (xy 29.794427 -217.615289) (xy 29.735883 -217.551069)
			(xy 29.683514 -217.481722) (xy 29.637767 -217.407838) (xy 29.599033 -217.330049) (xy 29.567641 -217.249017)
			(xy 29.54386 -217.165435) (xy 29.527892 -217.080015) (xy 29.519874 -216.993486) (xy 28.753816 -216.993486)
			(xy 28.753816 -218.526715) (xy 38.804334 -218.526715) (xy 38.804334 -218.455393) (xy 38.81232 -218.384519)
			(xy 38.82819 -218.314984) (xy 38.851747 -218.247664) (xy 38.882692 -218.183405) (xy 38.920638 -218.123014)
			(xy 38.965107 -218.067252) (xy 39.01554 -218.016819) (xy 39.071302 -217.97235) (xy 39.131693 -217.934404)
			(xy 39.195952 -217.903459) (xy 39.263272 -217.879902) (xy 39.332807 -217.864032) (xy 39.403681 -217.856046)
			(xy 39.475003 -217.856046) (xy 39.545877 -217.864032) (xy 39.615412 -217.879902) (xy 39.682732 -217.903459)
			(xy 39.746991 -217.934404) (xy 39.807382 -217.97235) (xy 39.863144 -218.016819) (xy 39.913577 -218.067252)
			(xy 39.958046 -218.123014) (xy 39.995992 -218.183405) (xy 40.026937 -218.247664) (xy 40.050494 -218.314984)
			(xy 40.066364 -218.384519) (xy 40.07435 -218.455393) (xy 40.07485 -218.491054) (xy 40.07435 -218.526715)
			(xy 40.691046 -218.526715) (xy 40.691046 -218.455393) (xy 40.699032 -218.384519) (xy 40.714902 -218.314984)
			(xy 40.738459 -218.247664) (xy 40.769404 -218.183405) (xy 40.80735 -218.123014) (xy 40.851819 -218.067252)
			(xy 40.902252 -218.016819) (xy 40.958014 -217.97235) (xy 41.018405 -217.934404) (xy 41.082664 -217.903459)
			(xy 41.149984 -217.879902) (xy 41.219519 -217.864032) (xy 41.290393 -217.856046) (xy 41.361715 -217.856046)
			(xy 41.432589 -217.864032) (xy 41.502124 -217.879902) (xy 41.569444 -217.903459) (xy 41.633703 -217.934404)
			(xy 41.694094 -217.97235) (xy 41.749856 -218.016819) (xy 41.800289 -218.067252) (xy 41.844758 -218.123014)
			(xy 41.882704 -218.183405) (xy 41.913649 -218.247664) (xy 41.937206 -218.314984) (xy 41.953076 -218.384519)
			(xy 41.961062 -218.455393) (xy 41.961562 -218.491054) (xy 41.961062 -218.526715) (xy 42.932088 -218.526715)
			(xy 42.932088 -218.455393) (xy 42.940074 -218.384519) (xy 42.955944 -218.314984) (xy 42.979501 -218.247664)
			(xy 43.010446 -218.183405) (xy 43.048392 -218.123014) (xy 43.092861 -218.067252) (xy 43.143294 -218.016819)
			(xy 43.199056 -217.97235) (xy 43.259447 -217.934404) (xy 43.323706 -217.903459) (xy 43.391026 -217.879902)
			(xy 43.460561 -217.864032) (xy 43.531435 -217.856046) (xy 43.602757 -217.856046) (xy 43.673631 -217.864032)
			(xy 43.743166 -217.879902) (xy 43.810486 -217.903459) (xy 43.874745 -217.934404) (xy 43.935136 -217.97235)
			(xy 43.990898 -218.016819) (xy 44.041331 -218.067252) (xy 44.0858 -218.123014) (xy 44.123746 -218.183405)
			(xy 44.154691 -218.247664) (xy 44.178248 -218.314984) (xy 44.194118 -218.384519) (xy 44.202104 -218.455393)
			(xy 44.202604 -218.491054) (xy 44.202104 -218.526715) (xy 44.836072 -218.526715) (xy 44.836072 -218.455393)
			(xy 44.844058 -218.384519) (xy 44.859928 -218.314984) (xy 44.883485 -218.247664) (xy 44.91443 -218.183405)
			(xy 44.952376 -218.123014) (xy 44.996845 -218.067252) (xy 45.047278 -218.016819) (xy 45.10304 -217.97235)
			(xy 45.163431 -217.934404) (xy 45.22769 -217.903459) (xy 45.29501 -217.879902) (xy 45.364545 -217.864032)
			(xy 45.435419 -217.856046) (xy 45.506741 -217.856046) (xy 45.577615 -217.864032) (xy 45.64715 -217.879902)
			(xy 45.71447 -217.903459) (xy 45.778729 -217.934404) (xy 45.83912 -217.97235) (xy 45.894882 -218.016819)
			(xy 45.945315 -218.067252) (xy 45.989784 -218.123014) (xy 46.02773 -218.183405) (xy 46.058675 -218.247664)
			(xy 46.082232 -218.314984) (xy 46.098102 -218.384519) (xy 46.106088 -218.455393) (xy 46.106588 -218.491054)
			(xy 46.106088 -218.526715) (xy 46.098102 -218.597589) (xy 46.082232 -218.667124) (xy 46.058675 -218.734444)
			(xy 46.02773 -218.798703) (xy 45.989784 -218.859094) (xy 45.945315 -218.914856) (xy 45.894882 -218.965289)
			(xy 45.83912 -219.009758) (xy 45.778729 -219.047704) (xy 45.71447 -219.078649) (xy 45.64715 -219.102206)
			(xy 45.577615 -219.118076) (xy 45.506741 -219.126062) (xy 45.435419 -219.126062) (xy 45.364545 -219.118076)
			(xy 45.29501 -219.102206) (xy 45.22769 -219.078649) (xy 45.163431 -219.047704) (xy 45.10304 -219.009758)
			(xy 45.047278 -218.965289) (xy 44.996845 -218.914856) (xy 44.952376 -218.859094) (xy 44.91443 -218.798703)
			(xy 44.883485 -218.734444) (xy 44.859928 -218.667124) (xy 44.844058 -218.597589) (xy 44.836072 -218.526715)
			(xy 44.202104 -218.526715) (xy 44.194118 -218.597589) (xy 44.178248 -218.667124) (xy 44.154691 -218.734444)
			(xy 44.123746 -218.798703) (xy 44.0858 -218.859094) (xy 44.041331 -218.914856) (xy 43.990898 -218.965289)
			(xy 43.935136 -219.009758) (xy 43.874745 -219.047704) (xy 43.810486 -219.078649) (xy 43.743166 -219.102206)
			(xy 43.673631 -219.118076) (xy 43.602757 -219.126062) (xy 43.531435 -219.126062) (xy 43.460561 -219.118076)
			(xy 43.391026 -219.102206) (xy 43.323706 -219.078649) (xy 43.259447 -219.047704) (xy 43.199056 -219.009758)
			(xy 43.143294 -218.965289) (xy 43.092861 -218.914856) (xy 43.048392 -218.859094) (xy 43.010446 -218.798703)
			(xy 42.979501 -218.734444) (xy 42.955944 -218.667124) (xy 42.940074 -218.597589) (xy 42.932088 -218.526715)
			(xy 41.961062 -218.526715) (xy 41.953076 -218.597589) (xy 41.937206 -218.667124) (xy 41.913649 -218.734444)
			(xy 41.882704 -218.798703) (xy 41.844758 -218.859094) (xy 41.800289 -218.914856) (xy 41.749856 -218.965289)
			(xy 41.694094 -219.009758) (xy 41.633703 -219.047704) (xy 41.569444 -219.078649) (xy 41.502124 -219.102206)
			(xy 41.432589 -219.118076) (xy 41.361715 -219.126062) (xy 41.290393 -219.126062) (xy 41.219519 -219.118076)
			(xy 41.149984 -219.102206) (xy 41.082664 -219.078649) (xy 41.018405 -219.047704) (xy 40.958014 -219.009758)
			(xy 40.902252 -218.965289) (xy 40.851819 -218.914856) (xy 40.80735 -218.859094) (xy 40.769404 -218.798703)
			(xy 40.738459 -218.734444) (xy 40.714902 -218.667124) (xy 40.699032 -218.597589) (xy 40.691046 -218.526715)
			(xy 40.07435 -218.526715) (xy 40.066364 -218.597589) (xy 40.050494 -218.667124) (xy 40.026937 -218.734444)
			(xy 39.995992 -218.798703) (xy 39.958046 -218.859094) (xy 39.913577 -218.914856) (xy 39.863144 -218.965289)
			(xy 39.807382 -219.009758) (xy 39.746991 -219.047704) (xy 39.682732 -219.078649) (xy 39.615412 -219.102206)
			(xy 39.545877 -219.118076) (xy 39.475003 -219.126062) (xy 39.403681 -219.126062) (xy 39.332807 -219.118076)
			(xy 39.263272 -219.102206) (xy 39.195952 -219.078649) (xy 39.131693 -219.047704) (xy 39.071302 -219.009758)
			(xy 39.01554 -218.965289) (xy 38.965107 -218.914856) (xy 38.920638 -218.859094) (xy 38.882692 -218.798703)
			(xy 38.851747 -218.734444) (xy 38.82819 -218.667124) (xy 38.81232 -218.597589) (xy 38.804334 -218.526715)
			(xy 28.753816 -218.526715) (xy 28.753816 -219.533486) (xy 29.519874 -219.533486) (xy 29.519874 -219.446586)
			(xy 29.527892 -219.360057) (xy 29.54386 -219.274637) (xy 29.567641 -219.191055) (xy 29.599033 -219.110023)
			(xy 29.637767 -219.032234) (xy 29.683514 -218.95835) (xy 29.735883 -218.889003) (xy 29.794427 -218.824783)
			(xy 29.858647 -218.766239) (xy 29.927994 -218.71387) (xy 30.001878 -218.668123) (xy 30.079667 -218.629389)
			(xy 30.160699 -218.597997) (xy 30.244281 -218.574216) (xy 30.329701 -218.558248) (xy 30.41623 -218.55023)
			(xy 30.50313 -218.55023) (xy 30.589659 -218.558248) (xy 30.675079 -218.574216) (xy 30.758661 -218.597997)
			(xy 30.839693 -218.629389) (xy 30.917482 -218.668123) (xy 30.991366 -218.71387) (xy 31.060713 -218.766239)
			(xy 31.124933 -218.824783) (xy 31.183477 -218.889003) (xy 31.235846 -218.95835) (xy 31.281593 -219.032234)
			(xy 31.320327 -219.110023) (xy 31.351719 -219.191055) (xy 31.3755 -219.274637) (xy 31.391468 -219.360057)
			(xy 31.399486 -219.446586) (xy 31.399988 -219.490036) (xy 31.399486 -219.533486) (xy 34.599874 -219.533486)
			(xy 34.599874 -219.446586) (xy 34.607892 -219.360057) (xy 34.62386 -219.274637) (xy 34.647641 -219.191055)
			(xy 34.679033 -219.110023) (xy 34.717767 -219.032234) (xy 34.763514 -218.95835) (xy 34.815883 -218.889003)
			(xy 34.874427 -218.824783) (xy 34.938647 -218.766239) (xy 35.007994 -218.71387) (xy 35.081878 -218.668123)
			(xy 35.159667 -218.629389) (xy 35.240699 -218.597997) (xy 35.324281 -218.574216) (xy 35.409701 -218.558248)
			(xy 35.49623 -218.55023) (xy 35.58313 -218.55023) (xy 35.669659 -218.558248) (xy 35.755079 -218.574216)
			(xy 35.838661 -218.597997) (xy 35.919693 -218.629389) (xy 35.997482 -218.668123) (xy 36.071366 -218.71387)
			(xy 36.140713 -218.766239) (xy 36.204933 -218.824783) (xy 36.263477 -218.889003) (xy 36.315846 -218.95835)
			(xy 36.361593 -219.032234) (xy 36.400327 -219.110023) (xy 36.431719 -219.191055) (xy 36.4555 -219.274637)
			(xy 36.471468 -219.360057) (xy 36.479486 -219.446586) (xy 36.479988 -219.490036) (xy 36.479486 -219.533486)
			(xy 36.471468 -219.620015) (xy 36.4555 -219.705435) (xy 36.431719 -219.789017) (xy 36.400327 -219.870049)
			(xy 36.361593 -219.947838) (xy 36.315846 -220.021722) (xy 36.263477 -220.091069) (xy 36.204933 -220.155289)
			(xy 36.140713 -220.213833) (xy 36.071366 -220.266202) (xy 35.997482 -220.311949) (xy 35.919693 -220.350683)
			(xy 35.838661 -220.382075) (xy 35.755079 -220.405856) (xy 35.669659 -220.421824) (xy 35.58313 -220.429842)
			(xy 35.49623 -220.429842) (xy 35.409701 -220.421824) (xy 35.324281 -220.405856) (xy 35.240699 -220.382075)
			(xy 35.159667 -220.350683) (xy 35.081878 -220.311949) (xy 35.007994 -220.266202) (xy 34.938647 -220.213833)
			(xy 34.874427 -220.155289) (xy 34.815883 -220.091069) (xy 34.763514 -220.021722) (xy 34.717767 -219.947838)
			(xy 34.679033 -219.870049) (xy 34.647641 -219.789017) (xy 34.62386 -219.705435) (xy 34.607892 -219.620015)
			(xy 34.599874 -219.533486) (xy 31.399486 -219.533486) (xy 31.391468 -219.620015) (xy 31.3755 -219.705435)
			(xy 31.351719 -219.789017) (xy 31.320327 -219.870049) (xy 31.281593 -219.947838) (xy 31.235846 -220.021722)
			(xy 31.183477 -220.091069) (xy 31.124933 -220.155289) (xy 31.060713 -220.213833) (xy 30.991366 -220.266202)
			(xy 30.917482 -220.311949) (xy 30.839693 -220.350683) (xy 30.758661 -220.382075) (xy 30.675079 -220.405856)
			(xy 30.589659 -220.421824) (xy 30.50313 -220.429842) (xy 30.41623 -220.429842) (xy 30.329701 -220.421824)
			(xy 30.244281 -220.405856) (xy 30.160699 -220.382075) (xy 30.079667 -220.350683) (xy 30.001878 -220.311949)
			(xy 29.927994 -220.266202) (xy 29.858647 -220.213833) (xy 29.794427 -220.155289) (xy 29.735883 -220.091069)
			(xy 29.683514 -220.021722) (xy 29.637767 -219.947838) (xy 29.599033 -219.870049) (xy 29.567641 -219.789017)
			(xy 29.54386 -219.705435) (xy 29.527892 -219.620015) (xy 29.519874 -219.533486) (xy 28.753816 -219.533486)
			(xy 28.753816 -220.436541) (xy 38.804334 -220.436541) (xy 38.804334 -220.365219) (xy 38.81232 -220.294345)
			(xy 38.82819 -220.22481) (xy 38.851747 -220.15749) (xy 38.882692 -220.093231) (xy 38.920638 -220.03284)
			(xy 38.965107 -219.977078) (xy 39.01554 -219.926645) (xy 39.071302 -219.882176) (xy 39.131693 -219.84423)
			(xy 39.195952 -219.813285) (xy 39.263272 -219.789728) (xy 39.332807 -219.773858) (xy 39.403681 -219.765872)
			(xy 39.475003 -219.765872) (xy 39.545877 -219.773858) (xy 39.615412 -219.789728) (xy 39.682732 -219.813285)
			(xy 39.746991 -219.84423) (xy 39.807382 -219.882176) (xy 39.863144 -219.926645) (xy 39.913577 -219.977078)
			(xy 39.958046 -220.03284) (xy 39.995992 -220.093231) (xy 40.026937 -220.15749) (xy 40.050494 -220.22481)
			(xy 40.066364 -220.294345) (xy 40.07435 -220.365219) (xy 40.07485 -220.40088) (xy 40.07435 -220.436541)
			(xy 40.691046 -220.436541) (xy 40.691046 -220.365219) (xy 40.699032 -220.294345) (xy 40.714902 -220.22481)
			(xy 40.738459 -220.15749) (xy 40.769404 -220.093231) (xy 40.80735 -220.03284) (xy 40.851819 -219.977078)
			(xy 40.902252 -219.926645) (xy 40.958014 -219.882176) (xy 41.018405 -219.84423) (xy 41.082664 -219.813285)
			(xy 41.149984 -219.789728) (xy 41.219519 -219.773858) (xy 41.290393 -219.765872) (xy 41.361715 -219.765872)
			(xy 41.432589 -219.773858) (xy 41.502124 -219.789728) (xy 41.569444 -219.813285) (xy 41.633703 -219.84423)
			(xy 41.694094 -219.882176) (xy 41.749856 -219.926645) (xy 41.800289 -219.977078) (xy 41.844758 -220.03284)
			(xy 41.882704 -220.093231) (xy 41.913649 -220.15749) (xy 41.937206 -220.22481) (xy 41.953076 -220.294345)
			(xy 41.961062 -220.365219) (xy 41.961562 -220.40088) (xy 41.961062 -220.436541) (xy 42.932088 -220.436541)
			(xy 42.932088 -220.365219) (xy 42.940074 -220.294345) (xy 42.955944 -220.22481) (xy 42.979501 -220.15749)
			(xy 43.010446 -220.093231) (xy 43.048392 -220.03284) (xy 43.092861 -219.977078) (xy 43.143294 -219.926645)
			(xy 43.199056 -219.882176) (xy 43.259447 -219.84423) (xy 43.323706 -219.813285) (xy 43.391026 -219.789728)
			(xy 43.460561 -219.773858) (xy 43.531435 -219.765872) (xy 43.602757 -219.765872) (xy 43.673631 -219.773858)
			(xy 43.743166 -219.789728) (xy 43.810486 -219.813285) (xy 43.874745 -219.84423) (xy 43.935136 -219.882176)
			(xy 43.990898 -219.926645) (xy 44.041331 -219.977078) (xy 44.0858 -220.03284) (xy 44.123746 -220.093231)
			(xy 44.154691 -220.15749) (xy 44.178248 -220.22481) (xy 44.194118 -220.294345) (xy 44.202104 -220.365219)
			(xy 44.202604 -220.40088) (xy 44.202104 -220.436541) (xy 44.836072 -220.436541) (xy 44.836072 -220.365219)
			(xy 44.844058 -220.294345) (xy 44.859928 -220.22481) (xy 44.883485 -220.15749) (xy 44.91443 -220.093231)
			(xy 44.952376 -220.03284) (xy 44.996845 -219.977078) (xy 45.047278 -219.926645) (xy 45.10304 -219.882176)
			(xy 45.163431 -219.84423) (xy 45.22769 -219.813285) (xy 45.29501 -219.789728) (xy 45.364545 -219.773858)
			(xy 45.435419 -219.765872) (xy 45.506741 -219.765872) (xy 45.577615 -219.773858) (xy 45.64715 -219.789728)
			(xy 45.71447 -219.813285) (xy 45.778729 -219.84423) (xy 45.83912 -219.882176) (xy 45.894882 -219.926645)
			(xy 45.945315 -219.977078) (xy 45.984108 -220.025722) (xy 68.62572 -220.025722) (xy 68.62572 -219.037916)
			(xy 68.626214 -219.006776) (xy 68.633811 -218.944961) (xy 68.648903 -218.884537) (xy 68.671266 -218.82641)
			(xy 68.700564 -218.771451) (xy 68.736358 -218.720485) (xy 68.778111 -218.674273) (xy 68.825198 -218.63351)
			(xy 68.876913 -218.598807) (xy 68.932482 -218.570682) (xy 68.99107 -218.549559) (xy 69.051801 -218.535752)
			(xy 69.113763 -218.52947) (xy 69.176029 -218.530807) (xy 69.237665 -218.539742) (xy 69.297747 -218.556141)
			(xy 69.355375 -218.579759) (xy 69.409686 -218.610242) (xy 69.459864 -218.647133) (xy 69.505159 -218.689878)
			(xy 69.525388 -218.713558) (xy 69.539442 -218.729955) (xy 69.572203 -218.758092) (xy 69.609251 -218.780284)
			(xy 69.649519 -218.79589) (xy 69.691845 -218.804461) (xy 69.735012 -218.805751) (xy 69.777774 -218.799722)
			(xy 69.818902 -218.786548) (xy 69.857208 -218.766608) (xy 69.891591 -218.740477) (xy 69.906642 -218.724988)
			(xy 69.928973 -218.701811) (xy 69.978494 -218.660701) (xy 70.032807 -218.626168) (xy 70.091044 -218.598766)
			(xy 70.152273 -218.578931) (xy 70.215516 -218.566983) (xy 70.27976 -218.56311) (xy 70.34398 -218.567377)
			(xy 70.407149 -218.579713) (xy 70.468255 -218.599922) (xy 70.526322 -218.627681) (xy 70.580423 -218.662546)
			(xy 70.62969 -218.70396) (xy 70.651878 -218.727274) (xy 70.667409 -218.743364) (xy 70.703043 -218.770379)
			(xy 70.742852 -218.790746) (xy 70.78561 -218.803836) (xy 70.829998 -218.809246) (xy 70.874648 -218.80681)
			(xy 70.918184 -218.796602) (xy 70.959263 -218.778937) (xy 70.99662 -218.75436) (xy 71.029103 -218.723628)
			(xy 71.042784 -218.705938) (xy 71.062341 -218.680247) (xy 71.106991 -218.633606) (xy 71.157188 -218.592994)
			(xy 71.212124 -218.559066) (xy 71.270914 -218.532368) (xy 71.332612 -218.513329) (xy 71.396224 -218.502257)
			(xy 71.460726 -218.49933) (xy 71.52508 -218.504594) (xy 71.588248 -218.517965) (xy 71.649215 -218.539228)
			(xy 71.706999 -218.56804) (xy 71.760669 -218.603938) (xy 71.80936 -218.646343) (xy 71.8312 -218.670124)
			(xy 71.847447 -218.687525) (xy 71.885195 -218.716525) (xy 71.92768 -218.737995) (xy 71.973418 -218.751184)
			(xy 72.020811 -218.755632) (xy 72.068204 -218.751184) (xy 72.113942 -218.737995) (xy 72.156427 -218.716525)
			(xy 72.194175 -218.687525) (xy 72.210422 -218.670124) (xy 72.232281 -218.646319) (xy 72.281025 -218.60388)
			(xy 72.334754 -218.56796) (xy 72.392602 -218.539138) (xy 72.453635 -218.517879) (xy 72.516871 -218.504526)
			(xy 72.581289 -218.499295) (xy 72.64585 -218.502268) (xy 72.709515 -218.513399) (xy 72.771255 -218.532508)
			(xy 72.830076 -218.559286) (xy 72.88503 -218.593303) (xy 72.93523 -218.63401) (xy 72.979867 -218.680749)
			(xy 73.018221 -218.732769) (xy 73.049673 -218.789229) (xy 73.073718 -218.84922) (xy 73.089966 -218.911774)
			(xy 73.098157 -218.975883) (xy 73.09866 -219.008198) (xy 73.09866 -220.025722) (xy 73.098128 -220.058457)
			(xy 73.089696 -220.123381) (xy 73.073 -220.186686) (xy 73.048317 -220.247325) (xy 73.016054 -220.304293)
			(xy 72.996806 -220.330776) (xy 72.97166 -220.364558) (xy 72.97166 -220.381576) (xy 72.956166 -220.381576)
			(xy 72.920352 -220.412056) (xy 72.895175 -220.432909) (xy 72.840443 -220.46866) (xy 72.781578 -220.497099)
			(xy 72.719553 -220.517754) (xy 72.655391 -220.530285) (xy 72.590152 -220.534485) (xy 72.524913 -220.530285)
			(xy 72.460751 -220.517754) (xy 72.398726 -220.497099) (xy 72.339861 -220.46866) (xy 72.285129 -220.432909)
			(xy 72.259952 -220.412056) (xy 72.224138 -220.381576) (xy 72.208644 -220.381576) (xy 72.208644 -220.364558)
			(xy 72.183498 -220.330776) (xy 72.169743 -220.311968) (xy 72.145318 -220.272284) (xy 72.13473 -220.251528)
			(xy 72.127372 -220.23761) (xy 72.107 -220.21362) (xy 72.081369 -220.195356) (xy 72.052043 -220.183932)
			(xy 72.020811 -220.180045) (xy 71.989579 -220.183932) (xy 71.960253 -220.195356) (xy 71.934622 -220.21362)
			(xy 71.91425 -220.23761) (xy 71.906892 -220.251528) (xy 71.896329 -220.272298) (xy 71.8719 -220.311983)
			(xy 71.858124 -220.330776) (xy 71.832724 -220.364558) (xy 71.832724 -220.381576) (xy 71.817484 -220.381576)
			(xy 71.78167 -220.412056) (xy 71.756493 -220.432909) (xy 71.701761 -220.46866) (xy 71.642896 -220.497099)
			(xy 71.580871 -220.517754) (xy 71.516709 -220.530285) (xy 71.45147 -220.534485) (xy 71.386231 -220.530285)
			(xy 71.322069 -220.517754) (xy 71.260044 -220.497099) (xy 71.201179 -220.46866) (xy 71.146447 -220.432909)
			(xy 71.12127 -220.412056) (xy 71.085456 -220.381576) (xy 71.070216 -220.381576) (xy 71.070216 -220.364558)
			(xy 71.044816 -220.330776) (xy 71.026177 -220.30514) (xy 70.994715 -220.250116) (xy 70.982078 -220.221048)
			(xy 70.97521 -220.205891) (xy 70.954957 -220.179505) (xy 70.928566 -220.159259) (xy 70.897835 -220.146531)
			(xy 70.864857 -220.14219) (xy 70.831879 -220.146531) (xy 70.801148 -220.159259) (xy 70.774757 -220.179505)
			(xy 70.754504 -220.205891) (xy 70.747636 -220.221048) (xy 70.734999 -220.250116) (xy 70.703538 -220.305141)
			(xy 70.684898 -220.330776) (xy 70.659752 -220.364558) (xy 70.659752 -220.381576) (xy 70.644258 -220.381576)
			(xy 70.608444 -220.412056) (xy 70.583267 -220.432909) (xy 70.528535 -220.46866) (xy 70.46967 -220.497099)
			(xy 70.407645 -220.517754) (xy 70.343483 -220.530285) (xy 70.278244 -220.534485) (xy 70.213005 -220.530285)
			(xy 70.148843 -220.517754) (xy 70.086818 -220.497099) (xy 70.027953 -220.46866) (xy 69.973221 -220.432909)
			(xy 69.948044 -220.412056) (xy 69.91223 -220.381576) (xy 69.896736 -220.381576) (xy 69.896736 -220.364558)
			(xy 69.87159 -220.330776) (xy 69.857064 -220.310945) (xy 69.831491 -220.268961) (xy 69.820536 -220.246956)
			(xy 69.813233 -220.232865) (xy 69.792865 -220.208539) (xy 69.767118 -220.19) (xy 69.737589 -220.178395)
			(xy 69.706109 -220.174446) (xy 69.674629 -220.178395) (xy 69.6451 -220.19) (xy 69.619353 -220.208539)
			(xy 69.598985 -220.232865) (xy 69.591682 -220.246956) (xy 69.58071 -220.268952) (xy 69.555139 -220.310935)
			(xy 69.540628 -220.330776) (xy 69.515228 -220.364558) (xy 69.515228 -220.381576) (xy 69.499988 -220.381576)
			(xy 69.464174 -220.412056) (xy 69.438997 -220.432909) (xy 69.384265 -220.46866) (xy 69.3254 -220.497099)
			(xy 69.263375 -220.517754) (xy 69.199213 -220.530285) (xy 69.133974 -220.534485) (xy 69.068735 -220.530285)
			(xy 69.004573 -220.517754) (xy 68.942548 -220.497099) (xy 68.883683 -220.46866) (xy 68.828951 -220.432909)
			(xy 68.803774 -220.412056) (xy 68.76796 -220.381576) (xy 68.75272 -220.381576) (xy 68.75272 -220.364558)
			(xy 68.72732 -220.330776) (xy 68.708064 -220.304306) (xy 68.67584 -220.247329) (xy 68.651206 -220.186683)
			(xy 68.634569 -220.123374) (xy 68.626205 -220.058452) (xy 68.62572 -220.025722) (xy 45.984108 -220.025722)
			(xy 45.989784 -220.03284) (xy 46.02773 -220.093231) (xy 46.058675 -220.15749) (xy 46.082232 -220.22481)
			(xy 46.098102 -220.294345) (xy 46.106088 -220.365219) (xy 46.106588 -220.40088) (xy 46.106088 -220.436541)
			(xy 46.098102 -220.507415) (xy 46.082232 -220.57695) (xy 46.058675 -220.64427) (xy 46.02773 -220.708529)
			(xy 45.989784 -220.76892) (xy 45.945315 -220.824682) (xy 45.894882 -220.875115) (xy 45.83912 -220.919584)
			(xy 45.778729 -220.95753) (xy 45.71447 -220.988475) (xy 45.64715 -221.012032) (xy 45.577615 -221.027902)
			(xy 45.506741 -221.035888) (xy 45.435419 -221.035888) (xy 45.364545 -221.027902) (xy 45.29501 -221.012032)
			(xy 45.22769 -220.988475) (xy 45.163431 -220.95753) (xy 45.10304 -220.919584) (xy 45.047278 -220.875115)
			(xy 44.996845 -220.824682) (xy 44.952376 -220.76892) (xy 44.91443 -220.708529) (xy 44.883485 -220.64427)
			(xy 44.859928 -220.57695) (xy 44.844058 -220.507415) (xy 44.836072 -220.436541) (xy 44.202104 -220.436541)
			(xy 44.194118 -220.507415) (xy 44.178248 -220.57695) (xy 44.154691 -220.64427) (xy 44.123746 -220.708529)
			(xy 44.0858 -220.76892) (xy 44.041331 -220.824682) (xy 43.990898 -220.875115) (xy 43.935136 -220.919584)
			(xy 43.874745 -220.95753) (xy 43.810486 -220.988475) (xy 43.743166 -221.012032) (xy 43.673631 -221.027902)
			(xy 43.602757 -221.035888) (xy 43.531435 -221.035888) (xy 43.460561 -221.027902) (xy 43.391026 -221.012032)
			(xy 43.323706 -220.988475) (xy 43.259447 -220.95753) (xy 43.199056 -220.919584) (xy 43.143294 -220.875115)
			(xy 43.092861 -220.824682) (xy 43.048392 -220.76892) (xy 43.010446 -220.708529) (xy 42.979501 -220.64427)
			(xy 42.955944 -220.57695) (xy 42.940074 -220.507415) (xy 42.932088 -220.436541) (xy 41.961062 -220.436541)
			(xy 41.953076 -220.507415) (xy 41.937206 -220.57695) (xy 41.913649 -220.64427) (xy 41.882704 -220.708529)
			(xy 41.844758 -220.76892) (xy 41.800289 -220.824682) (xy 41.749856 -220.875115) (xy 41.694094 -220.919584)
			(xy 41.633703 -220.95753) (xy 41.569444 -220.988475) (xy 41.502124 -221.012032) (xy 41.432589 -221.027902)
			(xy 41.361715 -221.035888) (xy 41.290393 -221.035888) (xy 41.219519 -221.027902) (xy 41.149984 -221.012032)
			(xy 41.082664 -220.988475) (xy 41.018405 -220.95753) (xy 40.958014 -220.919584) (xy 40.902252 -220.875115)
			(xy 40.851819 -220.824682) (xy 40.80735 -220.76892) (xy 40.769404 -220.708529) (xy 40.738459 -220.64427)
			(xy 40.714902 -220.57695) (xy 40.699032 -220.507415) (xy 40.691046 -220.436541) (xy 40.07435 -220.436541)
			(xy 40.066364 -220.507415) (xy 40.050494 -220.57695) (xy 40.026937 -220.64427) (xy 39.995992 -220.708529)
			(xy 39.958046 -220.76892) (xy 39.913577 -220.824682) (xy 39.863144 -220.875115) (xy 39.807382 -220.919584)
			(xy 39.746991 -220.95753) (xy 39.682732 -220.988475) (xy 39.615412 -221.012032) (xy 39.545877 -221.027902)
			(xy 39.475003 -221.035888) (xy 39.403681 -221.035888) (xy 39.332807 -221.027902) (xy 39.263272 -221.012032)
			(xy 39.195952 -220.988475) (xy 39.131693 -220.95753) (xy 39.071302 -220.919584) (xy 39.01554 -220.875115)
			(xy 38.965107 -220.824682) (xy 38.920638 -220.76892) (xy 38.882692 -220.708529) (xy 38.851747 -220.64427)
			(xy 38.82819 -220.57695) (xy 38.81232 -220.507415) (xy 38.804334 -220.436541) (xy 28.753816 -220.436541)
			(xy 28.753816 -222.073486) (xy 29.519874 -222.073486) (xy 29.519874 -221.986586) (xy 29.527892 -221.900057)
			(xy 29.54386 -221.814637) (xy 29.567641 -221.731055) (xy 29.599033 -221.650023) (xy 29.637767 -221.572234)
			(xy 29.683514 -221.49835) (xy 29.735883 -221.429003) (xy 29.794427 -221.364783) (xy 29.858647 -221.306239)
			(xy 29.927994 -221.25387) (xy 30.001878 -221.208123) (xy 30.079667 -221.169389) (xy 30.160699 -221.137997)
			(xy 30.244281 -221.114216) (xy 30.329701 -221.098248) (xy 30.41623 -221.09023) (xy 30.50313 -221.09023)
			(xy 30.589659 -221.098248) (xy 30.675079 -221.114216) (xy 30.758661 -221.137997) (xy 30.839693 -221.169389)
			(xy 30.917482 -221.208123) (xy 30.991366 -221.25387) (xy 31.060713 -221.306239) (xy 31.124933 -221.364783)
			(xy 31.183477 -221.429003) (xy 31.235846 -221.49835) (xy 31.281593 -221.572234) (xy 31.320327 -221.650023)
			(xy 31.351719 -221.731055) (xy 31.3755 -221.814637) (xy 31.391468 -221.900057) (xy 31.399486 -221.986586)
			(xy 31.399988 -222.030036) (xy 31.399486 -222.073486) (xy 34.599874 -222.073486) (xy 34.599874 -221.986586)
			(xy 34.607892 -221.900057) (xy 34.62386 -221.814637) (xy 34.647641 -221.731055) (xy 34.679033 -221.650023)
			(xy 34.717767 -221.572234) (xy 34.763514 -221.49835) (xy 34.815883 -221.429003) (xy 34.874427 -221.364783)
			(xy 34.938647 -221.306239) (xy 35.007994 -221.25387) (xy 35.081878 -221.208123) (xy 35.159667 -221.169389)
			(xy 35.240699 -221.137997) (xy 35.324281 -221.114216) (xy 35.409701 -221.098248) (xy 35.49623 -221.09023)
			(xy 35.58313 -221.09023) (xy 35.669659 -221.098248) (xy 35.755079 -221.114216) (xy 35.838661 -221.137997)
			(xy 35.919693 -221.169389) (xy 35.997482 -221.208123) (xy 36.071366 -221.25387) (xy 36.140713 -221.306239)
			(xy 36.204933 -221.364783) (xy 36.263477 -221.429003) (xy 36.315846 -221.49835) (xy 36.361593 -221.572234)
			(xy 36.400327 -221.650023) (xy 36.431719 -221.731055) (xy 36.4555 -221.814637) (xy 36.471468 -221.900057)
			(xy 36.479486 -221.986586) (xy 36.479988 -222.030036) (xy 36.479486 -222.073486) (xy 36.471468 -222.160015)
			(xy 36.4555 -222.245435) (xy 36.431719 -222.329017) (xy 36.400327 -222.410049) (xy 36.361593 -222.487838)
			(xy 36.315846 -222.561722) (xy 36.263477 -222.631069) (xy 36.204933 -222.695289) (xy 36.140713 -222.753833)
			(xy 36.071366 -222.806202) (xy 35.997482 -222.851949) (xy 35.919693 -222.890683) (xy 35.838661 -222.922075)
			(xy 35.755079 -222.945856) (xy 35.669659 -222.961824) (xy 35.58313 -222.969842) (xy 35.49623 -222.969842)
			(xy 35.409701 -222.961824) (xy 35.324281 -222.945856) (xy 35.240699 -222.922075) (xy 35.159667 -222.890683)
			(xy 35.081878 -222.851949) (xy 35.007994 -222.806202) (xy 34.938647 -222.753833) (xy 34.874427 -222.695289)
			(xy 34.815883 -222.631069) (xy 34.763514 -222.561722) (xy 34.717767 -222.487838) (xy 34.679033 -222.410049)
			(xy 34.647641 -222.329017) (xy 34.62386 -222.245435) (xy 34.607892 -222.160015) (xy 34.599874 -222.073486)
			(xy 31.399486 -222.073486) (xy 31.391468 -222.160015) (xy 31.3755 -222.245435) (xy 31.351719 -222.329017)
			(xy 31.320327 -222.410049) (xy 31.281593 -222.487838) (xy 31.235846 -222.561722) (xy 31.183477 -222.631069)
			(xy 31.124933 -222.695289) (xy 31.060713 -222.753833) (xy 30.991366 -222.806202) (xy 30.917482 -222.851949)
			(xy 30.839693 -222.890683) (xy 30.758661 -222.922075) (xy 30.675079 -222.945856) (xy 30.589659 -222.961824)
			(xy 30.50313 -222.969842) (xy 30.41623 -222.969842) (xy 30.329701 -222.961824) (xy 30.244281 -222.945856)
			(xy 30.160699 -222.922075) (xy 30.079667 -222.890683) (xy 30.001878 -222.851949) (xy 29.927994 -222.806202)
			(xy 29.858647 -222.753833) (xy 29.794427 -222.695289) (xy 29.735883 -222.631069) (xy 29.683514 -222.561722)
			(xy 29.637767 -222.487838) (xy 29.599033 -222.410049) (xy 29.567641 -222.329017) (xy 29.54386 -222.245435)
			(xy 29.527892 -222.160015) (xy 29.519874 -222.073486) (xy 28.753816 -222.073486) (xy 28.753816 -222.180404)
			(xy 28.942538 -222.369126) (xy 28.942538 -224.613486) (xy 29.519874 -224.613486) (xy 29.519874 -224.526586)
			(xy 29.527892 -224.440057) (xy 29.54386 -224.354637) (xy 29.567641 -224.271055) (xy 29.599033 -224.190023)
			(xy 29.637767 -224.112234) (xy 29.683514 -224.03835) (xy 29.735883 -223.969003) (xy 29.794427 -223.904783)
			(xy 29.858647 -223.846239) (xy 29.927994 -223.79387) (xy 30.001878 -223.748123) (xy 30.079667 -223.709389)
			(xy 30.160699 -223.677997) (xy 30.244281 -223.654216) (xy 30.329701 -223.638248) (xy 30.41623 -223.63023)
			(xy 30.50313 -223.63023) (xy 30.589659 -223.638248) (xy 30.675079 -223.654216) (xy 30.758661 -223.677997)
			(xy 30.839693 -223.709389) (xy 30.917482 -223.748123) (xy 30.991366 -223.79387) (xy 31.060713 -223.846239)
			(xy 31.124933 -223.904783) (xy 31.183477 -223.969003) (xy 31.235846 -224.03835) (xy 31.281593 -224.112234)
			(xy 31.320327 -224.190023) (xy 31.351719 -224.271055) (xy 31.3755 -224.354637) (xy 31.391468 -224.440057)
			(xy 31.399486 -224.526586) (xy 31.399988 -224.570036) (xy 31.399486 -224.613486) (xy 34.599874 -224.613486)
			(xy 34.599874 -224.526586) (xy 34.607892 -224.440057) (xy 34.62386 -224.354637) (xy 34.647641 -224.271055)
			(xy 34.679033 -224.190023) (xy 34.717767 -224.112234) (xy 34.763514 -224.03835) (xy 34.815883 -223.969003)
			(xy 34.874427 -223.904783) (xy 34.938647 -223.846239) (xy 35.007994 -223.79387) (xy 35.081878 -223.748123)
			(xy 35.159667 -223.709389) (xy 35.240699 -223.677997) (xy 35.324281 -223.654216) (xy 35.409701 -223.638248)
			(xy 35.49623 -223.63023) (xy 35.58313 -223.63023) (xy 35.669659 -223.638248) (xy 35.755079 -223.654216)
			(xy 35.838661 -223.677997) (xy 35.919693 -223.709389) (xy 35.997482 -223.748123) (xy 36.071366 -223.79387)
			(xy 36.140713 -223.846239) (xy 36.204933 -223.904783) (xy 36.263477 -223.969003) (xy 36.315846 -224.03835)
			(xy 36.361593 -224.112234) (xy 36.400327 -224.190023) (xy 36.431719 -224.271055) (xy 36.4555 -224.354637)
			(xy 36.471468 -224.440057) (xy 36.479486 -224.526586) (xy 36.479988 -224.570036) (xy 36.479486 -224.613486)
			(xy 36.471468 -224.700015) (xy 36.4555 -224.785435) (xy 36.431719 -224.869017) (xy 36.400327 -224.950049)
			(xy 36.361593 -225.027838) (xy 36.315846 -225.101722) (xy 36.263477 -225.171069) (xy 36.204933 -225.235289)
			(xy 36.140713 -225.293833) (xy 36.071366 -225.346202) (xy 35.997482 -225.391949) (xy 35.919693 -225.430683)
			(xy 35.838661 -225.462075) (xy 35.755079 -225.485856) (xy 35.669659 -225.501824) (xy 35.58313 -225.509842)
			(xy 35.49623 -225.509842) (xy 35.409701 -225.501824) (xy 35.324281 -225.485856) (xy 35.240699 -225.462075)
			(xy 35.159667 -225.430683) (xy 35.081878 -225.391949) (xy 35.007994 -225.346202) (xy 34.938647 -225.293833)
			(xy 34.874427 -225.235289) (xy 34.815883 -225.171069) (xy 34.763514 -225.101722) (xy 34.717767 -225.027838)
			(xy 34.679033 -224.950049) (xy 34.647641 -224.869017) (xy 34.62386 -224.785435) (xy 34.607892 -224.700015)
			(xy 34.599874 -224.613486) (xy 31.399486 -224.613486) (xy 31.391468 -224.700015) (xy 31.3755 -224.785435)
			(xy 31.351719 -224.869017) (xy 31.320327 -224.950049) (xy 31.281593 -225.027838) (xy 31.235846 -225.101722)
			(xy 31.183477 -225.171069) (xy 31.124933 -225.235289) (xy 31.060713 -225.293833) (xy 30.991366 -225.346202)
			(xy 30.917482 -225.391949) (xy 30.839693 -225.430683) (xy 30.758661 -225.462075) (xy 30.675079 -225.485856)
			(xy 30.589659 -225.501824) (xy 30.50313 -225.509842) (xy 30.41623 -225.509842) (xy 30.329701 -225.501824)
			(xy 30.244281 -225.485856) (xy 30.160699 -225.462075) (xy 30.079667 -225.430683) (xy 30.001878 -225.391949)
			(xy 29.927994 -225.346202) (xy 29.858647 -225.293833) (xy 29.794427 -225.235289) (xy 29.735883 -225.171069)
			(xy 29.683514 -225.101722) (xy 29.637767 -225.027838) (xy 29.599033 -224.950049) (xy 29.567641 -224.869017)
			(xy 29.54386 -224.785435) (xy 29.527892 -224.700015) (xy 29.519874 -224.613486) (xy 28.942538 -224.613486)
			(xy 28.942538 -227.153486) (xy 29.519874 -227.153486) (xy 29.519874 -227.066586) (xy 29.527892 -226.980057)
			(xy 29.54386 -226.894637) (xy 29.567641 -226.811055) (xy 29.599033 -226.730023) (xy 29.637767 -226.652234)
			(xy 29.683514 -226.57835) (xy 29.735883 -226.509003) (xy 29.794427 -226.444783) (xy 29.858647 -226.386239)
			(xy 29.927994 -226.33387) (xy 30.001878 -226.288123) (xy 30.079667 -226.249389) (xy 30.160699 -226.217997)
			(xy 30.244281 -226.194216) (xy 30.329701 -226.178248) (xy 30.41623 -226.17023) (xy 30.50313 -226.17023)
			(xy 30.589659 -226.178248) (xy 30.675079 -226.194216) (xy 30.758661 -226.217997) (xy 30.839693 -226.249389)
			(xy 30.917482 -226.288123) (xy 30.991366 -226.33387) (xy 31.060713 -226.386239) (xy 31.124933 -226.444783)
			(xy 31.183477 -226.509003) (xy 31.235846 -226.57835) (xy 31.281593 -226.652234) (xy 31.320327 -226.730023)
			(xy 31.351719 -226.811055) (xy 31.3755 -226.894637) (xy 31.391468 -226.980057) (xy 31.399486 -227.066586)
			(xy 31.399988 -227.110036) (xy 31.399486 -227.153486) (xy 34.599874 -227.153486) (xy 34.599874 -227.066586)
			(xy 34.607892 -226.980057) (xy 34.62386 -226.894637) (xy 34.647641 -226.811055) (xy 34.679033 -226.730023)
			(xy 34.717767 -226.652234) (xy 34.763514 -226.57835) (xy 34.815883 -226.509003) (xy 34.874427 -226.444783)
			(xy 34.938647 -226.386239) (xy 35.007994 -226.33387) (xy 35.081878 -226.288123) (xy 35.159667 -226.249389)
			(xy 35.240699 -226.217997) (xy 35.324281 -226.194216) (xy 35.409701 -226.178248) (xy 35.49623 -226.17023)
			(xy 35.58313 -226.17023) (xy 35.669659 -226.178248) (xy 35.755079 -226.194216) (xy 35.838661 -226.217997)
			(xy 35.919693 -226.249389) (xy 35.997482 -226.288123) (xy 36.071366 -226.33387) (xy 36.140713 -226.386239)
			(xy 36.204933 -226.444783) (xy 36.263477 -226.509003) (xy 36.315846 -226.57835) (xy 36.361593 -226.652234)
			(xy 36.400327 -226.730023) (xy 36.431719 -226.811055) (xy 36.4555 -226.894637) (xy 36.471468 -226.980057)
			(xy 36.479486 -227.066586) (xy 36.479988 -227.110036) (xy 36.479486 -227.153486) (xy 36.471468 -227.240015)
			(xy 36.4555 -227.325435) (xy 36.431719 -227.409017) (xy 36.400327 -227.490049) (xy 36.361593 -227.567838)
			(xy 36.315846 -227.641722) (xy 36.263477 -227.711069) (xy 36.204933 -227.775289) (xy 36.140713 -227.833833)
			(xy 36.071366 -227.886202) (xy 35.997482 -227.931949) (xy 35.919693 -227.970683) (xy 35.838661 -228.002075)
			(xy 35.755079 -228.025856) (xy 35.669659 -228.041824) (xy 35.58313 -228.049842) (xy 35.49623 -228.049842)
			(xy 35.409701 -228.041824) (xy 35.324281 -228.025856) (xy 35.240699 -228.002075) (xy 35.159667 -227.970683)
			(xy 35.081878 -227.931949) (xy 35.007994 -227.886202) (xy 34.938647 -227.833833) (xy 34.874427 -227.775289)
			(xy 34.815883 -227.711069) (xy 34.763514 -227.641722) (xy 34.717767 -227.567838) (xy 34.679033 -227.490049)
			(xy 34.647641 -227.409017) (xy 34.62386 -227.325435) (xy 34.607892 -227.240015) (xy 34.599874 -227.153486)
			(xy 31.399486 -227.153486) (xy 31.391468 -227.240015) (xy 31.3755 -227.325435) (xy 31.351719 -227.409017)
			(xy 31.320327 -227.490049) (xy 31.281593 -227.567838) (xy 31.235846 -227.641722) (xy 31.183477 -227.711069)
			(xy 31.124933 -227.775289) (xy 31.060713 -227.833833) (xy 30.991366 -227.886202) (xy 30.917482 -227.931949)
			(xy 30.839693 -227.970683) (xy 30.758661 -228.002075) (xy 30.675079 -228.025856) (xy 30.589659 -228.041824)
			(xy 30.50313 -228.049842) (xy 30.41623 -228.049842) (xy 30.329701 -228.041824) (xy 30.244281 -228.025856)
			(xy 30.160699 -228.002075) (xy 30.079667 -227.970683) (xy 30.001878 -227.931949) (xy 29.927994 -227.886202)
			(xy 29.858647 -227.833833) (xy 29.794427 -227.775289) (xy 29.735883 -227.711069) (xy 29.683514 -227.641722)
			(xy 29.637767 -227.567838) (xy 29.599033 -227.490049) (xy 29.567641 -227.409017) (xy 29.54386 -227.325435)
			(xy 29.527892 -227.240015) (xy 29.519874 -227.153486) (xy 28.942538 -227.153486) (xy 28.942538 -229.693486)
			(xy 29.519874 -229.693486) (xy 29.519874 -229.606586) (xy 29.527892 -229.520057) (xy 29.54386 -229.434637)
			(xy 29.567641 -229.351055) (xy 29.599033 -229.270023) (xy 29.637767 -229.192234) (xy 29.683514 -229.11835)
			(xy 29.735883 -229.049003) (xy 29.794427 -228.984783) (xy 29.858647 -228.926239) (xy 29.927994 -228.87387)
			(xy 30.001878 -228.828123) (xy 30.079667 -228.789389) (xy 30.160699 -228.757997) (xy 30.244281 -228.734216)
			(xy 30.329701 -228.718248) (xy 30.41623 -228.71023) (xy 30.50313 -228.71023) (xy 30.589659 -228.718248)
			(xy 30.675079 -228.734216) (xy 30.758661 -228.757997) (xy 30.839693 -228.789389) (xy 30.917482 -228.828123)
			(xy 30.991366 -228.87387) (xy 31.060713 -228.926239) (xy 31.124933 -228.984783) (xy 31.183477 -229.049003)
			(xy 31.235846 -229.11835) (xy 31.281593 -229.192234) (xy 31.320327 -229.270023) (xy 31.351719 -229.351055)
			(xy 31.3755 -229.434637) (xy 31.391468 -229.520057) (xy 31.399486 -229.606586) (xy 31.399988 -229.650036)
			(xy 31.399486 -229.693486) (xy 34.599874 -229.693486) (xy 34.599874 -229.606586) (xy 34.607892 -229.520057)
			(xy 34.62386 -229.434637) (xy 34.647641 -229.351055) (xy 34.679033 -229.270023) (xy 34.717767 -229.192234)
			(xy 34.763514 -229.11835) (xy 34.815883 -229.049003) (xy 34.874427 -228.984783) (xy 34.938647 -228.926239)
			(xy 35.007994 -228.87387) (xy 35.081878 -228.828123) (xy 35.159667 -228.789389) (xy 35.240699 -228.757997)
			(xy 35.324281 -228.734216) (xy 35.409701 -228.718248) (xy 35.49623 -228.71023) (xy 35.58313 -228.71023)
			(xy 35.669659 -228.718248) (xy 35.755079 -228.734216) (xy 35.838661 -228.757997) (xy 35.919693 -228.789389)
			(xy 35.997482 -228.828123) (xy 36.071366 -228.87387) (xy 36.140713 -228.926239) (xy 36.204933 -228.984783)
			(xy 36.263477 -229.049003) (xy 36.315846 -229.11835) (xy 36.341678 -229.16007) (xy 39.818063 -229.16007)
			(xy 39.82207 -229.044046) (xy 39.834072 -228.928574) (xy 39.854012 -228.814206) (xy 39.881795 -228.701486)
			(xy 39.917289 -228.590952) (xy 39.960324 -228.483129) (xy 40.010695 -228.378532) (xy 40.068162 -228.27766)
			(xy 40.132452 -228.180993) (xy 40.203257 -228.088992) (xy 40.280241 -228.002095) (xy 40.363037 -227.920716)
			(xy 40.45125 -227.845243) (xy 40.54446 -227.776036) (xy 40.642223 -227.713424) (xy 40.744072 -227.657707)
			(xy 40.849522 -227.609149) (xy 40.958071 -227.567981) (xy 41.069202 -227.534401) (xy 41.182385 -227.508568)
			(xy 41.29708 -227.490605) (xy 41.412742 -227.480597) (xy 41.528818 -227.478594) (xy 41.644756 -227.484603)
			(xy 41.760003 -227.498596) (xy 41.874009 -227.520507) (xy 41.986233 -227.550232) (xy 42.096139 -227.587628)
			(xy 42.203202 -227.632517) (xy 42.306914 -227.684686) (xy 42.406779 -227.743886) (xy 42.502322 -227.809835)
			(xy 42.502604 -227.81006) (xy 43.327577 -227.81006) (xy 43.331612 -227.734356) (xy 43.343671 -227.659511)
			(xy 43.363617 -227.58637) (xy 43.391224 -227.515765) (xy 43.42618 -227.448494) (xy 43.468088 -227.385319)
			(xy 43.516474 -227.326957) (xy 43.57079 -227.274069) (xy 43.630419 -227.227254) (xy 43.694687 -227.187042)
			(xy 43.762864 -227.15389) (xy 43.83418 -227.128172) (xy 43.907825 -227.11018) (xy 43.982965 -227.100118)
			(xy 44.058749 -227.098099) (xy 44.134319 -227.104148) (xy 44.208817 -227.118195) (xy 44.2814 -227.140081)
			(xy 44.351246 -227.169558) (xy 44.417563 -227.206293) (xy 44.479599 -227.249868) (xy 44.536652 -227.29979)
			(xy 44.588076 -227.355494) (xy 44.633287 -227.416349) (xy 44.671774 -227.481664) (xy 44.7031 -227.5507)
			(xy 44.72691 -227.622675) (xy 44.742935 -227.696773) (xy 44.750994 -227.772154) (xy 44.751498 -227.81006)
			(xy 45.867577 -227.81006) (xy 45.871612 -227.734356) (xy 45.883671 -227.659511) (xy 45.903617 -227.58637)
			(xy 45.931224 -227.515765) (xy 45.96618 -227.448494) (xy 46.008088 -227.385319) (xy 46.056474 -227.326957)
			(xy 46.11079 -227.274069) (xy 46.170419 -227.227254) (xy 46.234687 -227.187042) (xy 46.302864 -227.15389)
			(xy 46.37418 -227.128172) (xy 46.447825 -227.11018) (xy 46.522965 -227.100118) (xy 46.598749 -227.098099)
			(xy 46.674319 -227.104148) (xy 46.748817 -227.118195) (xy 46.8214 -227.140081) (xy 46.891246 -227.169558)
			(xy 46.957563 -227.206293) (xy 47.019599 -227.249868) (xy 47.076652 -227.29979) (xy 47.128076 -227.355494)
			(xy 47.173287 -227.416349) (xy 47.211774 -227.481664) (xy 47.2431 -227.5507) (xy 47.26691 -227.622675)
			(xy 47.282935 -227.696773) (xy 47.290994 -227.772154) (xy 47.291498 -227.81006) (xy 48.407577 -227.81006)
			(xy 48.411612 -227.734356) (xy 48.423671 -227.659511) (xy 48.443617 -227.58637) (xy 48.471224 -227.515765)
			(xy 48.50618 -227.448494) (xy 48.548088 -227.385319) (xy 48.596474 -227.326957) (xy 48.65079 -227.274069)
			(xy 48.710419 -227.227254) (xy 48.774687 -227.187042) (xy 48.842864 -227.15389) (xy 48.91418 -227.128172)
			(xy 48.987825 -227.11018) (xy 49.062965 -227.100118) (xy 49.138749 -227.098099) (xy 49.214319 -227.104148)
			(xy 49.288817 -227.118195) (xy 49.3614 -227.140081) (xy 49.431246 -227.169558) (xy 49.497563 -227.206293)
			(xy 49.559599 -227.249868) (xy 49.616652 -227.29979) (xy 49.668076 -227.355494) (xy 49.713287 -227.416349)
			(xy 49.751774 -227.481664) (xy 49.7831 -227.5507) (xy 49.80691 -227.622675) (xy 49.822935 -227.696773)
			(xy 49.830994 -227.772154) (xy 49.831498 -227.81006) (xy 50.947577 -227.81006) (xy 50.951612 -227.734356)
			(xy 50.963671 -227.659511) (xy 50.983617 -227.58637) (xy 51.011224 -227.515765) (xy 51.04618 -227.448494)
			(xy 51.088088 -227.385319) (xy 51.136474 -227.326957) (xy 51.19079 -227.274069) (xy 51.250419 -227.227254)
			(xy 51.314687 -227.187042) (xy 51.382864 -227.15389) (xy 51.45418 -227.128172) (xy 51.527825 -227.11018)
			(xy 51.602965 -227.100118) (xy 51.678749 -227.098099) (xy 51.754319 -227.104148) (xy 51.828817 -227.118195)
			(xy 51.9014 -227.140081) (xy 51.971246 -227.169558) (xy 52.037563 -227.206293) (xy 52.099599 -227.249868)
			(xy 52.156652 -227.29979) (xy 52.208076 -227.355494) (xy 52.253287 -227.416349) (xy 52.291774 -227.481664)
			(xy 52.3231 -227.5507) (xy 52.34691 -227.622675) (xy 52.362935 -227.696773) (xy 52.370994 -227.772154)
			(xy 52.371498 -227.81006) (xy 53.487577 -227.81006) (xy 53.491612 -227.734356) (xy 53.503671 -227.659511)
			(xy 53.523617 -227.58637) (xy 53.551224 -227.515765) (xy 53.58618 -227.448494) (xy 53.628088 -227.385319)
			(xy 53.676474 -227.326957) (xy 53.73079 -227.274069) (xy 53.790419 -227.227254) (xy 53.854687 -227.187042)
			(xy 53.922864 -227.15389) (xy 53.99418 -227.128172) (xy 54.067825 -227.11018) (xy 54.142965 -227.100118)
			(xy 54.218749 -227.098099) (xy 54.294319 -227.104148) (xy 54.368817 -227.118195) (xy 54.4414 -227.140081)
			(xy 54.511246 -227.169558) (xy 54.577563 -227.206293) (xy 54.639599 -227.249868) (xy 54.696652 -227.29979)
			(xy 54.748076 -227.355494) (xy 54.793287 -227.416349) (xy 54.831774 -227.481664) (xy 54.8631 -227.5507)
			(xy 54.88691 -227.622675) (xy 54.902935 -227.696773) (xy 54.910994 -227.772154) (xy 54.911498 -227.81006)
			(xy 56.027577 -227.81006) (xy 56.031612 -227.734356) (xy 56.043671 -227.659511) (xy 56.063617 -227.58637)
			(xy 56.091224 -227.515765) (xy 56.12618 -227.448494) (xy 56.168088 -227.385319) (xy 56.216474 -227.326957)
			(xy 56.27079 -227.274069) (xy 56.330419 -227.227254) (xy 56.394687 -227.187042) (xy 56.462864 -227.15389)
			(xy 56.53418 -227.128172) (xy 56.607825 -227.11018) (xy 56.682965 -227.100118) (xy 56.758749 -227.098099)
			(xy 56.834319 -227.104148) (xy 56.908817 -227.118195) (xy 56.9814 -227.140081) (xy 57.051246 -227.169558)
			(xy 57.117563 -227.206293) (xy 57.179599 -227.249868) (xy 57.236652 -227.29979) (xy 57.288076 -227.355494)
			(xy 57.333287 -227.416349) (xy 57.371774 -227.481664) (xy 57.4031 -227.5507) (xy 57.42691 -227.622675)
			(xy 57.442935 -227.696773) (xy 57.450994 -227.772154) (xy 57.451498 -227.81006) (xy 58.567577 -227.81006)
			(xy 58.571612 -227.734356) (xy 58.583671 -227.659511) (xy 58.603617 -227.58637) (xy 58.631224 -227.515765)
			(xy 58.66618 -227.448494) (xy 58.708088 -227.385319) (xy 58.756474 -227.326957) (xy 58.81079 -227.274069)
			(xy 58.870419 -227.227254) (xy 58.934687 -227.187042) (xy 59.002864 -227.15389) (xy 59.07418 -227.128172)
			(xy 59.147825 -227.11018) (xy 59.222965 -227.100118) (xy 59.298749 -227.098099) (xy 59.374319 -227.104148)
			(xy 59.448817 -227.118195) (xy 59.5214 -227.140081) (xy 59.591246 -227.169558) (xy 59.657563 -227.206293)
			(xy 59.719599 -227.249868) (xy 59.776652 -227.29979) (xy 59.828076 -227.355494) (xy 59.873287 -227.416349)
			(xy 59.911774 -227.481664) (xy 59.9431 -227.5507) (xy 59.96691 -227.622675) (xy 59.982935 -227.696773)
			(xy 59.990994 -227.772154) (xy 59.991498 -227.81006) (xy 61.107577 -227.81006) (xy 61.111612 -227.734356)
			(xy 61.123671 -227.659511) (xy 61.143617 -227.58637) (xy 61.171224 -227.515765) (xy 61.20618 -227.448494)
			(xy 61.248088 -227.385319) (xy 61.296474 -227.326957) (xy 61.35079 -227.274069) (xy 61.410419 -227.227254)
			(xy 61.474687 -227.187042) (xy 61.542864 -227.15389) (xy 61.61418 -227.128172) (xy 61.687825 -227.11018)
			(xy 61.762965 -227.100118) (xy 61.838749 -227.098099) (xy 61.914319 -227.104148) (xy 61.988817 -227.118195)
			(xy 62.0614 -227.140081) (xy 62.131246 -227.169558) (xy 62.197563 -227.206293) (xy 62.259599 -227.249868)
			(xy 62.265544 -227.25507) (xy 86.197697 -227.25507) (xy 86.201732 -227.179366) (xy 86.213791 -227.104521)
			(xy 86.233737 -227.03138) (xy 86.261344 -226.960775) (xy 86.2963 -226.893504) (xy 86.338208 -226.830329)
			(xy 86.386594 -226.771967) (xy 86.44091 -226.719079) (xy 86.500539 -226.672264) (xy 86.564807 -226.632052)
			(xy 86.632984 -226.5989) (xy 86.7043 -226.573182) (xy 86.777945 -226.55519) (xy 86.853085 -226.545128)
			(xy 86.928869 -226.543109) (xy 87.004439 -226.549158) (xy 87.078937 -226.563205) (xy 87.15152 -226.585091)
			(xy 87.221366 -226.614568) (xy 87.287683 -226.651303) (xy 87.349719 -226.694878) (xy 87.406772 -226.7448)
			(xy 87.458196 -226.800504) (xy 87.503407 -226.861359) (xy 87.541894 -226.926674) (xy 87.57322 -226.99571)
			(xy 87.59703 -227.067685) (xy 87.613055 -227.141783) (xy 87.621114 -227.217164) (xy 87.621618 -227.25507)
			(xy 88.737697 -227.25507) (xy 88.741732 -227.179366) (xy 88.753791 -227.104521) (xy 88.773737 -227.03138)
			(xy 88.801344 -226.960775) (xy 88.8363 -226.893504) (xy 88.878208 -226.830329) (xy 88.926594 -226.771967)
			(xy 88.98091 -226.719079) (xy 89.040539 -226.672264) (xy 89.104807 -226.632052) (xy 89.172984 -226.5989)
			(xy 89.2443 -226.573182) (xy 89.317945 -226.55519) (xy 89.393085 -226.545128) (xy 89.468869 -226.543109)
			(xy 89.544439 -226.549158) (xy 89.618937 -226.563205) (xy 89.69152 -226.585091) (xy 89.761366 -226.614568)
			(xy 89.827683 -226.651303) (xy 89.889719 -226.694878) (xy 89.946772 -226.7448) (xy 89.998196 -226.800504)
			(xy 90.043407 -226.861359) (xy 90.081894 -226.926674) (xy 90.11322 -226.99571) (xy 90.13703 -227.067685)
			(xy 90.153055 -227.141783) (xy 90.161114 -227.217164) (xy 90.161618 -227.25507) (xy 91.277697 -227.25507)
			(xy 91.281732 -227.179366) (xy 91.293791 -227.104521) (xy 91.313737 -227.03138) (xy 91.341344 -226.960775)
			(xy 91.3763 -226.893504) (xy 91.418208 -226.830329) (xy 91.466594 -226.771967) (xy 91.52091 -226.719079)
			(xy 91.580539 -226.672264) (xy 91.644807 -226.632052) (xy 91.712984 -226.5989) (xy 91.7843 -226.573182)
			(xy 91.857945 -226.55519) (xy 91.933085 -226.545128) (xy 92.008869 -226.543109) (xy 92.084439 -226.549158)
			(xy 92.158937 -226.563205) (xy 92.23152 -226.585091) (xy 92.301366 -226.614568) (xy 92.367683 -226.651303)
			(xy 92.429719 -226.694878) (xy 92.486772 -226.7448) (xy 92.538196 -226.800504) (xy 92.583407 -226.861359)
			(xy 92.621894 -226.926674) (xy 92.65322 -226.99571) (xy 92.67703 -227.067685) (xy 92.693055 -227.141783)
			(xy 92.701114 -227.217164) (xy 92.701618 -227.25507) (xy 92.701114 -227.292976) (xy 92.693055 -227.368357)
			(xy 92.67703 -227.442455) (xy 92.65322 -227.51443) (xy 92.621894 -227.583466) (xy 92.583407 -227.648781)
			(xy 92.538196 -227.709636) (xy 92.486772 -227.76534) (xy 92.429719 -227.815262) (xy 92.367683 -227.858837)
			(xy 92.301366 -227.895572) (xy 92.23152 -227.925049) (xy 92.158937 -227.946935) (xy 92.084439 -227.960982)
			(xy 92.008869 -227.967031) (xy 91.933085 -227.965012) (xy 91.857945 -227.95495) (xy 91.7843 -227.936958)
			(xy 91.712984 -227.91124) (xy 91.644807 -227.878088) (xy 91.580539 -227.837876) (xy 91.52091 -227.791061)
			(xy 91.466594 -227.738173) (xy 91.418208 -227.679811) (xy 91.3763 -227.616636) (xy 91.341344 -227.549365)
			(xy 91.313737 -227.47876) (xy 91.293791 -227.405619) (xy 91.281732 -227.330774) (xy 91.277697 -227.25507)
			(xy 90.161618 -227.25507) (xy 90.161114 -227.292976) (xy 90.153055 -227.368357) (xy 90.13703 -227.442455)
			(xy 90.11322 -227.51443) (xy 90.081894 -227.583466) (xy 90.043407 -227.648781) (xy 89.998196 -227.709636)
			(xy 89.946772 -227.76534) (xy 89.889719 -227.815262) (xy 89.827683 -227.858837) (xy 89.761366 -227.895572)
			(xy 89.69152 -227.925049) (xy 89.618937 -227.946935) (xy 89.544439 -227.960982) (xy 89.468869 -227.967031)
			(xy 89.393085 -227.965012) (xy 89.317945 -227.95495) (xy 89.2443 -227.936958) (xy 89.172984 -227.91124)
			(xy 89.104807 -227.878088) (xy 89.040539 -227.837876) (xy 88.98091 -227.791061) (xy 88.926594 -227.738173)
			(xy 88.878208 -227.679811) (xy 88.8363 -227.616636) (xy 88.801344 -227.549365) (xy 88.773737 -227.47876)
			(xy 88.753791 -227.405619) (xy 88.741732 -227.330774) (xy 88.737697 -227.25507) (xy 87.621618 -227.25507)
			(xy 87.621114 -227.292976) (xy 87.613055 -227.368357) (xy 87.59703 -227.442455) (xy 87.57322 -227.51443)
			(xy 87.541894 -227.583466) (xy 87.503407 -227.648781) (xy 87.458196 -227.709636) (xy 87.406772 -227.76534)
			(xy 87.349719 -227.815262) (xy 87.287683 -227.858837) (xy 87.221366 -227.895572) (xy 87.15152 -227.925049)
			(xy 87.078937 -227.946935) (xy 87.004439 -227.960982) (xy 86.928869 -227.967031) (xy 86.853085 -227.965012)
			(xy 86.777945 -227.95495) (xy 86.7043 -227.936958) (xy 86.632984 -227.91124) (xy 86.564807 -227.878088)
			(xy 86.500539 -227.837876) (xy 86.44091 -227.791061) (xy 86.386594 -227.738173) (xy 86.338208 -227.679811)
			(xy 86.2963 -227.616636) (xy 86.261344 -227.549365) (xy 86.233737 -227.47876) (xy 86.213791 -227.405619)
			(xy 86.201732 -227.330774) (xy 86.197697 -227.25507) (xy 62.265544 -227.25507) (xy 62.316652 -227.29979)
			(xy 62.368076 -227.355494) (xy 62.413287 -227.416349) (xy 62.451774 -227.481664) (xy 62.4831 -227.5507)
			(xy 62.50691 -227.622675) (xy 62.522935 -227.696773) (xy 62.530994 -227.772154) (xy 62.531498 -227.81006)
			(xy 62.530994 -227.847966) (xy 62.522935 -227.923347) (xy 62.50691 -227.997445) (xy 62.4831 -228.06942)
			(xy 62.451774 -228.138456) (xy 62.413287 -228.203771) (xy 62.368076 -228.264626) (xy 62.316652 -228.32033)
			(xy 62.259599 -228.370252) (xy 62.197563 -228.413827) (xy 62.131246 -228.450562) (xy 62.0614 -228.480039)
			(xy 61.988817 -228.501925) (xy 61.914319 -228.515972) (xy 61.838749 -228.522021) (xy 61.762965 -228.520002)
			(xy 61.687825 -228.50994) (xy 61.61418 -228.491948) (xy 61.542864 -228.46623) (xy 61.474687 -228.433078)
			(xy 61.410419 -228.392866) (xy 61.35079 -228.346051) (xy 61.296474 -228.293163) (xy 61.248088 -228.234801)
			(xy 61.20618 -228.171626) (xy 61.171224 -228.104355) (xy 61.143617 -228.03375) (xy 61.123671 -227.960609)
			(xy 61.111612 -227.885764) (xy 61.107577 -227.81006) (xy 59.991498 -227.81006) (xy 59.990994 -227.847966)
			(xy 59.982935 -227.923347) (xy 59.96691 -227.997445) (xy 59.9431 -228.06942) (xy 59.911774 -228.138456)
			(xy 59.873287 -228.203771) (xy 59.828076 -228.264626) (xy 59.776652 -228.32033) (xy 59.719599 -228.370252)
			(xy 59.657563 -228.413827) (xy 59.591246 -228.450562) (xy 59.5214 -228.480039) (xy 59.448817 -228.501925)
			(xy 59.374319 -228.515972) (xy 59.298749 -228.522021) (xy 59.222965 -228.520002) (xy 59.147825 -228.50994)
			(xy 59.07418 -228.491948) (xy 59.002864 -228.46623) (xy 58.934687 -228.433078) (xy 58.870419 -228.392866)
			(xy 58.81079 -228.346051) (xy 58.756474 -228.293163) (xy 58.708088 -228.234801) (xy 58.66618 -228.171626)
			(xy 58.631224 -228.104355) (xy 58.603617 -228.03375) (xy 58.583671 -227.960609) (xy 58.571612 -227.885764)
			(xy 58.567577 -227.81006) (xy 57.451498 -227.81006) (xy 57.450994 -227.847966) (xy 57.442935 -227.923347)
			(xy 57.42691 -227.997445) (xy 57.4031 -228.06942) (xy 57.371774 -228.138456) (xy 57.333287 -228.203771)
			(xy 57.288076 -228.264626) (xy 57.236652 -228.32033) (xy 57.179599 -228.370252) (xy 57.117563 -228.413827)
			(xy 57.051246 -228.450562) (xy 56.9814 -228.480039) (xy 56.908817 -228.501925) (xy 56.834319 -228.515972)
			(xy 56.758749 -228.522021) (xy 56.682965 -228.520002) (xy 56.607825 -228.50994) (xy 56.53418 -228.491948)
			(xy 56.462864 -228.46623) (xy 56.394687 -228.433078) (xy 56.330419 -228.392866) (xy 56.27079 -228.346051)
			(xy 56.216474 -228.293163) (xy 56.168088 -228.234801) (xy 56.12618 -228.171626) (xy 56.091224 -228.104355)
			(xy 56.063617 -228.03375) (xy 56.043671 -227.960609) (xy 56.031612 -227.885764) (xy 56.027577 -227.81006)
			(xy 54.911498 -227.81006) (xy 54.910994 -227.847966) (xy 54.902935 -227.923347) (xy 54.88691 -227.997445)
			(xy 54.8631 -228.06942) (xy 54.831774 -228.138456) (xy 54.793287 -228.203771) (xy 54.748076 -228.264626)
			(xy 54.696652 -228.32033) (xy 54.639599 -228.370252) (xy 54.577563 -228.413827) (xy 54.511246 -228.450562)
			(xy 54.4414 -228.480039) (xy 54.368817 -228.501925) (xy 54.294319 -228.515972) (xy 54.218749 -228.522021)
			(xy 54.142965 -228.520002) (xy 54.067825 -228.50994) (xy 53.99418 -228.491948) (xy 53.922864 -228.46623)
			(xy 53.854687 -228.433078) (xy 53.790419 -228.392866) (xy 53.73079 -228.346051) (xy 53.676474 -228.293163)
			(xy 53.628088 -228.234801) (xy 53.58618 -228.171626) (xy 53.551224 -228.104355) (xy 53.523617 -228.03375)
			(xy 53.503671 -227.960609) (xy 53.491612 -227.885764) (xy 53.487577 -227.81006) (xy 52.371498 -227.81006)
			(xy 52.370994 -227.847966) (xy 52.362935 -227.923347) (xy 52.34691 -227.997445) (xy 52.3231 -228.06942)
			(xy 52.291774 -228.138456) (xy 52.253287 -228.203771) (xy 52.208076 -228.264626) (xy 52.156652 -228.32033)
			(xy 52.099599 -228.370252) (xy 52.037563 -228.413827) (xy 51.971246 -228.450562) (xy 51.9014 -228.480039)
			(xy 51.828817 -228.501925) (xy 51.754319 -228.515972) (xy 51.678749 -228.522021) (xy 51.602965 -228.520002)
			(xy 51.527825 -228.50994) (xy 51.45418 -228.491948) (xy 51.382864 -228.46623) (xy 51.314687 -228.433078)
			(xy 51.250419 -228.392866) (xy 51.19079 -228.346051) (xy 51.136474 -228.293163) (xy 51.088088 -228.234801)
			(xy 51.04618 -228.171626) (xy 51.011224 -228.104355) (xy 50.983617 -228.03375) (xy 50.963671 -227.960609)
			(xy 50.951612 -227.885764) (xy 50.947577 -227.81006) (xy 49.831498 -227.81006) (xy 49.830994 -227.847966)
			(xy 49.822935 -227.923347) (xy 49.80691 -227.997445) (xy 49.7831 -228.06942) (xy 49.751774 -228.138456)
			(xy 49.713287 -228.203771) (xy 49.668076 -228.264626) (xy 49.616652 -228.32033) (xy 49.559599 -228.370252)
			(xy 49.497563 -228.413827) (xy 49.431246 -228.450562) (xy 49.3614 -228.480039) (xy 49.288817 -228.501925)
			(xy 49.214319 -228.515972) (xy 49.138749 -228.522021) (xy 49.062965 -228.520002) (xy 48.987825 -228.50994)
			(xy 48.91418 -228.491948) (xy 48.842864 -228.46623) (xy 48.774687 -228.433078) (xy 48.710419 -228.392866)
			(xy 48.65079 -228.346051) (xy 48.596474 -228.293163) (xy 48.548088 -228.234801) (xy 48.50618 -228.171626)
			(xy 48.471224 -228.104355) (xy 48.443617 -228.03375) (xy 48.423671 -227.960609) (xy 48.411612 -227.885764)
			(xy 48.407577 -227.81006) (xy 47.291498 -227.81006) (xy 47.290994 -227.847966) (xy 47.282935 -227.923347)
			(xy 47.26691 -227.997445) (xy 47.2431 -228.06942) (xy 47.211774 -228.138456) (xy 47.173287 -228.203771)
			(xy 47.128076 -228.264626) (xy 47.076652 -228.32033) (xy 47.019599 -228.370252) (xy 46.957563 -228.413827)
			(xy 46.891246 -228.450562) (xy 46.8214 -228.480039) (xy 46.748817 -228.501925) (xy 46.674319 -228.515972)
			(xy 46.598749 -228.522021) (xy 46.522965 -228.520002) (xy 46.447825 -228.50994) (xy 46.37418 -228.491948)
			(xy 46.302864 -228.46623) (xy 46.234687 -228.433078) (xy 46.170419 -228.392866) (xy 46.11079 -228.346051)
			(xy 46.056474 -228.293163) (xy 46.008088 -228.234801) (xy 45.96618 -228.171626) (xy 45.931224 -228.104355)
			(xy 45.903617 -228.03375) (xy 45.883671 -227.960609) (xy 45.871612 -227.885764) (xy 45.867577 -227.81006)
			(xy 44.751498 -227.81006) (xy 44.750994 -227.847966) (xy 44.742935 -227.923347) (xy 44.72691 -227.997445)
			(xy 44.7031 -228.06942) (xy 44.671774 -228.138456) (xy 44.633287 -228.203771) (xy 44.588076 -228.264626)
			(xy 44.536652 -228.32033) (xy 44.479599 -228.370252) (xy 44.417563 -228.413827) (xy 44.351246 -228.450562)
			(xy 44.2814 -228.480039) (xy 44.208817 -228.501925) (xy 44.134319 -228.515972) (xy 44.058749 -228.522021)
			(xy 43.982965 -228.520002) (xy 43.907825 -228.50994) (xy 43.83418 -228.491948) (xy 43.762864 -228.46623)
			(xy 43.694687 -228.433078) (xy 43.630419 -228.392866) (xy 43.57079 -228.346051) (xy 43.516474 -228.293163)
			(xy 43.468088 -228.234801) (xy 43.42618 -228.171626) (xy 43.391224 -228.104355) (xy 43.363617 -228.03375)
			(xy 43.343671 -227.960609) (xy 43.331612 -227.885764) (xy 43.327577 -227.81006) (xy 42.502604 -227.81006)
			(xy 42.593088 -227.882218) (xy 42.678643 -227.960691) (xy 42.758581 -228.044879) (xy 42.83252 -228.134381)
			(xy 42.900108 -228.228772) (xy 42.961022 -228.3276) (xy 43.014974 -228.430396) (xy 43.056604 -228.52507)
			(xy 84.927697 -228.52507) (xy 84.931732 -228.449366) (xy 84.943791 -228.374521) (xy 84.963737 -228.30138)
			(xy 84.991344 -228.230775) (xy 85.0263 -228.163504) (xy 85.068208 -228.100329) (xy 85.116594 -228.041967)
			(xy 85.17091 -227.989079) (xy 85.230539 -227.942264) (xy 85.294807 -227.902052) (xy 85.362984 -227.8689)
			(xy 85.4343 -227.843182) (xy 85.507945 -227.82519) (xy 85.583085 -227.815128) (xy 85.658869 -227.813109)
			(xy 85.734439 -227.819158) (xy 85.808937 -227.833205) (xy 85.88152 -227.855091) (xy 85.951366 -227.884568)
			(xy 86.017683 -227.921303) (xy 86.079719 -227.964878) (xy 86.136772 -228.0148) (xy 86.188196 -228.070504)
			(xy 86.233407 -228.131359) (xy 86.271894 -228.196674) (xy 86.30322 -228.26571) (xy 86.32703 -228.337685)
			(xy 86.343055 -228.411783) (xy 86.351114 -228.487164) (xy 86.351618 -228.52507) (xy 87.467697 -228.52507)
			(xy 87.471732 -228.449366) (xy 87.483791 -228.374521) (xy 87.503737 -228.30138) (xy 87.531344 -228.230775)
			(xy 87.5663 -228.163504) (xy 87.608208 -228.100329) (xy 87.656594 -228.041967) (xy 87.71091 -227.989079)
			(xy 87.770539 -227.942264) (xy 87.834807 -227.902052) (xy 87.902984 -227.8689) (xy 87.9743 -227.843182)
			(xy 88.047945 -227.82519) (xy 88.123085 -227.815128) (xy 88.198869 -227.813109) (xy 88.274439 -227.819158)
			(xy 88.348937 -227.833205) (xy 88.42152 -227.855091) (xy 88.491366 -227.884568) (xy 88.557683 -227.921303)
			(xy 88.619719 -227.964878) (xy 88.676772 -228.0148) (xy 88.728196 -228.070504) (xy 88.773407 -228.131359)
			(xy 88.811894 -228.196674) (xy 88.84322 -228.26571) (xy 88.86703 -228.337685) (xy 88.883055 -228.411783)
			(xy 88.891114 -228.487164) (xy 88.891618 -228.52507) (xy 90.007697 -228.52507) (xy 90.011732 -228.449366)
			(xy 90.023791 -228.374521) (xy 90.043737 -228.30138) (xy 90.071344 -228.230775) (xy 90.1063 -228.163504)
			(xy 90.148208 -228.100329) (xy 90.196594 -228.041967) (xy 90.25091 -227.989079) (xy 90.310539 -227.942264)
			(xy 90.374807 -227.902052) (xy 90.442984 -227.8689) (xy 90.5143 -227.843182) (xy 90.587945 -227.82519)
			(xy 90.663085 -227.815128) (xy 90.738869 -227.813109) (xy 90.814439 -227.819158) (xy 90.888937 -227.833205)
			(xy 90.96152 -227.855091) (xy 91.031366 -227.884568) (xy 91.097683 -227.921303) (xy 91.159719 -227.964878)
			(xy 91.216772 -228.0148) (xy 91.268196 -228.070504) (xy 91.313407 -228.131359) (xy 91.351894 -228.196674)
			(xy 91.38322 -228.26571) (xy 91.40703 -228.337685) (xy 91.423055 -228.411783) (xy 91.431114 -228.487164)
			(xy 91.431618 -228.52507) (xy 91.431114 -228.562976) (xy 91.423055 -228.638357) (xy 91.40703 -228.712455)
			(xy 91.38322 -228.78443) (xy 91.351894 -228.853466) (xy 91.313407 -228.918781) (xy 91.268196 -228.979636)
			(xy 91.216772 -229.03534) (xy 91.159719 -229.085262) (xy 91.097683 -229.128837) (xy 91.031366 -229.165572)
			(xy 90.96152 -229.195049) (xy 90.888937 -229.216935) (xy 90.814439 -229.230982) (xy 90.738869 -229.237031)
			(xy 90.663085 -229.235012) (xy 90.587945 -229.22495) (xy 90.5143 -229.206958) (xy 90.442984 -229.18124)
			(xy 90.374807 -229.148088) (xy 90.310539 -229.107876) (xy 90.25091 -229.061061) (xy 90.196594 -229.008173)
			(xy 90.148208 -228.949811) (xy 90.1063 -228.886636) (xy 90.071344 -228.819365) (xy 90.043737 -228.74876)
			(xy 90.023791 -228.675619) (xy 90.011732 -228.600774) (xy 90.007697 -228.52507) (xy 88.891618 -228.52507)
			(xy 88.891114 -228.562976) (xy 88.883055 -228.638357) (xy 88.86703 -228.712455) (xy 88.84322 -228.78443)
			(xy 88.811894 -228.853466) (xy 88.773407 -228.918781) (xy 88.728196 -228.979636) (xy 88.676772 -229.03534)
			(xy 88.619719 -229.085262) (xy 88.557683 -229.128837) (xy 88.491366 -229.165572) (xy 88.42152 -229.195049)
			(xy 88.348937 -229.216935) (xy 88.274439 -229.230982) (xy 88.198869 -229.237031) (xy 88.123085 -229.235012)
			(xy 88.047945 -229.22495) (xy 87.9743 -229.206958) (xy 87.902984 -229.18124) (xy 87.834807 -229.148088)
			(xy 87.770539 -229.107876) (xy 87.71091 -229.061061) (xy 87.656594 -229.008173) (xy 87.608208 -228.949811)
			(xy 87.5663 -228.886636) (xy 87.531344 -228.819365) (xy 87.503737 -228.74876) (xy 87.483791 -228.675619)
			(xy 87.471732 -228.600774) (xy 87.467697 -228.52507) (xy 86.351618 -228.52507) (xy 86.351114 -228.562976)
			(xy 86.343055 -228.638357) (xy 86.32703 -228.712455) (xy 86.30322 -228.78443) (xy 86.271894 -228.853466)
			(xy 86.233407 -228.918781) (xy 86.188196 -228.979636) (xy 86.136772 -229.03534) (xy 86.079719 -229.085262)
			(xy 86.017683 -229.128837) (xy 85.951366 -229.165572) (xy 85.88152 -229.195049) (xy 85.808937 -229.216935)
			(xy 85.734439 -229.230982) (xy 85.658869 -229.237031) (xy 85.583085 -229.235012) (xy 85.507945 -229.22495)
			(xy 85.4343 -229.206958) (xy 85.362984 -229.18124) (xy 85.294807 -229.148088) (xy 85.230539 -229.107876)
			(xy 85.17091 -229.061061) (xy 85.116594 -229.008173) (xy 85.068208 -228.949811) (xy 85.0263 -228.886636)
			(xy 84.991344 -228.819365) (xy 84.963737 -228.74876) (xy 84.943791 -228.675619) (xy 84.931732 -228.600774)
			(xy 84.927697 -228.52507) (xy 43.056604 -228.52507) (xy 43.061704 -228.536669) (xy 43.100992 -228.645913)
			(xy 43.132649 -228.757606) (xy 43.156525 -228.871218) (xy 43.172506 -228.986206) (xy 43.180515 -229.102023)
			(xy 43.181016 -229.16007) (xy 43.180515 -229.218117) (xy 43.172506 -229.333934) (xy 43.156525 -229.448922)
			(xy 43.132649 -229.562534) (xy 43.100992 -229.674227) (xy 43.061704 -229.783471) (xy 43.056604 -229.79507)
			(xy 86.197697 -229.79507) (xy 86.201732 -229.719366) (xy 86.213791 -229.644521) (xy 86.233737 -229.57138)
			(xy 86.261344 -229.500775) (xy 86.2963 -229.433504) (xy 86.338208 -229.370329) (xy 86.386594 -229.311967)
			(xy 86.44091 -229.259079) (xy 86.500539 -229.212264) (xy 86.564807 -229.172052) (xy 86.632984 -229.1389)
			(xy 86.7043 -229.113182) (xy 86.777945 -229.09519) (xy 86.853085 -229.085128) (xy 86.928869 -229.083109)
			(xy 87.004439 -229.089158) (xy 87.078937 -229.103205) (xy 87.15152 -229.125091) (xy 87.221366 -229.154568)
			(xy 87.287683 -229.191303) (xy 87.349719 -229.234878) (xy 87.406772 -229.2848) (xy 87.458196 -229.340504)
			(xy 87.503407 -229.401359) (xy 87.541894 -229.466674) (xy 87.57322 -229.53571) (xy 87.59703 -229.607685)
			(xy 87.613055 -229.681783) (xy 87.621114 -229.757164) (xy 87.621618 -229.79507) (xy 88.737697 -229.79507)
			(xy 88.741732 -229.719366) (xy 88.753791 -229.644521) (xy 88.773737 -229.57138) (xy 88.801344 -229.500775)
			(xy 88.8363 -229.433504) (xy 88.878208 -229.370329) (xy 88.926594 -229.311967) (xy 88.98091 -229.259079)
			(xy 89.040539 -229.212264) (xy 89.104807 -229.172052) (xy 89.172984 -229.1389) (xy 89.2443 -229.113182)
			(xy 89.317945 -229.09519) (xy 89.393085 -229.085128) (xy 89.468869 -229.083109) (xy 89.544439 -229.089158)
			(xy 89.618937 -229.103205) (xy 89.69152 -229.125091) (xy 89.761366 -229.154568) (xy 89.827683 -229.191303)
			(xy 89.889719 -229.234878) (xy 89.946772 -229.2848) (xy 89.998196 -229.340504) (xy 90.043407 -229.401359)
			(xy 90.081894 -229.466674) (xy 90.11322 -229.53571) (xy 90.13703 -229.607685) (xy 90.153055 -229.681783)
			(xy 90.161114 -229.757164) (xy 90.161618 -229.79507) (xy 91.277697 -229.79507) (xy 91.281732 -229.719366)
			(xy 91.293791 -229.644521) (xy 91.313737 -229.57138) (xy 91.341344 -229.500775) (xy 91.3763 -229.433504)
			(xy 91.418208 -229.370329) (xy 91.466594 -229.311967) (xy 91.52091 -229.259079) (xy 91.580539 -229.212264)
			(xy 91.644807 -229.172052) (xy 91.712984 -229.1389) (xy 91.7843 -229.113182) (xy 91.857945 -229.09519)
			(xy 91.933085 -229.085128) (xy 92.008869 -229.083109) (xy 92.084439 -229.089158) (xy 92.158937 -229.103205)
			(xy 92.23152 -229.125091) (xy 92.301366 -229.154568) (xy 92.367683 -229.191303) (xy 92.429719 -229.234878)
			(xy 92.486772 -229.2848) (xy 92.538196 -229.340504) (xy 92.583407 -229.401359) (xy 92.621894 -229.466674)
			(xy 92.65322 -229.53571) (xy 92.67703 -229.607685) (xy 92.693055 -229.681783) (xy 92.701114 -229.757164)
			(xy 92.701618 -229.79507) (xy 92.701114 -229.832976) (xy 92.693055 -229.908357) (xy 92.67703 -229.982455)
			(xy 92.65322 -230.05443) (xy 92.621894 -230.123466) (xy 92.583407 -230.188781) (xy 92.538196 -230.249636)
			(xy 92.486772 -230.30534) (xy 92.429719 -230.355262) (xy 92.367683 -230.398837) (xy 92.301366 -230.435572)
			(xy 92.23152 -230.465049) (xy 92.158937 -230.486935) (xy 92.084439 -230.500982) (xy 92.008869 -230.507031)
			(xy 91.933085 -230.505012) (xy 91.857945 -230.49495) (xy 91.7843 -230.476958) (xy 91.712984 -230.45124)
			(xy 91.644807 -230.418088) (xy 91.580539 -230.377876) (xy 91.52091 -230.331061) (xy 91.466594 -230.278173)
			(xy 91.418208 -230.219811) (xy 91.3763 -230.156636) (xy 91.341344 -230.089365) (xy 91.313737 -230.01876)
			(xy 91.293791 -229.945619) (xy 91.281732 -229.870774) (xy 91.277697 -229.79507) (xy 90.161618 -229.79507)
			(xy 90.161114 -229.832976) (xy 90.153055 -229.908357) (xy 90.13703 -229.982455) (xy 90.11322 -230.05443)
			(xy 90.081894 -230.123466) (xy 90.043407 -230.188781) (xy 89.998196 -230.249636) (xy 89.946772 -230.30534)
			(xy 89.889719 -230.355262) (xy 89.827683 -230.398837) (xy 89.761366 -230.435572) (xy 89.69152 -230.465049)
			(xy 89.618937 -230.486935) (xy 89.544439 -230.500982) (xy 89.468869 -230.507031) (xy 89.393085 -230.505012)
			(xy 89.317945 -230.49495) (xy 89.2443 -230.476958) (xy 89.172984 -230.45124) (xy 89.104807 -230.418088)
			(xy 89.040539 -230.377876) (xy 88.98091 -230.331061) (xy 88.926594 -230.278173) (xy 88.878208 -230.219811)
			(xy 88.8363 -230.156636) (xy 88.801344 -230.089365) (xy 88.773737 -230.01876) (xy 88.753791 -229.945619)
			(xy 88.741732 -229.870774) (xy 88.737697 -229.79507) (xy 87.621618 -229.79507) (xy 87.621114 -229.832976)
			(xy 87.613055 -229.908357) (xy 87.59703 -229.982455) (xy 87.57322 -230.05443) (xy 87.541894 -230.123466)
			(xy 87.503407 -230.188781) (xy 87.458196 -230.249636) (xy 87.406772 -230.30534) (xy 87.349719 -230.355262)
			(xy 87.287683 -230.398837) (xy 87.221366 -230.435572) (xy 87.15152 -230.465049) (xy 87.078937 -230.486935)
			(xy 87.004439 -230.500982) (xy 86.928869 -230.507031) (xy 86.853085 -230.505012) (xy 86.777945 -230.49495)
			(xy 86.7043 -230.476958) (xy 86.632984 -230.45124) (xy 86.564807 -230.418088) (xy 86.500539 -230.377876)
			(xy 86.44091 -230.331061) (xy 86.386594 -230.278173) (xy 86.338208 -230.219811) (xy 86.2963 -230.156636)
			(xy 86.261344 -230.089365) (xy 86.233737 -230.01876) (xy 86.213791 -229.945619) (xy 86.201732 -229.870774)
			(xy 86.197697 -229.79507) (xy 43.056604 -229.79507) (xy 43.055152 -229.798372) (xy 43.328336 -229.798372)
			(xy 44.751244 -229.798372) (xy 44.751244 -230.51008) (xy 45.867577 -230.51008) (xy 45.871612 -230.434376)
			(xy 45.883671 -230.359531) (xy 45.903617 -230.28639) (xy 45.931224 -230.215785) (xy 45.96618 -230.148514)
			(xy 46.008088 -230.085339) (xy 46.056474 -230.026977) (xy 46.11079 -229.974089) (xy 46.170419 -229.927274)
			(xy 46.234687 -229.887062) (xy 46.302864 -229.85391) (xy 46.37418 -229.828192) (xy 46.447825 -229.8102)
			(xy 46.522965 -229.800138) (xy 46.598749 -229.798119) (xy 46.674319 -229.804168) (xy 46.748817 -229.818215)
			(xy 46.8214 -229.840101) (xy 46.891246 -229.869578) (xy 46.957563 -229.906313) (xy 47.019599 -229.949888)
			(xy 47.076652 -229.99981) (xy 47.128076 -230.055514) (xy 47.173287 -230.116369) (xy 47.211774 -230.181684)
			(xy 47.2431 -230.25072) (xy 47.26691 -230.322695) (xy 47.282935 -230.396793) (xy 47.290994 -230.472174)
			(xy 47.291498 -230.51008) (xy 48.407577 -230.51008) (xy 48.411612 -230.434376) (xy 48.423671 -230.359531)
			(xy 48.443617 -230.28639) (xy 48.471224 -230.215785) (xy 48.50618 -230.148514) (xy 48.548088 -230.085339)
			(xy 48.596474 -230.026977) (xy 48.65079 -229.974089) (xy 48.710419 -229.927274) (xy 48.774687 -229.887062)
			(xy 48.842864 -229.85391) (xy 48.91418 -229.828192) (xy 48.987825 -229.8102) (xy 49.062965 -229.800138)
			(xy 49.138749 -229.798119) (xy 49.214319 -229.804168) (xy 49.288817 -229.818215) (xy 49.3614 -229.840101)
			(xy 49.431246 -229.869578) (xy 49.497563 -229.906313) (xy 49.559599 -229.949888) (xy 49.616652 -229.99981)
			(xy 49.668076 -230.055514) (xy 49.713287 -230.116369) (xy 49.751774 -230.181684) (xy 49.7831 -230.25072)
			(xy 49.80691 -230.322695) (xy 49.822935 -230.396793) (xy 49.830994 -230.472174) (xy 49.831498 -230.51008)
			(xy 50.947577 -230.51008) (xy 50.951612 -230.434376) (xy 50.963671 -230.359531) (xy 50.983617 -230.28639)
			(xy 51.011224 -230.215785) (xy 51.04618 -230.148514) (xy 51.088088 -230.085339) (xy 51.136474 -230.026977)
			(xy 51.19079 -229.974089) (xy 51.250419 -229.927274) (xy 51.314687 -229.887062) (xy 51.382864 -229.85391)
			(xy 51.45418 -229.828192) (xy 51.527825 -229.8102) (xy 51.602965 -229.800138) (xy 51.678749 -229.798119)
			(xy 51.754319 -229.804168) (xy 51.828817 -229.818215) (xy 51.9014 -229.840101) (xy 51.971246 -229.869578)
			(xy 52.037563 -229.906313) (xy 52.099599 -229.949888) (xy 52.156652 -229.99981) (xy 52.208076 -230.055514)
			(xy 52.253287 -230.116369) (xy 52.291774 -230.181684) (xy 52.3231 -230.25072) (xy 52.34691 -230.322695)
			(xy 52.362935 -230.396793) (xy 52.370994 -230.472174) (xy 52.371498 -230.51008) (xy 53.487577 -230.51008)
			(xy 53.491612 -230.434376) (xy 53.503671 -230.359531) (xy 53.523617 -230.28639) (xy 53.551224 -230.215785)
			(xy 53.58618 -230.148514) (xy 53.628088 -230.085339) (xy 53.676474 -230.026977) (xy 53.73079 -229.974089)
			(xy 53.790419 -229.927274) (xy 53.854687 -229.887062) (xy 53.922864 -229.85391) (xy 53.99418 -229.828192)
			(xy 54.067825 -229.8102) (xy 54.142965 -229.800138) (xy 54.218749 -229.798119) (xy 54.294319 -229.804168)
			(xy 54.368817 -229.818215) (xy 54.4414 -229.840101) (xy 54.511246 -229.869578) (xy 54.577563 -229.906313)
			(xy 54.639599 -229.949888) (xy 54.696652 -229.99981) (xy 54.748076 -230.055514) (xy 54.793287 -230.116369)
			(xy 54.831774 -230.181684) (xy 54.8631 -230.25072) (xy 54.88691 -230.322695) (xy 54.902935 -230.396793)
			(xy 54.910994 -230.472174) (xy 54.911498 -230.51008) (xy 56.027577 -230.51008) (xy 56.031612 -230.434376)
			(xy 56.043671 -230.359531) (xy 56.063617 -230.28639) (xy 56.091224 -230.215785) (xy 56.12618 -230.148514)
			(xy 56.168088 -230.085339) (xy 56.216474 -230.026977) (xy 56.27079 -229.974089) (xy 56.330419 -229.927274)
			(xy 56.394687 -229.887062) (xy 56.462864 -229.85391) (xy 56.53418 -229.828192) (xy 56.607825 -229.8102)
			(xy 56.682965 -229.800138) (xy 56.758749 -229.798119) (xy 56.834319 -229.804168) (xy 56.908817 -229.818215)
			(xy 56.9814 -229.840101) (xy 57.051246 -229.869578) (xy 57.117563 -229.906313) (xy 57.179599 -229.949888)
			(xy 57.236652 -229.99981) (xy 57.288076 -230.055514) (xy 57.333287 -230.116369) (xy 57.371774 -230.181684)
			(xy 57.4031 -230.25072) (xy 57.42691 -230.322695) (xy 57.442935 -230.396793) (xy 57.450994 -230.472174)
			(xy 57.451498 -230.51008) (xy 58.567577 -230.51008) (xy 58.571612 -230.434376) (xy 58.583671 -230.359531)
			(xy 58.603617 -230.28639) (xy 58.631224 -230.215785) (xy 58.66618 -230.148514) (xy 58.708088 -230.085339)
			(xy 58.756474 -230.026977) (xy 58.81079 -229.974089) (xy 58.870419 -229.927274) (xy 58.934687 -229.887062)
			(xy 59.002864 -229.85391) (xy 59.07418 -229.828192) (xy 59.147825 -229.8102) (xy 59.222965 -229.800138)
			(xy 59.298749 -229.798119) (xy 59.374319 -229.804168) (xy 59.448817 -229.818215) (xy 59.5214 -229.840101)
			(xy 59.591246 -229.869578) (xy 59.657563 -229.906313) (xy 59.719599 -229.949888) (xy 59.776652 -229.99981)
			(xy 59.828076 -230.055514) (xy 59.873287 -230.116369) (xy 59.911774 -230.181684) (xy 59.9431 -230.25072)
			(xy 59.96691 -230.322695) (xy 59.982935 -230.396793) (xy 59.990994 -230.472174) (xy 59.991498 -230.51008)
			(xy 61.107577 -230.51008) (xy 61.111612 -230.434376) (xy 61.123671 -230.359531) (xy 61.143617 -230.28639)
			(xy 61.171224 -230.215785) (xy 61.20618 -230.148514) (xy 61.248088 -230.085339) (xy 61.296474 -230.026977)
			(xy 61.35079 -229.974089) (xy 61.410419 -229.927274) (xy 61.474687 -229.887062) (xy 61.542864 -229.85391)
			(xy 61.61418 -229.828192) (xy 61.687825 -229.8102) (xy 61.762965 -229.800138) (xy 61.838749 -229.798119)
			(xy 61.914319 -229.804168) (xy 61.988817 -229.818215) (xy 62.0614 -229.840101) (xy 62.131246 -229.869578)
			(xy 62.197563 -229.906313) (xy 62.259599 -229.949888) (xy 62.316652 -229.99981) (xy 62.368076 -230.055514)
			(xy 62.413287 -230.116369) (xy 62.451774 -230.181684) (xy 62.4831 -230.25072) (xy 62.50691 -230.322695)
			(xy 62.522935 -230.396793) (xy 62.530994 -230.472174) (xy 62.531498 -230.51008) (xy 62.530994 -230.547986)
			(xy 62.522935 -230.623367) (xy 62.50691 -230.697465) (xy 62.4831 -230.76944) (xy 62.451774 -230.838476)
			(xy 62.413287 -230.903791) (xy 62.368076 -230.964646) (xy 62.316652 -231.02035) (xy 62.265544 -231.06507)
			(xy 84.927697 -231.06507) (xy 84.931732 -230.989366) (xy 84.943791 -230.914521) (xy 84.963737 -230.84138)
			(xy 84.991344 -230.770775) (xy 85.0263 -230.703504) (xy 85.068208 -230.640329) (xy 85.116594 -230.581967)
			(xy 85.17091 -230.529079) (xy 85.230539 -230.482264) (xy 85.294807 -230.442052) (xy 85.362984 -230.4089)
			(xy 85.4343 -230.383182) (xy 85.507945 -230.36519) (xy 85.583085 -230.355128) (xy 85.658869 -230.353109)
			(xy 85.734439 -230.359158) (xy 85.808937 -230.373205) (xy 85.88152 -230.395091) (xy 85.951366 -230.424568)
			(xy 86.017683 -230.461303) (xy 86.079719 -230.504878) (xy 86.136772 -230.5548) (xy 86.188196 -230.610504)
			(xy 86.233407 -230.671359) (xy 86.271894 -230.736674) (xy 86.30322 -230.80571) (xy 86.32703 -230.877685)
			(xy 86.343055 -230.951783) (xy 86.351114 -231.027164) (xy 86.351618 -231.06507) (xy 87.467697 -231.06507)
			(xy 87.471732 -230.989366) (xy 87.483791 -230.914521) (xy 87.503737 -230.84138) (xy 87.531344 -230.770775)
			(xy 87.5663 -230.703504) (xy 87.608208 -230.640329) (xy 87.656594 -230.581967) (xy 87.71091 -230.529079)
			(xy 87.770539 -230.482264) (xy 87.834807 -230.442052) (xy 87.902984 -230.4089) (xy 87.9743 -230.383182)
			(xy 88.047945 -230.36519) (xy 88.123085 -230.355128) (xy 88.198869 -230.353109) (xy 88.274439 -230.359158)
			(xy 88.348937 -230.373205) (xy 88.42152 -230.395091) (xy 88.491366 -230.424568) (xy 88.557683 -230.461303)
			(xy 88.619719 -230.504878) (xy 88.676772 -230.5548) (xy 88.728196 -230.610504) (xy 88.773407 -230.671359)
			(xy 88.811894 -230.736674) (xy 88.84322 -230.80571) (xy 88.86703 -230.877685) (xy 88.883055 -230.951783)
			(xy 88.891114 -231.027164) (xy 88.891618 -231.06507) (xy 90.007697 -231.06507) (xy 90.011732 -230.989366)
			(xy 90.023791 -230.914521) (xy 90.043737 -230.84138) (xy 90.071344 -230.770775) (xy 90.1063 -230.703504)
			(xy 90.148208 -230.640329) (xy 90.196594 -230.581967) (xy 90.25091 -230.529079) (xy 90.310539 -230.482264)
			(xy 90.374807 -230.442052) (xy 90.442984 -230.4089) (xy 90.5143 -230.383182) (xy 90.587945 -230.36519)
			(xy 90.663085 -230.355128) (xy 90.738869 -230.353109) (xy 90.814439 -230.359158) (xy 90.888937 -230.373205)
			(xy 90.96152 -230.395091) (xy 91.031366 -230.424568) (xy 91.097683 -230.461303) (xy 91.159719 -230.504878)
			(xy 91.165664 -230.51008) (xy 93.154506 -230.51008) (xy 93.158522 -230.39381) (xy 93.170549 -230.278095)
			(xy 93.190531 -230.163485) (xy 93.218373 -230.050526) (xy 93.253942 -229.939758) (xy 93.297068 -229.831707)
			(xy 93.347545 -229.726889) (xy 93.405134 -229.625804) (xy 93.46956 -229.528932) (xy 93.540515 -229.436736)
			(xy 93.617662 -229.349655) (xy 93.700633 -229.268104) (xy 93.789033 -229.192472) (xy 93.88244 -229.123118)
			(xy 93.980409 -229.060375) (xy 94.082473 -229.004539) (xy 94.188147 -228.955878) (xy 94.296926 -228.914624)
			(xy 94.408291 -228.880973) (xy 94.521714 -228.855085) (xy 94.636651 -228.837084) (xy 94.752557 -228.827055)
			(xy 94.868879 -228.825047) (xy 94.985062 -228.831069) (xy 95.100553 -228.845092) (xy 95.214801 -228.86705)
			(xy 95.327262 -228.896837) (xy 95.4374 -228.934312) (xy 95.54469 -228.979297) (xy 95.648621 -229.031576)
			(xy 95.748697 -229.090901) (xy 95.844443 -229.156989) (xy 95.9354 -229.229525) (xy 96.021136 -229.308164)
			(xy 96.101243 -229.39253) (xy 96.175339 -229.482222) (xy 96.243069 -229.576812) (xy 96.304113 -229.67585)
			(xy 96.358178 -229.778863) (xy 96.405008 -229.88536) (xy 96.444379 -229.994835) (xy 96.476103 -230.106765)
			(xy 96.500029 -230.220617) (xy 96.516043 -230.335849) (xy 96.52407 -230.451911) (xy 96.524572 -230.51008)
			(xy 96.52407 -230.568249) (xy 96.516043 -230.684311) (xy 96.500029 -230.799543) (xy 96.476103 -230.913395)
			(xy 96.444379 -231.025325) (xy 96.405008 -231.1348) (xy 96.358178 -231.241297) (xy 96.304113 -231.34431)
			(xy 96.243069 -231.443348) (xy 96.175339 -231.537938) (xy 96.101243 -231.62763) (xy 96.021136 -231.711996)
			(xy 95.9354 -231.790635) (xy 95.844443 -231.863171) (xy 95.748697 -231.929259) (xy 95.648621 -231.988584)
			(xy 95.54469 -232.040863) (xy 95.4374 -232.085848) (xy 95.327262 -232.123323) (xy 95.214801 -232.15311)
			(xy 95.100553 -232.175068) (xy 94.985062 -232.189091) (xy 94.868879 -232.195113) (xy 94.752557 -232.193105)
			(xy 94.636651 -232.183076) (xy 94.521714 -232.165075) (xy 94.408291 -232.139187) (xy 94.296926 -232.105536)
			(xy 94.188147 -232.064282) (xy 94.082473 -232.015621) (xy 93.980409 -231.959785) (xy 93.88244 -231.897042)
			(xy 93.789033 -231.827688) (xy 93.700633 -231.752056) (xy 93.617662 -231.670505) (xy 93.540515 -231.583424)
			(xy 93.46956 -231.491228) (xy 93.405134 -231.394356) (xy 93.347545 -231.293271) (xy 93.297068 -231.188453)
			(xy 93.253942 -231.080402) (xy 93.218373 -230.969634) (xy 93.190531 -230.856675) (xy 93.170549 -230.742065)
			(xy 93.158522 -230.62635) (xy 93.154506 -230.51008) (xy 91.165664 -230.51008) (xy 91.216772 -230.5548)
			(xy 91.268196 -230.610504) (xy 91.313407 -230.671359) (xy 91.351894 -230.736674) (xy 91.38322 -230.80571)
			(xy 91.40703 -230.877685) (xy 91.423055 -230.951783) (xy 91.431114 -231.027164) (xy 91.431618 -231.06507)
			(xy 91.431114 -231.102976) (xy 91.423055 -231.178357) (xy 91.40703 -231.252455) (xy 91.38322 -231.32443)
			(xy 91.351894 -231.393466) (xy 91.313407 -231.458781) (xy 91.268196 -231.519636) (xy 91.216772 -231.57534)
			(xy 91.159719 -231.625262) (xy 91.097683 -231.668837) (xy 91.031366 -231.705572) (xy 90.96152 -231.735049)
			(xy 90.888937 -231.756935) (xy 90.814439 -231.770982) (xy 90.738869 -231.777031) (xy 90.663085 -231.775012)
			(xy 90.587945 -231.76495) (xy 90.5143 -231.746958) (xy 90.442984 -231.72124) (xy 90.374807 -231.688088)
			(xy 90.310539 -231.647876) (xy 90.25091 -231.601061) (xy 90.196594 -231.548173) (xy 90.148208 -231.489811)
			(xy 90.1063 -231.426636) (xy 90.071344 -231.359365) (xy 90.043737 -231.28876) (xy 90.023791 -231.215619)
			(xy 90.011732 -231.140774) (xy 90.007697 -231.06507) (xy 88.891618 -231.06507) (xy 88.891114 -231.102976)
			(xy 88.883055 -231.178357) (xy 88.86703 -231.252455) (xy 88.84322 -231.32443) (xy 88.811894 -231.393466)
			(xy 88.773407 -231.458781) (xy 88.728196 -231.519636) (xy 88.676772 -231.57534) (xy 88.619719 -231.625262)
			(xy 88.557683 -231.668837) (xy 88.491366 -231.705572) (xy 88.42152 -231.735049) (xy 88.348937 -231.756935)
			(xy 88.274439 -231.770982) (xy 88.198869 -231.777031) (xy 88.123085 -231.775012) (xy 88.047945 -231.76495)
			(xy 87.9743 -231.746958) (xy 87.902984 -231.72124) (xy 87.834807 -231.688088) (xy 87.770539 -231.647876)
			(xy 87.71091 -231.601061) (xy 87.656594 -231.548173) (xy 87.608208 -231.489811) (xy 87.5663 -231.426636)
			(xy 87.531344 -231.359365) (xy 87.503737 -231.28876) (xy 87.483791 -231.215619) (xy 87.471732 -231.140774)
			(xy 87.467697 -231.06507) (xy 86.351618 -231.06507) (xy 86.351114 -231.102976) (xy 86.343055 -231.178357)
			(xy 86.32703 -231.252455) (xy 86.30322 -231.32443) (xy 86.271894 -231.393466) (xy 86.233407 -231.458781)
			(xy 86.188196 -231.519636) (xy 86.136772 -231.57534) (xy 86.079719 -231.625262) (xy 86.017683 -231.668837)
			(xy 85.951366 -231.705572) (xy 85.88152 -231.735049) (xy 85.808937 -231.756935) (xy 85.734439 -231.770982)
			(xy 85.658869 -231.777031) (xy 85.583085 -231.775012) (xy 85.507945 -231.76495) (xy 85.4343 -231.746958)
			(xy 85.362984 -231.72124) (xy 85.294807 -231.688088) (xy 85.230539 -231.647876) (xy 85.17091 -231.601061)
			(xy 85.116594 -231.548173) (xy 85.068208 -231.489811) (xy 85.0263 -231.426636) (xy 84.991344 -231.359365)
			(xy 84.963737 -231.28876) (xy 84.943791 -231.215619) (xy 84.931732 -231.140774) (xy 84.927697 -231.06507)
			(xy 62.265544 -231.06507) (xy 62.259599 -231.070272) (xy 62.197563 -231.113847) (xy 62.131246 -231.150582)
			(xy 62.0614 -231.180059) (xy 61.988817 -231.201945) (xy 61.914319 -231.215992) (xy 61.838749 -231.222041)
			(xy 61.762965 -231.220022) (xy 61.687825 -231.20996) (xy 61.61418 -231.191968) (xy 61.542864 -231.16625)
			(xy 61.474687 -231.133098) (xy 61.410419 -231.092886) (xy 61.35079 -231.046071) (xy 61.296474 -230.993183)
			(xy 61.248088 -230.934821) (xy 61.20618 -230.871646) (xy 61.171224 -230.804375) (xy 61.143617 -230.73377)
			(xy 61.123671 -230.660629) (xy 61.111612 -230.585784) (xy 61.107577 -230.51008) (xy 59.991498 -230.51008)
			(xy 59.990994 -230.547986) (xy 59.982935 -230.623367) (xy 59.96691 -230.697465) (xy 59.9431 -230.76944)
			(xy 59.911774 -230.838476) (xy 59.873287 -230.903791) (xy 59.828076 -230.964646) (xy 59.776652 -231.02035)
			(xy 59.719599 -231.070272) (xy 59.657563 -231.113847) (xy 59.591246 -231.150582) (xy 59.5214 -231.180059)
			(xy 59.448817 -231.201945) (xy 59.374319 -231.215992) (xy 59.298749 -231.222041) (xy 59.222965 -231.220022)
			(xy 59.147825 -231.20996) (xy 59.07418 -231.191968) (xy 59.002864 -231.16625) (xy 58.934687 -231.133098)
			(xy 58.870419 -231.092886) (xy 58.81079 -231.046071) (xy 58.756474 -230.993183) (xy 58.708088 -230.934821)
			(xy 58.66618 -230.871646) (xy 58.631224 -230.804375) (xy 58.603617 -230.73377) (xy 58.583671 -230.660629)
			(xy 58.571612 -230.585784) (xy 58.567577 -230.51008) (xy 57.451498 -230.51008) (xy 57.450994 -230.547986)
			(xy 57.442935 -230.623367) (xy 57.42691 -230.697465) (xy 57.4031 -230.76944) (xy 57.371774 -230.838476)
			(xy 57.333287 -230.903791) (xy 57.288076 -230.964646) (xy 57.236652 -231.02035) (xy 57.179599 -231.070272)
			(xy 57.117563 -231.113847) (xy 57.051246 -231.150582) (xy 56.9814 -231.180059) (xy 56.908817 -231.201945)
			(xy 56.834319 -231.215992) (xy 56.758749 -231.222041) (xy 56.682965 -231.220022) (xy 56.607825 -231.20996)
			(xy 56.53418 -231.191968) (xy 56.462864 -231.16625) (xy 56.394687 -231.133098) (xy 56.330419 -231.092886)
			(xy 56.27079 -231.046071) (xy 56.216474 -230.993183) (xy 56.168088 -230.934821) (xy 56.12618 -230.871646)
			(xy 56.091224 -230.804375) (xy 56.063617 -230.73377) (xy 56.043671 -230.660629) (xy 56.031612 -230.585784)
			(xy 56.027577 -230.51008) (xy 54.911498 -230.51008) (xy 54.910994 -230.547986) (xy 54.902935 -230.623367)
			(xy 54.88691 -230.697465) (xy 54.8631 -230.76944) (xy 54.831774 -230.838476) (xy 54.793287 -230.903791)
			(xy 54.748076 -230.964646) (xy 54.696652 -231.02035) (xy 54.639599 -231.070272) (xy 54.577563 -231.113847)
			(xy 54.511246 -231.150582) (xy 54.4414 -231.180059) (xy 54.368817 -231.201945) (xy 54.294319 -231.215992)
			(xy 54.218749 -231.222041) (xy 54.142965 -231.220022) (xy 54.067825 -231.20996) (xy 53.99418 -231.191968)
			(xy 53.922864 -231.16625) (xy 53.854687 -231.133098) (xy 53.790419 -231.092886) (xy 53.73079 -231.046071)
			(xy 53.676474 -230.993183) (xy 53.628088 -230.934821) (xy 53.58618 -230.871646) (xy 53.551224 -230.804375)
			(xy 53.523617 -230.73377) (xy 53.503671 -230.660629) (xy 53.491612 -230.585784) (xy 53.487577 -230.51008)
			(xy 52.371498 -230.51008) (xy 52.370994 -230.547986) (xy 52.362935 -230.623367) (xy 52.34691 -230.697465)
			(xy 52.3231 -230.76944) (xy 52.291774 -230.838476) (xy 52.253287 -230.903791) (xy 52.208076 -230.964646)
			(xy 52.156652 -231.02035) (xy 52.099599 -231.070272) (xy 52.037563 -231.113847) (xy 51.971246 -231.150582)
			(xy 51.9014 -231.180059) (xy 51.828817 -231.201945) (xy 51.754319 -231.215992) (xy 51.678749 -231.222041)
			(xy 51.602965 -231.220022) (xy 51.527825 -231.20996) (xy 51.45418 -231.191968) (xy 51.382864 -231.16625)
			(xy 51.314687 -231.133098) (xy 51.250419 -231.092886) (xy 51.19079 -231.046071) (xy 51.136474 -230.993183)
			(xy 51.088088 -230.934821) (xy 51.04618 -230.871646) (xy 51.011224 -230.804375) (xy 50.983617 -230.73377)
			(xy 50.963671 -230.660629) (xy 50.951612 -230.585784) (xy 50.947577 -230.51008) (xy 49.831498 -230.51008)
			(xy 49.830994 -230.547986) (xy 49.822935 -230.623367) (xy 49.80691 -230.697465) (xy 49.7831 -230.76944)
			(xy 49.751774 -230.838476) (xy 49.713287 -230.903791) (xy 49.668076 -230.964646) (xy 49.616652 -231.02035)
			(xy 49.559599 -231.070272) (xy 49.497563 -231.113847) (xy 49.431246 -231.150582) (xy 49.3614 -231.180059)
			(xy 49.288817 -231.201945) (xy 49.214319 -231.215992) (xy 49.138749 -231.222041) (xy 49.062965 -231.220022)
			(xy 48.987825 -231.20996) (xy 48.91418 -231.191968) (xy 48.842864 -231.16625) (xy 48.774687 -231.133098)
			(xy 48.710419 -231.092886) (xy 48.65079 -231.046071) (xy 48.596474 -230.993183) (xy 48.548088 -230.934821)
			(xy 48.50618 -230.871646) (xy 48.471224 -230.804375) (xy 48.443617 -230.73377) (xy 48.423671 -230.660629)
			(xy 48.411612 -230.585784) (xy 48.407577 -230.51008) (xy 47.291498 -230.51008) (xy 47.290994 -230.547986)
			(xy 47.282935 -230.623367) (xy 47.26691 -230.697465) (xy 47.2431 -230.76944) (xy 47.211774 -230.838476)
			(xy 47.173287 -230.903791) (xy 47.128076 -230.964646) (xy 47.076652 -231.02035) (xy 47.019599 -231.070272)
			(xy 46.957563 -231.113847) (xy 46.891246 -231.150582) (xy 46.8214 -231.180059) (xy 46.748817 -231.201945)
			(xy 46.674319 -231.215992) (xy 46.598749 -231.222041) (xy 46.522965 -231.220022) (xy 46.447825 -231.20996)
			(xy 46.37418 -231.191968) (xy 46.302864 -231.16625) (xy 46.234687 -231.133098) (xy 46.170419 -231.092886)
			(xy 46.11079 -231.046071) (xy 46.056474 -230.993183) (xy 46.008088 -230.934821) (xy 45.96618 -230.871646)
			(xy 45.931224 -230.804375) (xy 45.903617 -230.73377) (xy 45.883671 -230.660629) (xy 45.871612 -230.585784)
			(xy 45.867577 -230.51008) (xy 44.751244 -230.51008) (xy 44.751244 -231.221788) (xy 43.328336 -231.221788)
			(xy 43.328336 -229.798372) (xy 43.055152 -229.798372) (xy 43.014974 -229.889744) (xy 42.961022 -229.99254)
			(xy 42.900108 -230.091368) (xy 42.83252 -230.185759) (xy 42.758581 -230.275261) (xy 42.678643 -230.359449)
			(xy 42.593088 -230.437922) (xy 42.502322 -230.510305) (xy 42.406779 -230.576254) (xy 42.306914 -230.635454)
			(xy 42.203202 -230.687623) (xy 42.096139 -230.732512) (xy 41.986233 -230.769908) (xy 41.874009 -230.799633)
			(xy 41.760003 -230.821544) (xy 41.644756 -230.835537) (xy 41.528818 -230.841546) (xy 41.412742 -230.839543)
			(xy 41.29708 -230.829535) (xy 41.182385 -230.811572) (xy 41.069202 -230.785739) (xy 40.958071 -230.752159)
			(xy 40.849522 -230.710991) (xy 40.744072 -230.662433) (xy 40.642223 -230.606716) (xy 40.54446 -230.544104)
			(xy 40.45125 -230.474897) (xy 40.363037 -230.399424) (xy 40.280241 -230.318045) (xy 40.203257 -230.231148)
			(xy 40.132452 -230.139147) (xy 40.068162 -230.04248) (xy 40.010695 -229.941608) (xy 39.960324 -229.837011)
			(xy 39.917289 -229.729188) (xy 39.881795 -229.618654) (xy 39.854012 -229.505934) (xy 39.834072 -229.391566)
			(xy 39.82207 -229.276094) (xy 39.818063 -229.16007) (xy 36.341678 -229.16007) (xy 36.361593 -229.192234)
			(xy 36.400327 -229.270023) (xy 36.431719 -229.351055) (xy 36.4555 -229.434637) (xy 36.471468 -229.520057)
			(xy 36.479486 -229.606586) (xy 36.479988 -229.650036) (xy 36.479486 -229.693486) (xy 36.471468 -229.780015)
			(xy 36.4555 -229.865435) (xy 36.431719 -229.949017) (xy 36.400327 -230.030049) (xy 36.361593 -230.107838)
			(xy 36.315846 -230.181722) (xy 36.263477 -230.251069) (xy 36.204933 -230.315289) (xy 36.140713 -230.373833)
			(xy 36.071366 -230.426202) (xy 35.997482 -230.471949) (xy 35.919693 -230.510683) (xy 35.838661 -230.542075)
			(xy 35.755079 -230.565856) (xy 35.669659 -230.581824) (xy 35.58313 -230.589842) (xy 35.49623 -230.589842)
			(xy 35.409701 -230.581824) (xy 35.324281 -230.565856) (xy 35.240699 -230.542075) (xy 35.159667 -230.510683)
			(xy 35.081878 -230.471949) (xy 35.007994 -230.426202) (xy 34.938647 -230.373833) (xy 34.874427 -230.315289)
			(xy 34.815883 -230.251069) (xy 34.763514 -230.181722) (xy 34.717767 -230.107838) (xy 34.679033 -230.030049)
			(xy 34.647641 -229.949017) (xy 34.62386 -229.865435) (xy 34.607892 -229.780015) (xy 34.599874 -229.693486)
			(xy 31.399486 -229.693486) (xy 31.391468 -229.780015) (xy 31.3755 -229.865435) (xy 31.351719 -229.949017)
			(xy 31.320327 -230.030049) (xy 31.281593 -230.107838) (xy 31.235846 -230.181722) (xy 31.183477 -230.251069)
			(xy 31.124933 -230.315289) (xy 31.060713 -230.373833) (xy 30.991366 -230.426202) (xy 30.917482 -230.471949)
			(xy 30.839693 -230.510683) (xy 30.758661 -230.542075) (xy 30.675079 -230.565856) (xy 30.589659 -230.581824)
			(xy 30.50313 -230.589842) (xy 30.41623 -230.589842) (xy 30.329701 -230.581824) (xy 30.244281 -230.565856)
			(xy 30.160699 -230.542075) (xy 30.079667 -230.510683) (xy 30.001878 -230.471949) (xy 29.927994 -230.426202)
			(xy 29.858647 -230.373833) (xy 29.794427 -230.315289) (xy 29.735883 -230.251069) (xy 29.683514 -230.181722)
			(xy 29.637767 -230.107838) (xy 29.599033 -230.030049) (xy 29.567641 -229.949017) (xy 29.54386 -229.865435)
			(xy 29.527892 -229.780015) (xy 29.519874 -229.693486) (xy 28.942538 -229.693486) (xy 28.942538 -235.294678)
			(xy 85.880192 -235.294678) (xy 85.884263 -235.239056) (xy 85.896389 -235.184619) (xy 85.916312 -235.132528)
			(xy 85.943608 -235.083893) (xy 85.977694 -235.03975) (xy 86.017843 -235.001041) (xy 86.063201 -234.96859)
			(xy 86.112801 -234.943089) (xy 86.165585 -234.925082) (xy 86.220428 -234.914952) (xy 86.276162 -234.912915)
			(xy 86.331599 -234.919015) (xy 86.385556 -234.933121) (xy 86.436885 -234.954933) (xy 86.484491 -234.983987)
			(xy 86.527359 -235.019662) (xy 86.564576 -235.061199) (xy 86.595349 -235.107712) (xy 86.619021 -235.158209)
			(xy 86.635089 -235.211616) (xy 86.643209 -235.266792) (xy 86.643718 -235.294678) (xy 86.643209 -235.322564)
			(xy 86.635089 -235.37774) (xy 86.619021 -235.431147) (xy 86.595349 -235.481644) (xy 86.564576 -235.528157)
			(xy 86.527359 -235.569694) (xy 86.484491 -235.605369) (xy 86.436885 -235.634423) (xy 86.385556 -235.656235)
			(xy 86.331599 -235.670341) (xy 86.276162 -235.676441) (xy 86.220428 -235.674404) (xy 86.165585 -235.664274)
			(xy 86.112801 -235.646267) (xy 86.063201 -235.620766) (xy 86.017843 -235.588315) (xy 85.977694 -235.549606)
			(xy 85.943608 -235.505463) (xy 85.916312 -235.456828) (xy 85.896389 -235.404737) (xy 85.884263 -235.3503)
			(xy 85.880192 -235.294678) (xy 28.942538 -235.294678) (xy 28.942538 -235.829856) (xy 84.276182 -235.829856)
			(xy 84.280253 -235.774234) (xy 84.292379 -235.719797) (xy 84.312302 -235.667706) (xy 84.339598 -235.619071)
			(xy 84.373684 -235.574928) (xy 84.413833 -235.536219) (xy 84.459191 -235.503768) (xy 84.508791 -235.478267)
			(xy 84.561575 -235.46026) (xy 84.616418 -235.45013) (xy 84.672152 -235.448093) (xy 84.727589 -235.454193)
			(xy 84.781546 -235.468299) (xy 84.832875 -235.490111) (xy 84.880481 -235.519165) (xy 84.923349 -235.55484)
			(xy 84.960566 -235.596377) (xy 84.991339 -235.64289) (xy 85.015011 -235.693387) (xy 85.031079 -235.746794)
			(xy 85.039199 -235.80197) (xy 85.039708 -235.829856) (xy 85.039199 -235.857742) (xy 85.031079 -235.912918)
			(xy 85.015011 -235.966325) (xy 84.991339 -236.016822) (xy 84.960566 -236.063335) (xy 84.923349 -236.104872)
			(xy 84.880481 -236.140547) (xy 84.832875 -236.169601) (xy 84.781546 -236.191413) (xy 84.727589 -236.205519)
			(xy 84.672152 -236.211619) (xy 84.616418 -236.209582) (xy 84.561575 -236.199452) (xy 84.508791 -236.181445)
			(xy 84.459191 -236.155944) (xy 84.413833 -236.123493) (xy 84.373684 -236.084784) (xy 84.339598 -236.040641)
			(xy 84.312302 -235.992006) (xy 84.292379 -235.939915) (xy 84.280253 -235.885478) (xy 84.276182 -235.829856)
			(xy 28.942538 -235.829856) (xy 28.942538 -236.214412) (xy 81.880454 -236.214412) (xy 81.884525 -236.15879)
			(xy 81.896651 -236.104353) (xy 81.916574 -236.052262) (xy 81.94387 -236.003627) (xy 81.977956 -235.959484)
			(xy 82.018105 -235.920775) (xy 82.063463 -235.888324) (xy 82.113063 -235.862823) (xy 82.165847 -235.844816)
			(xy 82.22069 -235.834686) (xy 82.276424 -235.832649) (xy 82.331861 -235.838749) (xy 82.385818 -235.852855)
			(xy 82.437147 -235.874667) (xy 82.484753 -235.903721) (xy 82.527621 -235.939396) (xy 82.564838 -235.980933)
			(xy 82.595611 -236.027446) (xy 82.619283 -236.077943) (xy 82.635351 -236.13135) (xy 82.643471 -236.186526)
			(xy 82.64398 -236.214412) (xy 82.643471 -236.242298) (xy 82.635351 -236.297474) (xy 82.619283 -236.350881)
			(xy 82.595611 -236.401378) (xy 82.564838 -236.447891) (xy 82.527621 -236.489428) (xy 82.484753 -236.525103)
			(xy 82.437147 -236.554157) (xy 82.385818 -236.575969) (xy 82.331861 -236.590075) (xy 82.276424 -236.596175)
			(xy 82.22069 -236.594138) (xy 82.165847 -236.584008) (xy 82.113063 -236.566001) (xy 82.063463 -236.5405)
			(xy 82.018105 -236.508049) (xy 81.977956 -236.46934) (xy 81.94387 -236.425197) (xy 81.916574 -236.376562)
			(xy 81.896651 -236.324471) (xy 81.884525 -236.270034) (xy 81.880454 -236.214412) (xy 28.942538 -236.214412)
			(xy 28.942538 -237.048548) (xy 83.078064 -237.048548) (xy 83.082135 -236.992926) (xy 83.094261 -236.938489)
			(xy 83.114184 -236.886398) (xy 83.14148 -236.837763) (xy 83.175566 -236.79362) (xy 83.215715 -236.754911)
			(xy 83.261073 -236.72246) (xy 83.310673 -236.696959) (xy 83.363457 -236.678952) (xy 83.4183 -236.668822)
			(xy 83.474034 -236.666785) (xy 83.529471 -236.672885) (xy 83.583428 -236.686991) (xy 83.634757 -236.708803)
			(xy 83.682363 -236.737857) (xy 83.725231 -236.773532) (xy 83.762448 -236.815069) (xy 83.793221 -236.861582)
			(xy 83.816893 -236.912079) (xy 83.832961 -236.965486) (xy 83.841081 -237.020662) (xy 83.84159 -237.048548)
			(xy 83.841081 -237.076434) (xy 83.832961 -237.13161) (xy 83.822569 -237.16615) (xy 86.906606 -237.16615)
			(xy 86.910677 -237.110528) (xy 86.922803 -237.056091) (xy 86.942726 -237.004) (xy 86.970022 -236.955365)
			(xy 87.004108 -236.911222) (xy 87.044257 -236.872513) (xy 87.089615 -236.840062) (xy 87.139215 -236.814561)
			(xy 87.191999 -236.796554) (xy 87.246842 -236.786424) (xy 87.302576 -236.784387) (xy 87.358013 -236.790487)
			(xy 87.41197 -236.804593) (xy 87.463299 -236.826405) (xy 87.510905 -236.855459) (xy 87.553773 -236.891134)
			(xy 87.59099 -236.932671) (xy 87.621763 -236.979184) (xy 87.645435 -237.029681) (xy 87.661503 -237.083088)
			(xy 87.669623 -237.138264) (xy 87.670132 -237.16615) (xy 87.669623 -237.194036) (xy 87.661503 -237.249212)
			(xy 87.645435 -237.302619) (xy 87.621763 -237.353116) (xy 87.59099 -237.399629) (xy 87.553773 -237.441166)
			(xy 87.510905 -237.476841) (xy 87.463299 -237.505895) (xy 87.41197 -237.527707) (xy 87.358013 -237.541813)
			(xy 87.302576 -237.547913) (xy 87.246842 -237.545876) (xy 87.191999 -237.535746) (xy 87.139215 -237.517739)
			(xy 87.089615 -237.492238) (xy 87.044257 -237.459787) (xy 87.004108 -237.421078) (xy 86.970022 -237.376935)
			(xy 86.942726 -237.3283) (xy 86.922803 -237.276209) (xy 86.910677 -237.221772) (xy 86.906606 -237.16615)
			(xy 83.822569 -237.16615) (xy 83.816893 -237.185017) (xy 83.793221 -237.235514) (xy 83.762448 -237.282027)
			(xy 83.725231 -237.323564) (xy 83.682363 -237.359239) (xy 83.634757 -237.388293) (xy 83.583428 -237.410105)
			(xy 83.529471 -237.424211) (xy 83.474034 -237.430311) (xy 83.4183 -237.428274) (xy 83.363457 -237.418144)
			(xy 83.310673 -237.400137) (xy 83.261073 -237.374636) (xy 83.215715 -237.342185) (xy 83.175566 -237.303476)
			(xy 83.14148 -237.259333) (xy 83.114184 -237.210698) (xy 83.094261 -237.158607) (xy 83.082135 -237.10417)
			(xy 83.078064 -237.048548) (xy 28.942538 -237.048548) (xy 28.942538 -237.986199) (xy 44.224173 -237.986199)
			(xy 44.224173 -237.922933) (xy 44.232431 -237.860209) (xy 44.248805 -237.7991) (xy 44.273016 -237.74065)
			(xy 44.304649 -237.685861) (xy 44.343162 -237.635669) (xy 44.387897 -237.590934) (xy 44.438089 -237.552421)
			(xy 44.492878 -237.520788) (xy 44.551328 -237.496577) (xy 44.612437 -237.480203) (xy 44.675161 -237.471945)
			(xy 44.738427 -237.471945) (xy 44.801151 -237.480203) (xy 44.86226 -237.496577) (xy 44.92071 -237.520788)
			(xy 44.975499 -237.552421) (xy 45.025691 -237.590934) (xy 45.048424 -237.612936) (xy 45.161962 -237.726474)
			(xy 45.1741 -237.737861) (xy 45.202876 -237.754555) (xy 45.234991 -237.763233) (xy 45.251624 -237.763812)
			(xy 46.030642 -237.763812) (xy 46.058931 -237.764181) (xy 46.115126 -237.770737) (xy 46.170168 -237.783824)
			(xy 46.2233 -237.803263) (xy 46.273793 -237.828786) (xy 46.297596 -237.844076) (xy 46.329346 -237.865412)
			(xy 46.386496 -237.865412) (xy 46.386496 -237.920276) (xy 46.406327 -237.942626) (xy 46.440973 -237.991307)
			(xy 46.469348 -238.043891) (xy 46.491019 -238.099574) (xy 46.505654 -238.157505) (xy 46.513029 -238.216799)
			(xy 46.513032 -238.276551) (xy 46.505663 -238.335846) (xy 46.491034 -238.393778) (xy 46.469369 -238.449464)
			(xy 46.441 -238.50205) (xy 46.406358 -238.550735) (xy 46.386496 -238.573056) (xy 46.386496 -238.62792)
			(xy 46.329346 -238.62792) (xy 46.297596 -238.649256) (xy 46.273789 -238.664536) (xy 46.223286 -238.690028)
			(xy 46.170153 -238.709452) (xy 46.115116 -238.722545) (xy 46.058928 -238.729128) (xy 46.030642 -238.72952)
			(xy 44.798742 -238.72952) (xy 44.365164 -238.296196) (xy 44.343162 -238.273463) (xy 44.304649 -238.223271)
			(xy 44.273016 -238.168482) (xy 44.248805 -238.110032) (xy 44.232431 -238.048923) (xy 44.224173 -237.986199)
			(xy 28.942538 -237.986199) (xy 28.942538 -239.944031) (xy 44.218585 -239.944031) (xy 44.218585 -239.880765)
			(xy 44.226843 -239.818041) (xy 44.243217 -239.756932) (xy 44.267428 -239.698482) (xy 44.299061 -239.643693)
			(xy 44.337574 -239.593501) (xy 44.359576 -239.570768) (xy 44.744386 -239.186212) (xy 46.008036 -239.186212)
			(xy 46.0363 -239.186574) (xy 46.092443 -239.193153) (xy 46.147431 -239.20625) (xy 46.200512 -239.225687)
			(xy 46.250955 -239.251197) (xy 46.274736 -239.266476) (xy 46.30674 -239.287558) (xy 46.469554 -239.287558)
			(xy 46.503336 -239.262158) (xy 46.52981 -239.24296) (xy 46.586745 -239.210789) (xy 46.647336 -239.186184)
			(xy 46.710582 -239.169551) (xy 46.775438 -239.161166) (xy 46.840834 -239.161166) (xy 46.90569 -239.169551)
			(xy 46.968936 -239.186184) (xy 47.029527 -239.210789) (xy 47.086462 -239.24296) (xy 47.112936 -239.262158)
			(xy 47.146718 -239.287558) (xy 47.164244 -239.287558) (xy 47.164244 -239.306354) (xy 47.187897 -239.330333)
			(xy 47.229336 -239.383431) (xy 47.2634 -239.441537) (xy 47.289493 -239.503632) (xy 47.307156 -239.568629)
			(xy 47.316082 -239.635389) (xy 47.316644 -239.669066) (xy 47.316644 -240.629863) (xy 49.037484 -240.629863)
			(xy 49.037484 -240.548753) (xy 49.045434 -240.468034) (xy 49.061257 -240.388483) (xy 49.084802 -240.310867)
			(xy 49.115841 -240.235931) (xy 49.154076 -240.164399) (xy 49.199138 -240.096959) (xy 49.250593 -240.03426)
			(xy 49.307946 -239.976907) (xy 49.370645 -239.925452) (xy 49.438085 -239.88039) (xy 49.509617 -239.842155)
			(xy 49.584553 -239.811116) (xy 49.662169 -239.787571) (xy 49.74172 -239.771748) (xy 49.822439 -239.763798)
			(xy 49.903549 -239.763798) (xy 49.984268 -239.771748) (xy 50.063819 -239.787571) (xy 50.141435 -239.811116)
			(xy 50.216371 -239.842155) (xy 50.287903 -239.88039) (xy 50.355343 -239.925452) (xy 50.410622 -239.970818)
			(xy 69.586856 -239.970818) (xy 69.586856 -238.953294) (xy 69.587538 -238.917228) (xy 69.597867 -238.845836)
			(xy 69.60743 -238.811054) (xy 69.612256 -238.793528) (xy 69.612256 -238.41964) (xy 70.578472 -238.41964)
			(xy 70.578472 -238.793528) (xy 70.583298 -238.811054) (xy 70.592846 -238.845839) (xy 70.603169 -238.917229)
			(xy 70.603872 -238.953294) (xy 70.603872 -239.126268) (xy 70.914768 -239.126268) (xy 70.914768 -238.108744)
			(xy 70.915296 -238.076009) (xy 70.923731 -238.011085) (xy 70.940429 -237.947781) (xy 70.965113 -237.887142)
			(xy 70.997375 -237.830174) (xy 71.016622 -237.80369) (xy 71.041768 -237.769908) (xy 71.041768 -237.752636)
			(xy 71.057262 -237.752636) (xy 71.093076 -237.72241) (xy 71.118253 -237.701557) (xy 71.172985 -237.665806)
			(xy 71.23185 -237.637367) (xy 71.293875 -237.616712) (xy 71.358037 -237.604181) (xy 71.423276 -237.599981)
			(xy 71.488515 -237.604181) (xy 71.552677 -237.616712) (xy 71.614702 -237.637367) (xy 71.673567 -237.665806)
			(xy 71.728299 -237.701557) (xy 71.753476 -237.72241) (xy 71.78929 -237.752636) (xy 71.804784 -237.752636)
			(xy 71.804784 -237.769908) (xy 71.82993 -237.80369) (xy 71.850955 -237.832744) (xy 71.885503 -237.89559)
			(xy 71.898764 -237.928912) (xy 71.904588 -237.943179) (xy 71.922033 -237.968573) (xy 71.945059 -237.989041)
			(xy 71.972323 -238.003389) (xy 72.002232 -238.010779) (xy 72.03304 -238.010779) (xy 72.062949 -238.003389)
			(xy 72.090213 -237.989041) (xy 72.113239 -237.968573) (xy 72.130684 -237.943179) (xy 72.136508 -237.928912)
			(xy 72.149782 -237.895596) (xy 72.184321 -237.832746) (xy 72.205342 -237.80369) (xy 72.230488 -237.769908)
			(xy 72.230488 -237.752636) (xy 72.245982 -237.752636) (xy 72.281796 -237.72241) (xy 72.306973 -237.701557)
			(xy 72.361705 -237.665806) (xy 72.42057 -237.637367) (xy 72.482595 -237.616712) (xy 72.546757 -237.604181)
			(xy 72.611996 -237.599981) (xy 72.677235 -237.604181) (xy 72.741397 -237.616712) (xy 72.803422 -237.637367)
			(xy 72.862287 -237.665806) (xy 72.917019 -237.701557) (xy 72.942196 -237.72241) (xy 72.97801 -237.752636)
			(xy 72.993504 -237.752636) (xy 72.993504 -237.769908) (xy 73.01865 -237.80369) (xy 73.037896 -237.830174)
			(xy 73.07016 -237.887142) (xy 73.094845 -237.94778) (xy 73.111544 -238.011085) (xy 73.11849 -238.064548)
			(xy 85.002622 -238.064548) (xy 85.006693 -238.008926) (xy 85.018819 -237.954489) (xy 85.038742 -237.902398)
			(xy 85.066038 -237.853763) (xy 85.100124 -237.80962) (xy 85.140273 -237.770911) (xy 85.185631 -237.73846)
			(xy 85.235231 -237.712959) (xy 85.288015 -237.694952) (xy 85.342858 -237.684822) (xy 85.398592 -237.682785)
			(xy 85.454029 -237.688885) (xy 85.507986 -237.702991) (xy 85.559315 -237.724803) (xy 85.606921 -237.753857)
			(xy 85.649789 -237.789532) (xy 85.687006 -237.831069) (xy 85.717779 -237.877582) (xy 85.741451 -237.928079)
			(xy 85.757519 -237.981486) (xy 85.765639 -238.036662) (xy 85.766148 -238.064548) (xy 85.765639 -238.092434)
			(xy 85.757519 -238.14761) (xy 85.741451 -238.201017) (xy 85.717779 -238.251514) (xy 85.687006 -238.298027)
			(xy 85.649789 -238.339564) (xy 85.606921 -238.375239) (xy 85.559315 -238.404293) (xy 85.507986 -238.426105)
			(xy 85.454029 -238.440211) (xy 85.398592 -238.446311) (xy 85.342858 -238.444274) (xy 85.288015 -238.434144)
			(xy 85.235231 -238.416137) (xy 85.185631 -238.390636) (xy 85.140273 -238.358185) (xy 85.100124 -238.319476)
			(xy 85.066038 -238.275333) (xy 85.038742 -238.226698) (xy 85.018819 -238.174607) (xy 85.006693 -238.12017)
			(xy 85.002622 -238.064548) (xy 73.11849 -238.064548) (xy 73.119979 -238.076009) (xy 73.120504 -238.108744)
			(xy 73.120504 -239.059212) (xy 80.53146 -239.059212) (xy 80.535531 -239.00359) (xy 80.547657 -238.949153)
			(xy 80.56758 -238.897062) (xy 80.594876 -238.848427) (xy 80.628962 -238.804284) (xy 80.669111 -238.765575)
			(xy 80.714469 -238.733124) (xy 80.764069 -238.707623) (xy 80.816853 -238.689616) (xy 80.871696 -238.679486)
			(xy 80.92743 -238.677449) (xy 80.982867 -238.683549) (xy 81.036824 -238.697655) (xy 81.05682 -238.706152)
			(xy 82.586066 -238.706152) (xy 82.590137 -238.65053) (xy 82.602263 -238.596093) (xy 82.622186 -238.544002)
			(xy 82.649482 -238.495367) (xy 82.683568 -238.451224) (xy 82.723717 -238.412515) (xy 82.769075 -238.380064)
			(xy 82.818675 -238.354563) (xy 82.871459 -238.336556) (xy 82.926302 -238.326426) (xy 82.982036 -238.324389)
			(xy 83.037473 -238.330489) (xy 83.09143 -238.344595) (xy 83.142759 -238.366407) (xy 83.190365 -238.395461)
			(xy 83.233233 -238.431136) (xy 83.27045 -238.472673) (xy 83.301223 -238.519186) (xy 83.324895 -238.569683)
			(xy 83.340963 -238.62309) (xy 83.349083 -238.678266) (xy 83.349592 -238.706152) (xy 83.349083 -238.734038)
			(xy 83.340963 -238.789214) (xy 83.324895 -238.842621) (xy 83.301223 -238.893118) (xy 83.27045 -238.939631)
			(xy 83.233233 -238.981168) (xy 83.190365 -239.016843) (xy 83.142759 -239.045897) (xy 83.09143 -239.067709)
			(xy 83.037473 -239.081815) (xy 82.982036 -239.087915) (xy 82.926302 -239.085878) (xy 82.871459 -239.075748)
			(xy 82.818675 -239.057741) (xy 82.769075 -239.03224) (xy 82.723717 -238.999789) (xy 82.683568 -238.96108)
			(xy 82.649482 -238.916937) (xy 82.622186 -238.868302) (xy 82.602263 -238.816211) (xy 82.590137 -238.761774)
			(xy 82.586066 -238.706152) (xy 81.05682 -238.706152) (xy 81.088153 -238.719467) (xy 81.135759 -238.748521)
			(xy 81.178627 -238.784196) (xy 81.215844 -238.825733) (xy 81.246617 -238.872246) (xy 81.270289 -238.922743)
			(xy 81.286357 -238.97615) (xy 81.294477 -239.031326) (xy 81.294986 -239.059212) (xy 81.294477 -239.087098)
			(xy 81.286357 -239.142274) (xy 81.270289 -239.195681) (xy 81.246617 -239.246178) (xy 81.215844 -239.292691)
			(xy 81.178627 -239.334228) (xy 81.135759 -239.369903) (xy 81.088153 -239.398957) (xy 81.036824 -239.420769)
			(xy 80.982867 -239.434875) (xy 80.92743 -239.440975) (xy 80.871696 -239.438938) (xy 80.816853 -239.428808)
			(xy 80.764069 -239.410801) (xy 80.714469 -239.3853) (xy 80.669111 -239.352849) (xy 80.628962 -239.31414)
			(xy 80.594876 -239.269997) (xy 80.56758 -239.221362) (xy 80.547657 -239.169271) (xy 80.535531 -239.114834)
			(xy 80.53146 -239.059212) (xy 73.120504 -239.059212) (xy 73.120504 -239.126268) (xy 73.12005 -239.157611)
			(xy 73.112358 -239.219824) (xy 73.097073 -239.280619) (xy 73.074429 -239.339073) (xy 73.044769 -239.394298)
			(xy 73.008543 -239.445457) (xy 72.966301 -239.491774) (xy 72.918684 -239.532544) (xy 72.866415 -239.56715)
			(xy 72.810287 -239.595065) (xy 72.751153 -239.615867) (xy 72.689909 -239.629239) (xy 72.627486 -239.634978)
			(xy 72.564831 -239.632998) (xy 72.502895 -239.623329) (xy 72.442618 -239.606116) (xy 72.384915 -239.581622)
			(xy 72.330661 -239.550218) (xy 72.280682 -239.512381) (xy 72.235734 -239.468685) (xy 72.215756 -239.44453)
			(xy 72.201121 -239.427127) (xy 72.166789 -239.397319) (xy 72.127704 -239.37409) (xy 72.085112 -239.358181)
			(xy 72.040369 -239.350097) (xy 71.994903 -239.350097) (xy 71.95016 -239.358181) (xy 71.907568 -239.37409)
			(xy 71.868483 -239.397319) (xy 71.834151 -239.427127) (xy 71.819516 -239.44453) (xy 71.799608 -239.468737)
			(xy 71.754646 -239.51241) (xy 71.704657 -239.550224) (xy 71.650399 -239.581606) (xy 71.592694 -239.606081)
			(xy 71.532419 -239.623277) (xy 71.470487 -239.632933) (xy 71.407838 -239.634903) (xy 71.345421 -239.629156)
			(xy 71.284185 -239.615781) (xy 71.225057 -239.594979) (xy 71.168934 -239.567067) (xy 71.116669 -239.532467)
			(xy 71.069053 -239.491705) (xy 71.026809 -239.445399) (xy 70.990577 -239.394252) (xy 70.960907 -239.339038)
			(xy 70.93825 -239.280596) (xy 70.922949 -239.219812) (xy 70.915236 -239.157608) (xy 70.914768 -239.126268)
			(xy 70.603872 -239.126268) (xy 70.603872 -239.711484) (xy 84.07984 -239.711484) (xy 84.083911 -239.655862)
			(xy 84.096037 -239.601425) (xy 84.11596 -239.549334) (xy 84.143256 -239.500699) (xy 84.177342 -239.456556)
			(xy 84.217491 -239.417847) (xy 84.262849 -239.385396) (xy 84.312449 -239.359895) (xy 84.365233 -239.341888)
			(xy 84.420076 -239.331758) (xy 84.47581 -239.329721) (xy 84.531247 -239.335821) (xy 84.585204 -239.349927)
			(xy 84.636533 -239.371739) (xy 84.684139 -239.400793) (xy 84.727007 -239.436468) (xy 84.764224 -239.478005)
			(xy 84.794997 -239.524518) (xy 84.818669 -239.575015) (xy 84.834737 -239.628422) (xy 84.842857 -239.683598)
			(xy 84.843366 -239.711484) (xy 84.842857 -239.73937) (xy 84.834737 -239.794546) (xy 84.818669 -239.847953)
			(xy 84.794997 -239.89845) (xy 84.764224 -239.944963) (xy 84.727007 -239.9865) (xy 84.684139 -240.022175)
			(xy 84.636533 -240.051229) (xy 84.585204 -240.073041) (xy 84.531247 -240.087147) (xy 84.47581 -240.093247)
			(xy 84.420076 -240.09121) (xy 84.365233 -240.08108) (xy 84.312449 -240.063073) (xy 84.262849 -240.037572)
			(xy 84.217491 -240.005121) (xy 84.177342 -239.966412) (xy 84.143256 -239.922269) (xy 84.11596 -239.873634)
			(xy 84.096037 -239.821543) (xy 84.083911 -239.767106) (xy 84.07984 -239.711484) (xy 70.603872 -239.711484)
			(xy 70.603872 -239.970818) (xy 70.60337 -240.002779) (xy 70.595359 -240.066197) (xy 70.579462 -240.128111)
			(xy 70.55593 -240.187544) (xy 70.525136 -240.243559) (xy 70.487563 -240.295274) (xy 70.473344 -240.310416)
			(xy 81.938874 -240.310416) (xy 81.942945 -240.254794) (xy 81.955071 -240.200357) (xy 81.974994 -240.148266)
			(xy 82.00229 -240.099631) (xy 82.036376 -240.055488) (xy 82.076525 -240.016779) (xy 82.121883 -239.984328)
			(xy 82.171483 -239.958827) (xy 82.224267 -239.94082) (xy 82.27911 -239.93069) (xy 82.334844 -239.928653)
			(xy 82.390281 -239.934753) (xy 82.444238 -239.948859) (xy 82.495567 -239.970671) (xy 82.543173 -239.999725)
			(xy 82.586041 -240.0354) (xy 82.623258 -240.076937) (xy 82.654031 -240.12345) (xy 82.677703 -240.173947)
			(xy 82.693771 -240.227354) (xy 82.701891 -240.28253) (xy 82.7024 -240.310416) (xy 82.701891 -240.338302)
			(xy 82.693771 -240.393478) (xy 82.677703 -240.446885) (xy 82.654031 -240.497382) (xy 82.623258 -240.543895)
			(xy 82.586041 -240.585432) (xy 82.543173 -240.621107) (xy 82.495567 -240.650161) (xy 82.444238 -240.671973)
			(xy 82.390281 -240.686079) (xy 82.334844 -240.692179) (xy 82.27911 -240.690142) (xy 82.224267 -240.680012)
			(xy 82.171483 -240.662005) (xy 82.121883 -240.636504) (xy 82.076525 -240.604053) (xy 82.036376 -240.565344)
			(xy 82.00229 -240.521201) (xy 81.974994 -240.472566) (xy 81.955071 -240.420475) (xy 81.942945 -240.366038)
			(xy 81.938874 -240.310416) (xy 70.473344 -240.310416) (xy 70.443806 -240.341871) (xy 70.394553 -240.382616)
			(xy 70.340582 -240.416867) (xy 70.282743 -240.444084) (xy 70.22195 -240.463837) (xy 70.15916 -240.475815)
			(xy 70.095364 -240.479829) (xy 70.031568 -240.475815) (xy 69.968778 -240.463837) (xy 69.907985 -240.444084)
			(xy 69.850146 -240.416867) (xy 69.796175 -240.382616) (xy 69.746922 -240.341871) (xy 69.703165 -240.295274)
			(xy 69.665592 -240.243559) (xy 69.634798 -240.187544) (xy 69.611266 -240.128111) (xy 69.595369 -240.066197)
			(xy 69.587358 -240.002779) (xy 69.586856 -239.970818) (xy 50.410622 -239.970818) (xy 50.418042 -239.976907)
			(xy 50.475395 -240.03426) (xy 50.52685 -240.096959) (xy 50.571912 -240.164399) (xy 50.610147 -240.235931)
			(xy 50.641186 -240.310867) (xy 50.664731 -240.388483) (xy 50.680554 -240.468034) (xy 50.688504 -240.548753)
			(xy 50.689002 -240.589308) (xy 50.688504 -240.629863) (xy 50.680554 -240.710582) (xy 50.664731 -240.790133)
			(xy 50.641186 -240.867749) (xy 50.610147 -240.942685) (xy 50.588051 -240.984024) (xy 83.422234 -240.984024)
			(xy 83.426305 -240.928402) (xy 83.438431 -240.873965) (xy 83.458354 -240.821874) (xy 83.48565 -240.773239)
			(xy 83.519736 -240.729096) (xy 83.559885 -240.690387) (xy 83.605243 -240.657936) (xy 83.654843 -240.632435)
			(xy 83.707627 -240.614428) (xy 83.76247 -240.604298) (xy 83.818204 -240.602261) (xy 83.873641 -240.608361)
			(xy 83.927598 -240.622467) (xy 83.978927 -240.644279) (xy 84.026533 -240.673333) (xy 84.069401 -240.709008)
			(xy 84.106618 -240.750545) (xy 84.137391 -240.797058) (xy 84.161063 -240.847555) (xy 84.177131 -240.900962)
			(xy 84.185251 -240.956138) (xy 84.18576 -240.984024) (xy 84.185251 -241.01191) (xy 84.177131 -241.067086)
			(xy 84.161063 -241.120493) (xy 84.137391 -241.17099) (xy 84.106618 -241.217503) (xy 84.069401 -241.25904)
			(xy 84.026533 -241.294715) (xy 83.978927 -241.323769) (xy 83.927598 -241.345581) (xy 83.873641 -241.359687)
			(xy 83.818204 -241.365787) (xy 83.76247 -241.36375) (xy 83.707627 -241.35362) (xy 83.654843 -241.335613)
			(xy 83.605243 -241.310112) (xy 83.559885 -241.277661) (xy 83.519736 -241.238952) (xy 83.48565 -241.194809)
			(xy 83.458354 -241.146174) (xy 83.438431 -241.094083) (xy 83.426305 -241.039646) (xy 83.422234 -240.984024)
			(xy 50.588051 -240.984024) (xy 50.571912 -241.014217) (xy 50.52685 -241.081657) (xy 50.475395 -241.144356)
			(xy 50.418042 -241.201709) (xy 50.355343 -241.253164) (xy 50.287903 -241.298226) (xy 50.216371 -241.336461)
			(xy 50.141435 -241.3675) (xy 50.063819 -241.391045) (xy 49.984268 -241.406868) (xy 49.903549 -241.414818)
			(xy 49.822439 -241.414818) (xy 49.74172 -241.406868) (xy 49.662169 -241.391045) (xy 49.584553 -241.3675)
			(xy 49.509617 -241.336461) (xy 49.438085 -241.298226) (xy 49.370645 -241.253164) (xy 49.307946 -241.201709)
			(xy 49.250593 -241.144356) (xy 49.199138 -241.081657) (xy 49.154076 -241.014217) (xy 49.115841 -240.942685)
			(xy 49.084802 -240.867749) (xy 49.061257 -240.790133) (xy 49.045434 -240.710582) (xy 49.037484 -240.629863)
			(xy 47.316644 -240.629863) (xy 47.316644 -240.876074) (xy 47.316142 -240.908035) (xy 47.308131 -240.971453)
			(xy 47.292234 -241.033367) (xy 47.268702 -241.0928) (xy 47.237908 -241.148815) (xy 47.200335 -241.20053)
			(xy 47.156578 -241.247127) (xy 47.107325 -241.287872) (xy 47.053354 -241.322123) (xy 46.995515 -241.34934)
			(xy 46.934722 -241.369093) (xy 46.871932 -241.381071) (xy 46.808136 -241.385085) (xy 46.74434 -241.381071)
			(xy 46.68155 -241.369093) (xy 46.620757 -241.34934) (xy 46.562918 -241.322123) (xy 46.508947 -241.287872)
			(xy 46.459694 -241.247127) (xy 46.415937 -241.20053) (xy 46.378364 -241.148815) (xy 46.34757 -241.0928)
			(xy 46.324038 -241.033367) (xy 46.308141 -240.971453) (xy 46.30013 -240.908035) (xy 46.299628 -240.876074)
			(xy 46.299628 -240.405158) (xy 46.299147 -240.382248) (xy 46.290958 -240.337166) (xy 46.274818 -240.294284)
			(xy 46.251249 -240.254991) (xy 46.221016 -240.220562) (xy 46.185099 -240.192113) (xy 46.144662 -240.170565)
			(xy 46.101017 -240.156619) (xy 46.055579 -240.150725) (xy 46.032674 -240.151412) (xy 46.008036 -240.15192)
			(xy 45.197268 -240.15192) (xy 45.180587 -240.152441) (xy 45.148365 -240.161094) (xy 45.119486 -240.1778)
			(xy 45.107352 -240.189258) (xy 45.042836 -240.254028) (xy 45.020103 -240.27603) (xy 44.969911 -240.314543)
			(xy 44.915122 -240.346176) (xy 44.856672 -240.370387) (xy 44.795563 -240.386761) (xy 44.732839 -240.395019)
			(xy 44.669573 -240.395019) (xy 44.606849 -240.386761) (xy 44.54574 -240.370387) (xy 44.48729 -240.346176)
			(xy 44.432501 -240.314543) (xy 44.382309 -240.27603) (xy 44.337574 -240.231295) (xy 44.299061 -240.181103)
			(xy 44.267428 -240.126314) (xy 44.243217 -240.067864) (xy 44.226843 -240.006755) (xy 44.218585 -239.944031)
			(xy 28.942538 -239.944031) (xy 28.942538 -241.958977) (xy 58.125098 -241.958977) (xy 58.125098 -241.887655)
			(xy 58.133084 -241.816781) (xy 58.148954 -241.747246) (xy 58.172511 -241.679926) (xy 58.203456 -241.615667)
			(xy 58.241402 -241.555276) (xy 58.285871 -241.499514) (xy 58.336304 -241.449081) (xy 58.392066 -241.404612)
			(xy 58.452457 -241.366666) (xy 58.516716 -241.335721) (xy 58.584036 -241.312164) (xy 58.653571 -241.296294)
			(xy 58.724445 -241.288308) (xy 58.795767 -241.288308) (xy 58.866641 -241.296294) (xy 58.936176 -241.312164)
			(xy 59.003496 -241.335721) (xy 59.067755 -241.366666) (xy 59.128146 -241.404612) (xy 59.183908 -241.449081)
			(xy 59.234341 -241.499514) (xy 59.27881 -241.555276) (xy 59.316756 -241.615667) (xy 59.347701 -241.679926)
			(xy 59.371258 -241.747246) (xy 59.387128 -241.816781) (xy 59.395114 -241.887655) (xy 59.395614 -241.923316)
			(xy 59.395114 -241.958977) (xy 60.01181 -241.958977) (xy 60.01181 -241.887655) (xy 60.019796 -241.816781)
			(xy 60.035666 -241.747246) (xy 60.059223 -241.679926) (xy 60.090168 -241.615667) (xy 60.128114 -241.555276)
			(xy 60.172583 -241.499514) (xy 60.223016 -241.449081) (xy 60.278778 -241.404612) (xy 60.339169 -241.366666)
			(xy 60.403428 -241.335721) (xy 60.470748 -241.312164) (xy 60.540283 -241.296294) (xy 60.611157 -241.288308)
			(xy 60.682479 -241.288308) (xy 60.753353 -241.296294) (xy 60.822888 -241.312164) (xy 60.890208 -241.335721)
			(xy 60.954467 -241.366666) (xy 61.014858 -241.404612) (xy 61.07062 -241.449081) (xy 61.121053 -241.499514)
			(xy 61.165522 -241.555276) (xy 61.203468 -241.615667) (xy 61.234413 -241.679926) (xy 61.241633 -241.700558)
			(xy 81.259932 -241.700558) (xy 81.264003 -241.644936) (xy 81.276129 -241.590499) (xy 81.296052 -241.538408)
			(xy 81.323348 -241.489773) (xy 81.357434 -241.44563) (xy 81.397583 -241.406921) (xy 81.442941 -241.37447)
			(xy 81.492541 -241.348969) (xy 81.545325 -241.330962) (xy 81.600168 -241.320832) (xy 81.655902 -241.318795)
			(xy 81.711339 -241.324895) (xy 81.765296 -241.339001) (xy 81.816625 -241.360813) (xy 81.864231 -241.389867)
			(xy 81.907099 -241.425542) (xy 81.944316 -241.467079) (xy 81.975089 -241.513592) (xy 81.998761 -241.564089)
			(xy 82.014829 -241.617496) (xy 82.022949 -241.672672) (xy 82.023458 -241.700558) (xy 82.022949 -241.728444)
			(xy 82.014829 -241.78362) (xy 81.998761 -241.837027) (xy 81.975089 -241.887524) (xy 81.944316 -241.934037)
			(xy 81.907099 -241.975574) (xy 81.864231 -242.011249) (xy 81.816625 -242.040303) (xy 81.765296 -242.062115)
			(xy 81.711339 -242.076221) (xy 81.655902 -242.082321) (xy 81.600168 -242.080284) (xy 81.545325 -242.070154)
			(xy 81.492541 -242.052147) (xy 81.442941 -242.026646) (xy 81.397583 -241.994195) (xy 81.357434 -241.955486)
			(xy 81.323348 -241.911343) (xy 81.296052 -241.862708) (xy 81.276129 -241.810617) (xy 81.264003 -241.75618)
			(xy 81.259932 -241.700558) (xy 61.241633 -241.700558) (xy 61.25797 -241.747246) (xy 61.27384 -241.816781)
			(xy 61.281826 -241.887655) (xy 61.282326 -241.923316) (xy 61.281826 -241.958977) (xy 61.27384 -242.029851)
			(xy 61.25797 -242.099386) (xy 61.234413 -242.166706) (xy 61.203468 -242.230965) (xy 61.185149 -242.26012)
			(xy 86.39887 -242.26012) (xy 86.402874 -242.060022) (xy 86.414881 -241.860244) (xy 86.434872 -241.661107)
			(xy 86.462814 -241.462929) (xy 86.498662 -241.266027) (xy 86.54236 -241.070718) (xy 86.593837 -240.877313)
			(xy 86.653011 -240.686123) (xy 86.719787 -240.497453) (xy 86.794059 -240.311606) (xy 86.875706 -240.128879)
			(xy 86.964599 -239.949566) (xy 87.060595 -239.773952) (xy 87.16354 -239.60232) (xy 87.27327 -239.434944)
			(xy 87.389608 -239.272093) (xy 87.512369 -239.114026) (xy 87.641356 -238.960998) (xy 87.776363 -238.813253)
			(xy 87.917172 -238.671027) (xy 88.063559 -238.53455) (xy 88.215289 -238.404038) (xy 88.37212 -238.279702)
			(xy 88.533799 -238.16174) (xy 88.700069 -238.050341) (xy 88.870662 -237.945684) (xy 89.045306 -237.847936)
			(xy 89.223722 -237.757253) (xy 89.405622 -237.673782) (xy 89.590717 -237.597655) (xy 89.778709 -237.528995)
			(xy 89.969298 -237.467911) (xy 90.162178 -237.414501) (xy 90.35704 -237.368852) (xy 90.553573 -237.331035)
			(xy 90.751462 -237.301111) (xy 90.950389 -237.279129) (xy 91.150037 -237.265124) (xy 91.350085 -237.259118)
			(xy 91.550213 -237.26112) (xy 91.750101 -237.271128) (xy 91.949428 -237.289125) (xy 92.147876 -237.315083)
			(xy 92.345126 -237.34896) (xy 92.540863 -237.390702) (xy 92.734773 -237.440241) (xy 92.926546 -237.497499)
			(xy 93.115875 -237.562384) (xy 93.302455 -237.634792) (xy 93.48599 -237.714608) (xy 93.666184 -237.801702)
			(xy 93.842749 -237.895936) (xy 94.015402 -237.997159) (xy 94.183867 -238.105209) (xy 94.347875 -238.219912)
			(xy 94.507162 -238.341086) (xy 94.661473 -238.468535) (xy 94.810561 -238.602056) (xy 94.954188 -238.741436)
			(xy 95.092124 -238.88645) (xy 95.224147 -239.036867) (xy 95.350046 -239.192445) (xy 95.46962 -239.352937)
			(xy 95.582676 -239.518083) (xy 95.689035 -239.687621) (xy 95.788526 -239.861279) (xy 95.880989 -240.038778)
			(xy 95.966276 -240.219834) (xy 96.044251 -240.404158) (xy 96.114788 -240.591454) (xy 96.177776 -240.781422)
			(xy 96.233113 -240.973758) (xy 96.28071 -241.168154) (xy 96.320491 -241.364299) (xy 96.352393 -241.561878)
			(xy 96.376364 -241.760575) (xy 96.392366 -241.960073) (xy 96.400373 -242.160051) (xy 96.400874 -242.26012)
			(xy 96.400373 -242.360189) (xy 96.392366 -242.560167) (xy 96.376364 -242.759665) (xy 96.352393 -242.958362)
			(xy 96.320491 -243.155941) (xy 96.28071 -243.352086) (xy 96.233113 -243.546482) (xy 96.177776 -243.738818)
			(xy 96.114788 -243.928786) (xy 96.044251 -244.116082) (xy 95.966276 -244.300406) (xy 95.880989 -244.481462)
			(xy 95.788526 -244.658961) (xy 95.689035 -244.832619) (xy 95.582676 -245.002157) (xy 95.46962 -245.167303)
			(xy 95.350046 -245.327795) (xy 95.224147 -245.483373) (xy 95.092124 -245.63379) (xy 94.954188 -245.778804)
			(xy 94.810561 -245.918184) (xy 94.661473 -246.051705) (xy 94.507162 -246.179154) (xy 94.347875 -246.300328)
			(xy 94.183867 -246.415031) (xy 94.015402 -246.523081) (xy 93.842749 -246.624304) (xy 93.666184 -246.718538)
			(xy 93.48599 -246.805632) (xy 93.302455 -246.885448) (xy 93.115875 -246.957856) (xy 92.926546 -247.022741)
			(xy 92.734773 -247.079999) (xy 92.540863 -247.129538) (xy 92.345126 -247.17128) (xy 92.147876 -247.205157)
			(xy 91.949428 -247.231115) (xy 91.750101 -247.249112) (xy 91.550213 -247.25912) (xy 91.350085 -247.261122)
			(xy 91.150037 -247.255116) (xy 90.950389 -247.241111) (xy 90.751462 -247.219129) (xy 90.553573 -247.189205)
			(xy 90.35704 -247.151388) (xy 90.162178 -247.105739) (xy 89.969298 -247.052329) (xy 89.778709 -246.991245)
			(xy 89.590717 -246.922585) (xy 89.405622 -246.846458) (xy 89.223722 -246.762987) (xy 89.045306 -246.672304)
			(xy 88.870662 -246.574556) (xy 88.700069 -246.469899) (xy 88.533799 -246.3585) (xy 88.37212 -246.240538)
			(xy 88.215289 -246.116202) (xy 88.063559 -245.98569) (xy 87.917172 -245.849213) (xy 87.776363 -245.706987)
			(xy 87.641356 -245.559242) (xy 87.512369 -245.406214) (xy 87.389608 -245.248147) (xy 87.27327 -245.085296)
			(xy 87.16354 -244.91792) (xy 87.060595 -244.746288) (xy 86.964599 -244.570674) (xy 86.875706 -244.391361)
			(xy 86.794059 -244.208634) (xy 86.719787 -244.022787) (xy 86.653011 -243.834117) (xy 86.593837 -243.642927)
			(xy 86.54236 -243.449522) (xy 86.498662 -243.254213) (xy 86.462814 -243.057311) (xy 86.434872 -242.859133)
			(xy 86.414881 -242.659996) (xy 86.402874 -242.460218) (xy 86.39887 -242.26012) (xy 61.185149 -242.26012)
			(xy 61.165522 -242.291356) (xy 61.121053 -242.347118) (xy 61.07062 -242.397551) (xy 61.014858 -242.44202)
			(xy 60.954467 -242.479966) (xy 60.890208 -242.510911) (xy 60.822888 -242.534468) (xy 60.753353 -242.550338)
			(xy 60.682479 -242.558324) (xy 60.611157 -242.558324) (xy 60.540283 -242.550338) (xy 60.470748 -242.534468)
			(xy 60.403428 -242.510911) (xy 60.339169 -242.479966) (xy 60.278778 -242.44202) (xy 60.223016 -242.397551)
			(xy 60.172583 -242.347118) (xy 60.128114 -242.291356) (xy 60.090168 -242.230965) (xy 60.059223 -242.166706)
			(xy 60.035666 -242.099386) (xy 60.019796 -242.029851) (xy 60.01181 -241.958977) (xy 59.395114 -241.958977)
			(xy 59.387128 -242.029851) (xy 59.371258 -242.099386) (xy 59.347701 -242.166706) (xy 59.316756 -242.230965)
			(xy 59.27881 -242.291356) (xy 59.234341 -242.347118) (xy 59.183908 -242.397551) (xy 59.128146 -242.44202)
			(xy 59.067755 -242.479966) (xy 59.003496 -242.510911) (xy 58.936176 -242.534468) (xy 58.866641 -242.550338)
			(xy 58.795767 -242.558324) (xy 58.724445 -242.558324) (xy 58.653571 -242.550338) (xy 58.584036 -242.534468)
			(xy 58.516716 -242.510911) (xy 58.452457 -242.479966) (xy 58.392066 -242.44202) (xy 58.336304 -242.397551)
			(xy 58.285871 -242.347118) (xy 58.241402 -242.291356) (xy 58.203456 -242.230965) (xy 58.172511 -242.166706)
			(xy 58.148954 -242.099386) (xy 58.133084 -242.029851) (xy 58.125098 -241.958977) (xy 28.942538 -241.958977)
			(xy 28.942538 -242.846489) (xy 44.109873 -242.846489) (xy 44.109873 -242.783223) (xy 44.118131 -242.720499)
			(xy 44.134505 -242.65939) (xy 44.158716 -242.60094) (xy 44.190349 -242.546151) (xy 44.228862 -242.495959)
			(xy 44.273597 -242.451224) (xy 44.323789 -242.412711) (xy 44.378578 -242.381078) (xy 44.437028 -242.356867)
			(xy 44.498137 -242.340493) (xy 44.560861 -242.332235) (xy 44.624127 -242.332235) (xy 44.686851 -242.340493)
			(xy 44.74796 -242.356867) (xy 44.80641 -242.381078) (xy 44.861199 -242.412711) (xy 44.911391 -242.451224)
			(xy 44.934124 -242.473226) (xy 45.036486 -242.575842) (xy 45.048623 -242.5873) (xy 45.077496 -242.604023)
			(xy 45.109719 -242.61268) (xy 45.126402 -242.61318) (xy 46.00829 -242.61318) (xy 46.036578 -242.61358)
			(xy 46.092772 -242.620129) (xy 46.147813 -242.63321) (xy 46.200946 -242.652641) (xy 46.25144 -242.678157)
			(xy 46.275244 -242.693444) (xy 46.306994 -242.71478) (xy 46.364144 -242.71478) (xy 46.364144 -242.769644)
			(xy 46.384044 -242.791935) (xy 46.418692 -242.840623) (xy 46.447068 -242.893215) (xy 46.468737 -242.948905)
			(xy 46.483369 -243.006844) (xy 46.490739 -243.066146) (xy 46.490736 -243.125904) (xy 46.483359 -243.185205)
			(xy 46.468722 -243.243142) (xy 46.447047 -243.298831) (xy 46.418666 -243.351419) (xy 46.384013 -243.400104)
			(xy 46.364144 -243.422424) (xy 46.364144 -243.477288) (xy 46.306994 -243.477288) (xy 46.275244 -243.498624)
			(xy 46.251422 -243.51388) (xy 46.200923 -243.539377) (xy 46.147794 -243.558807) (xy 46.092761 -243.571905)
			(xy 46.036575 -243.578493) (xy 46.00829 -243.578888) (xy 44.67352 -243.578888) (xy 44.250864 -243.156486)
			(xy 44.228862 -243.133753) (xy 44.190349 -243.083561) (xy 44.158716 -243.028772) (xy 44.134505 -242.970322)
			(xy 44.118131 -242.909213) (xy 44.109873 -242.846489) (xy 28.942538 -242.846489) (xy 28.942538 -243.792603)
			(xy 58.125098 -243.792603) (xy 58.125098 -243.721281) (xy 58.133084 -243.650407) (xy 58.148954 -243.580872)
			(xy 58.172511 -243.513552) (xy 58.203456 -243.449293) (xy 58.241402 -243.388902) (xy 58.285871 -243.33314)
			(xy 58.336304 -243.282707) (xy 58.392066 -243.238238) (xy 58.452457 -243.200292) (xy 58.516716 -243.169347)
			(xy 58.584036 -243.14579) (xy 58.653571 -243.12992) (xy 58.724445 -243.121934) (xy 58.795767 -243.121934)
			(xy 58.866641 -243.12992) (xy 58.936176 -243.14579) (xy 59.003496 -243.169347) (xy 59.067755 -243.200292)
			(xy 59.128146 -243.238238) (xy 59.183908 -243.282707) (xy 59.234341 -243.33314) (xy 59.27881 -243.388902)
			(xy 59.316756 -243.449293) (xy 59.347701 -243.513552) (xy 59.371258 -243.580872) (xy 59.387128 -243.650407)
			(xy 59.395114 -243.721281) (xy 59.395614 -243.756942) (xy 59.395114 -243.792603) (xy 60.01181 -243.792603)
			(xy 60.01181 -243.721281) (xy 60.019796 -243.650407) (xy 60.035666 -243.580872) (xy 60.059223 -243.513552)
			(xy 60.090168 -243.449293) (xy 60.128114 -243.388902) (xy 60.172583 -243.33314) (xy 60.223016 -243.282707)
			(xy 60.278778 -243.238238) (xy 60.339169 -243.200292) (xy 60.403428 -243.169347) (xy 60.470748 -243.14579)
			(xy 60.540283 -243.12992) (xy 60.611157 -243.121934) (xy 60.682479 -243.121934) (xy 60.753353 -243.12992)
			(xy 60.822888 -243.14579) (xy 60.890208 -243.169347) (xy 60.954467 -243.200292) (xy 61.014858 -243.238238)
			(xy 61.07062 -243.282707) (xy 61.121053 -243.33314) (xy 61.165522 -243.388902) (xy 61.203468 -243.449293)
			(xy 61.234413 -243.513552) (xy 61.25797 -243.580872) (xy 61.27384 -243.650407) (xy 61.281826 -243.721281)
			(xy 61.282326 -243.756942) (xy 61.281826 -243.792603) (xy 62.252852 -243.792603) (xy 62.252852 -243.721281)
			(xy 62.260838 -243.650407) (xy 62.276708 -243.580872) (xy 62.300265 -243.513552) (xy 62.33121 -243.449293)
			(xy 62.369156 -243.388902) (xy 62.413625 -243.33314) (xy 62.464058 -243.282707) (xy 62.51982 -243.238238)
			(xy 62.580211 -243.200292) (xy 62.64447 -243.169347) (xy 62.71179 -243.14579) (xy 62.781325 -243.12992)
			(xy 62.852199 -243.121934) (xy 62.923521 -243.121934) (xy 62.994395 -243.12992) (xy 63.06393 -243.14579)
			(xy 63.13125 -243.169347) (xy 63.195509 -243.200292) (xy 63.2559 -243.238238) (xy 63.311662 -243.282707)
			(xy 63.362095 -243.33314) (xy 63.406564 -243.388902) (xy 63.44451 -243.449293) (xy 63.475455 -243.513552)
			(xy 63.499012 -243.580872) (xy 63.514882 -243.650407) (xy 63.522868 -243.721281) (xy 63.523368 -243.756942)
			(xy 63.522868 -243.792603) (xy 64.156836 -243.792603) (xy 64.156836 -243.721281) (xy 64.164822 -243.650407)
			(xy 64.180692 -243.580872) (xy 64.204249 -243.513552) (xy 64.235194 -243.449293) (xy 64.27314 -243.388902)
			(xy 64.317609 -243.33314) (xy 64.368042 -243.282707) (xy 64.423804 -243.238238) (xy 64.484195 -243.200292)
			(xy 64.548454 -243.169347) (xy 64.615774 -243.14579) (xy 64.685309 -243.12992) (xy 64.756183 -243.121934)
			(xy 64.827505 -243.121934) (xy 64.898379 -243.12992) (xy 64.967914 -243.14579) (xy 65.035234 -243.169347)
			(xy 65.099493 -243.200292) (xy 65.159884 -243.238238) (xy 65.215646 -243.282707) (xy 65.266079 -243.33314)
			(xy 65.310548 -243.388902) (xy 65.348494 -243.449293) (xy 65.379439 -243.513552) (xy 65.402996 -243.580872)
			(xy 65.418866 -243.650407) (xy 65.426852 -243.721281) (xy 65.427352 -243.756942) (xy 65.426852 -243.792603)
			(xy 65.418866 -243.863477) (xy 65.402996 -243.933012) (xy 65.379439 -244.000332) (xy 65.348494 -244.064591)
			(xy 65.310548 -244.124982) (xy 65.266079 -244.180744) (xy 65.215646 -244.231177) (xy 65.159884 -244.275646)
			(xy 65.099493 -244.313592) (xy 65.035234 -244.344537) (xy 64.967914 -244.368094) (xy 64.898379 -244.383964)
			(xy 64.827505 -244.39195) (xy 64.756183 -244.39195) (xy 64.685309 -244.383964) (xy 64.615774 -244.368094)
			(xy 64.548454 -244.344537) (xy 64.484195 -244.313592) (xy 64.423804 -244.275646) (xy 64.368042 -244.231177)
			(xy 64.317609 -244.180744) (xy 64.27314 -244.124982) (xy 64.235194 -244.064591) (xy 64.204249 -244.000332)
			(xy 64.180692 -243.933012) (xy 64.164822 -243.863477) (xy 64.156836 -243.792603) (xy 63.522868 -243.792603)
			(xy 63.514882 -243.863477) (xy 63.499012 -243.933012) (xy 63.475455 -244.000332) (xy 63.44451 -244.064591)
			(xy 63.406564 -244.124982) (xy 63.362095 -244.180744) (xy 63.311662 -244.231177) (xy 63.2559 -244.275646)
			(xy 63.195509 -244.313592) (xy 63.13125 -244.344537) (xy 63.06393 -244.368094) (xy 62.994395 -244.383964)
			(xy 62.923521 -244.39195) (xy 62.852199 -244.39195) (xy 62.781325 -244.383964) (xy 62.71179 -244.368094)
			(xy 62.64447 -244.344537) (xy 62.580211 -244.313592) (xy 62.51982 -244.275646) (xy 62.464058 -244.231177)
			(xy 62.413625 -244.180744) (xy 62.369156 -244.124982) (xy 62.33121 -244.064591) (xy 62.300265 -244.000332)
			(xy 62.276708 -243.933012) (xy 62.260838 -243.863477) (xy 62.252852 -243.792603) (xy 61.281826 -243.792603)
			(xy 61.27384 -243.863477) (xy 61.25797 -243.933012) (xy 61.234413 -244.000332) (xy 61.203468 -244.064591)
			(xy 61.165522 -244.124982) (xy 61.121053 -244.180744) (xy 61.07062 -244.231177) (xy 61.014858 -244.275646)
			(xy 60.954467 -244.313592) (xy 60.890208 -244.344537) (xy 60.822888 -244.368094) (xy 60.753353 -244.383964)
			(xy 60.682479 -244.39195) (xy 60.611157 -244.39195) (xy 60.540283 -244.383964) (xy 60.470748 -244.368094)
			(xy 60.403428 -244.344537) (xy 60.339169 -244.313592) (xy 60.278778 -244.275646) (xy 60.223016 -244.231177)
			(xy 60.172583 -244.180744) (xy 60.128114 -244.124982) (xy 60.090168 -244.064591) (xy 60.059223 -244.000332)
			(xy 60.035666 -243.933012) (xy 60.019796 -243.863477) (xy 60.01181 -243.792603) (xy 59.395114 -243.792603)
			(xy 59.387128 -243.863477) (xy 59.371258 -243.933012) (xy 59.347701 -244.000332) (xy 59.316756 -244.064591)
			(xy 59.27881 -244.124982) (xy 59.234341 -244.180744) (xy 59.183908 -244.231177) (xy 59.128146 -244.275646)
			(xy 59.067755 -244.313592) (xy 59.003496 -244.344537) (xy 58.936176 -244.368094) (xy 58.866641 -244.383964)
			(xy 58.795767 -244.39195) (xy 58.724445 -244.39195) (xy 58.653571 -244.383964) (xy 58.584036 -244.368094)
			(xy 58.516716 -244.344537) (xy 58.452457 -244.313592) (xy 58.392066 -244.275646) (xy 58.336304 -244.231177)
			(xy 58.285871 -244.180744) (xy 58.241402 -244.124982) (xy 58.203456 -244.064591) (xy 58.172511 -244.000332)
			(xy 58.148954 -243.933012) (xy 58.133084 -243.863477) (xy 58.125098 -243.792603) (xy 28.942538 -243.792603)
			(xy 28.942538 -244.757077) (xy 44.058565 -244.757077) (xy 44.058565 -244.693811) (xy 44.066823 -244.631087)
			(xy 44.083197 -244.569978) (xy 44.107408 -244.511528) (xy 44.139041 -244.456739) (xy 44.177554 -244.406547)
			(xy 44.199556 -244.383814) (xy 44.548044 -244.03558) (xy 45.985684 -244.03558) (xy 46.013947 -244.035973)
			(xy 46.070088 -244.042545) (xy 46.125077 -244.055636) (xy 46.178157 -244.075066) (xy 46.228602 -244.100568)
			(xy 46.252384 -244.115844) (xy 46.284388 -244.136926) (xy 46.447202 -244.136926) (xy 46.480984 -244.111526)
			(xy 46.507458 -244.092328) (xy 46.564393 -244.060157) (xy 46.624984 -244.035552) (xy 46.68823 -244.018919)
			(xy 46.753086 -244.010534) (xy 46.818482 -244.010534) (xy 46.883338 -244.018919) (xy 46.946584 -244.035552)
			(xy 47.007175 -244.060157) (xy 47.06411 -244.092328) (xy 47.090584 -244.111526) (xy 47.124366 -244.136926)
			(xy 47.141892 -244.136926) (xy 47.141892 -244.155722) (xy 47.165538 -244.179707) (xy 47.206976 -244.232805)
			(xy 47.24104 -244.290909) (xy 47.267134 -244.353003) (xy 47.284799 -244.417999) (xy 47.293728 -244.484758)
			(xy 47.294292 -244.518434) (xy 47.294292 -245.693539) (xy 58.125098 -245.693539) (xy 58.125098 -245.622217)
			(xy 58.133084 -245.551343) (xy 58.148954 -245.481808) (xy 58.172511 -245.414488) (xy 58.203456 -245.350229)
			(xy 58.241402 -245.289838) (xy 58.285871 -245.234076) (xy 58.336304 -245.183643) (xy 58.392066 -245.139174)
			(xy 58.452457 -245.101228) (xy 58.516716 -245.070283) (xy 58.584036 -245.046726) (xy 58.653571 -245.030856)
			(xy 58.724445 -245.02287) (xy 58.795767 -245.02287) (xy 58.866641 -245.030856) (xy 58.936176 -245.046726)
			(xy 59.003496 -245.070283) (xy 59.067755 -245.101228) (xy 59.128146 -245.139174) (xy 59.183908 -245.183643)
			(xy 59.234341 -245.234076) (xy 59.27881 -245.289838) (xy 59.316756 -245.350229) (xy 59.347701 -245.414488)
			(xy 59.371258 -245.481808) (xy 59.387128 -245.551343) (xy 59.395114 -245.622217) (xy 59.395614 -245.657878)
			(xy 59.395114 -245.693539) (xy 60.01181 -245.693539) (xy 60.01181 -245.622217) (xy 60.019796 -245.551343)
			(xy 60.035666 -245.481808) (xy 60.059223 -245.414488) (xy 60.090168 -245.350229) (xy 60.128114 -245.289838)
			(xy 60.172583 -245.234076) (xy 60.223016 -245.183643) (xy 60.278778 -245.139174) (xy 60.339169 -245.101228)
			(xy 60.403428 -245.070283) (xy 60.470748 -245.046726) (xy 60.540283 -245.030856) (xy 60.611157 -245.02287)
			(xy 60.682479 -245.02287) (xy 60.753353 -245.030856) (xy 60.822888 -245.046726) (xy 60.890208 -245.070283)
			(xy 60.954467 -245.101228) (xy 61.014858 -245.139174) (xy 61.07062 -245.183643) (xy 61.121053 -245.234076)
			(xy 61.165522 -245.289838) (xy 61.203468 -245.350229) (xy 61.234413 -245.414488) (xy 61.25797 -245.481808)
			(xy 61.27384 -245.551343) (xy 61.281826 -245.622217) (xy 61.282326 -245.657878) (xy 61.281826 -245.693539)
			(xy 62.252852 -245.693539) (xy 62.252852 -245.622217) (xy 62.260838 -245.551343) (xy 62.276708 -245.481808)
			(xy 62.300265 -245.414488) (xy 62.33121 -245.350229) (xy 62.369156 -245.289838) (xy 62.413625 -245.234076)
			(xy 62.464058 -245.183643) (xy 62.51982 -245.139174) (xy 62.580211 -245.101228) (xy 62.64447 -245.070283)
			(xy 62.71179 -245.046726) (xy 62.781325 -245.030856) (xy 62.852199 -245.02287) (xy 62.923521 -245.02287)
			(xy 62.994395 -245.030856) (xy 63.06393 -245.046726) (xy 63.13125 -245.070283) (xy 63.195509 -245.101228)
			(xy 63.2559 -245.139174) (xy 63.311662 -245.183643) (xy 63.362095 -245.234076) (xy 63.406564 -245.289838)
			(xy 63.44451 -245.350229) (xy 63.475455 -245.414488) (xy 63.499012 -245.481808) (xy 63.514882 -245.551343)
			(xy 63.522868 -245.622217) (xy 63.523368 -245.657878) (xy 63.522868 -245.693539) (xy 64.156836 -245.693539)
			(xy 64.156836 -245.622217) (xy 64.164822 -245.551343) (xy 64.180692 -245.481808) (xy 64.204249 -245.414488)
			(xy 64.235194 -245.350229) (xy 64.27314 -245.289838) (xy 64.317609 -245.234076) (xy 64.368042 -245.183643)
			(xy 64.423804 -245.139174) (xy 64.484195 -245.101228) (xy 64.548454 -245.070283) (xy 64.615774 -245.046726)
			(xy 64.685309 -245.030856) (xy 64.756183 -245.02287) (xy 64.827505 -245.02287) (xy 64.898379 -245.030856)
			(xy 64.967914 -245.046726) (xy 65.035234 -245.070283) (xy 65.099493 -245.101228) (xy 65.159884 -245.139174)
			(xy 65.215646 -245.183643) (xy 65.266079 -245.234076) (xy 65.310548 -245.289838) (xy 65.348494 -245.350229)
			(xy 65.379439 -245.414488) (xy 65.402996 -245.481808) (xy 65.418866 -245.551343) (xy 65.426852 -245.622217)
			(xy 65.427352 -245.657878) (xy 65.426852 -245.693539) (xy 65.418866 -245.764413) (xy 65.402996 -245.833948)
			(xy 65.379439 -245.901268) (xy 65.348494 -245.965527) (xy 65.310548 -246.025918) (xy 65.266079 -246.08168)
			(xy 65.215646 -246.132113) (xy 65.159884 -246.176582) (xy 65.099493 -246.214528) (xy 65.035234 -246.245473)
			(xy 64.967914 -246.26903) (xy 64.898379 -246.2849) (xy 64.827505 -246.292886) (xy 64.756183 -246.292886)
			(xy 64.685309 -246.2849) (xy 64.615774 -246.26903) (xy 64.548454 -246.245473) (xy 64.484195 -246.214528)
			(xy 64.423804 -246.176582) (xy 64.368042 -246.132113) (xy 64.317609 -246.08168) (xy 64.27314 -246.025918)
			(xy 64.235194 -245.965527) (xy 64.204249 -245.901268) (xy 64.180692 -245.833948) (xy 64.164822 -245.764413)
			(xy 64.156836 -245.693539) (xy 63.522868 -245.693539) (xy 63.514882 -245.764413) (xy 63.499012 -245.833948)
			(xy 63.475455 -245.901268) (xy 63.44451 -245.965527) (xy 63.406564 -246.025918) (xy 63.362095 -246.08168)
			(xy 63.311662 -246.132113) (xy 63.2559 -246.176582) (xy 63.195509 -246.214528) (xy 63.13125 -246.245473)
			(xy 63.06393 -246.26903) (xy 62.994395 -246.2849) (xy 62.923521 -246.292886) (xy 62.852199 -246.292886)
			(xy 62.781325 -246.2849) (xy 62.71179 -246.26903) (xy 62.64447 -246.245473) (xy 62.580211 -246.214528)
			(xy 62.51982 -246.176582) (xy 62.464058 -246.132113) (xy 62.413625 -246.08168) (xy 62.369156 -246.025918)
			(xy 62.33121 -245.965527) (xy 62.300265 -245.901268) (xy 62.276708 -245.833948) (xy 62.260838 -245.764413)
			(xy 62.252852 -245.693539) (xy 61.281826 -245.693539) (xy 61.27384 -245.764413) (xy 61.25797 -245.833948)
			(xy 61.234413 -245.901268) (xy 61.203468 -245.965527) (xy 61.165522 -246.025918) (xy 61.121053 -246.08168)
			(xy 61.07062 -246.132113) (xy 61.014858 -246.176582) (xy 60.954467 -246.214528) (xy 60.890208 -246.245473)
			(xy 60.822888 -246.26903) (xy 60.753353 -246.2849) (xy 60.682479 -246.292886) (xy 60.611157 -246.292886)
			(xy 60.540283 -246.2849) (xy 60.470748 -246.26903) (xy 60.403428 -246.245473) (xy 60.339169 -246.214528)
			(xy 60.278778 -246.176582) (xy 60.223016 -246.132113) (xy 60.172583 -246.08168) (xy 60.128114 -246.025918)
			(xy 60.090168 -245.965527) (xy 60.059223 -245.901268) (xy 60.035666 -245.833948) (xy 60.019796 -245.764413)
			(xy 60.01181 -245.693539) (xy 59.395114 -245.693539) (xy 59.387128 -245.764413) (xy 59.371258 -245.833948)
			(xy 59.347701 -245.901268) (xy 59.316756 -245.965527) (xy 59.27881 -246.025918) (xy 59.234341 -246.08168)
			(xy 59.183908 -246.132113) (xy 59.128146 -246.176582) (xy 59.067755 -246.214528) (xy 59.003496 -246.245473)
			(xy 58.936176 -246.26903) (xy 58.866641 -246.2849) (xy 58.795767 -246.292886) (xy 58.724445 -246.292886)
			(xy 58.653571 -246.2849) (xy 58.584036 -246.26903) (xy 58.516716 -246.245473) (xy 58.452457 -246.214528)
			(xy 58.392066 -246.176582) (xy 58.336304 -246.132113) (xy 58.285871 -246.08168) (xy 58.241402 -246.025918)
			(xy 58.203456 -245.965527) (xy 58.172511 -245.901268) (xy 58.148954 -245.833948) (xy 58.133084 -245.764413)
			(xy 58.125098 -245.693539) (xy 47.294292 -245.693539) (xy 47.294292 -245.712234) (xy 47.29379 -245.744195)
			(xy 47.285779 -245.807613) (xy 47.269882 -245.869527) (xy 47.24635 -245.92896) (xy 47.215556 -245.984975)
			(xy 47.177983 -246.03669) (xy 47.134226 -246.083287) (xy 47.084973 -246.124032) (xy 47.031002 -246.158283)
			(xy 46.973163 -246.1855) (xy 46.91237 -246.205253) (xy 46.84958 -246.217231) (xy 46.785784 -246.221245)
			(xy 46.721988 -246.217231) (xy 46.659198 -246.205253) (xy 46.598405 -246.1855) (xy 46.540566 -246.158283)
			(xy 46.486595 -246.124032) (xy 46.437342 -246.083287) (xy 46.393585 -246.03669) (xy 46.356012 -245.984975)
			(xy 46.325218 -245.92896) (xy 46.301686 -245.869527) (xy 46.285789 -245.807613) (xy 46.277778 -245.744195)
			(xy 46.277276 -245.712234) (xy 46.277276 -245.254526) (xy 46.276774 -245.231618) (xy 46.268582 -245.186541)
			(xy 46.252441 -245.143663) (xy 46.228873 -245.104374) (xy 46.198643 -245.069947) (xy 46.16273 -245.041498)
			(xy 46.122299 -245.019949) (xy 46.078659 -245.005998) (xy 46.033225 -245.000098) (xy 46.010322 -245.00078)
			(xy 45.985684 -245.001288) (xy 45.00118 -245.001288) (xy 44.984455 -245.001766) (xy 44.95214 -245.010406)
			(xy 44.923178 -245.02714) (xy 44.91101 -245.038626) (xy 44.882816 -245.067074) (xy 44.860083 -245.089076)
			(xy 44.809891 -245.127589) (xy 44.755102 -245.159222) (xy 44.696652 -245.183433) (xy 44.635543 -245.199807)
			(xy 44.572819 -245.208065) (xy 44.509553 -245.208065) (xy 44.446829 -245.199807) (xy 44.38572 -245.183433)
			(xy 44.32727 -245.159222) (xy 44.272481 -245.127589) (xy 44.222289 -245.089076) (xy 44.177554 -245.044341)
			(xy 44.139041 -244.994149) (xy 44.107408 -244.93936) (xy 44.083197 -244.88091) (xy 44.066823 -244.819801)
			(xy 44.058565 -244.757077) (xy 28.942538 -244.757077) (xy 28.942538 -247.044093) (xy 44.001669 -247.044093)
			(xy 44.001669 -246.980827) (xy 44.009927 -246.918103) (xy 44.026301 -246.856994) (xy 44.050512 -246.798544)
			(xy 44.082145 -246.743755) (xy 44.120658 -246.693563) (xy 44.165393 -246.648828) (xy 44.215585 -246.610315)
			(xy 44.270374 -246.578682) (xy 44.328824 -246.554471) (xy 44.389933 -246.538097) (xy 44.452657 -246.529839)
			(xy 44.515923 -246.529839) (xy 44.578647 -246.538097) (xy 44.639756 -246.554471) (xy 44.698206 -246.578682)
			(xy 44.752995 -246.610315) (xy 44.803187 -246.648828) (xy 44.82592 -246.67083) (xy 44.954698 -246.799608)
			(xy 46.072806 -246.799608) (xy 46.1011 -246.800041) (xy 46.157299 -246.806655) (xy 46.21234 -246.819791)
			(xy 46.26547 -246.839269) (xy 46.315959 -246.864823) (xy 46.33976 -246.880126) (xy 46.37151 -246.901208)
			(xy 46.42866 -246.901208) (xy 46.42866 -246.956326) (xy 46.448542 -246.978633) (xy 46.483189 -247.027319)
			(xy 46.511564 -247.079908) (xy 46.533234 -247.135597) (xy 46.547866 -247.193534) (xy 46.555238 -247.252834)
			(xy 46.555237 -247.31259) (xy 46.548262 -247.368669) (xy 58.125098 -247.368669) (xy 58.125098 -247.297347)
			(xy 58.133084 -247.226473) (xy 58.148954 -247.156938) (xy 58.172511 -247.089618) (xy 58.203456 -247.025359)
			(xy 58.241402 -246.964968) (xy 58.285871 -246.909206) (xy 58.336304 -246.858773) (xy 58.392066 -246.814304)
			(xy 58.452457 -246.776358) (xy 58.516716 -246.745413) (xy 58.584036 -246.721856) (xy 58.653571 -246.705986)
			(xy 58.724445 -246.698) (xy 58.795767 -246.698) (xy 58.866641 -246.705986) (xy 58.936176 -246.721856)
			(xy 59.003496 -246.745413) (xy 59.067755 -246.776358) (xy 59.128146 -246.814304) (xy 59.183908 -246.858773)
			(xy 59.234341 -246.909206) (xy 59.27881 -246.964968) (xy 59.316756 -247.025359) (xy 59.347701 -247.089618)
			(xy 59.371258 -247.156938) (xy 59.387128 -247.226473) (xy 59.395114 -247.297347) (xy 59.395614 -247.333008)
			(xy 59.395114 -247.368669) (xy 60.01181 -247.368669) (xy 60.01181 -247.297347) (xy 60.019796 -247.226473)
			(xy 60.035666 -247.156938) (xy 60.059223 -247.089618) (xy 60.090168 -247.025359) (xy 60.128114 -246.964968)
			(xy 60.172583 -246.909206) (xy 60.223016 -246.858773) (xy 60.278778 -246.814304) (xy 60.339169 -246.776358)
			(xy 60.403428 -246.745413) (xy 60.470748 -246.721856) (xy 60.540283 -246.705986) (xy 60.611157 -246.698)
			(xy 60.682479 -246.698) (xy 60.753353 -246.705986) (xy 60.822888 -246.721856) (xy 60.890208 -246.745413)
			(xy 60.954467 -246.776358) (xy 61.014858 -246.814304) (xy 61.07062 -246.858773) (xy 61.121053 -246.909206)
			(xy 61.165522 -246.964968) (xy 61.203468 -247.025359) (xy 61.234413 -247.089618) (xy 61.25797 -247.156938)
			(xy 61.27384 -247.226473) (xy 61.281826 -247.297347) (xy 61.282326 -247.333008) (xy 61.281826 -247.368669)
			(xy 62.252852 -247.368669) (xy 62.252852 -247.297347) (xy 62.260838 -247.226473) (xy 62.276708 -247.156938)
			(xy 62.300265 -247.089618) (xy 62.33121 -247.025359) (xy 62.369156 -246.964968) (xy 62.413625 -246.909206)
			(xy 62.464058 -246.858773) (xy 62.51982 -246.814304) (xy 62.580211 -246.776358) (xy 62.64447 -246.745413)
			(xy 62.71179 -246.721856) (xy 62.781325 -246.705986) (xy 62.852199 -246.698) (xy 62.923521 -246.698)
			(xy 62.994395 -246.705986) (xy 63.06393 -246.721856) (xy 63.13125 -246.745413) (xy 63.195509 -246.776358)
			(xy 63.2559 -246.814304) (xy 63.311662 -246.858773) (xy 63.362095 -246.909206) (xy 63.406564 -246.964968)
			(xy 63.44451 -247.025359) (xy 63.475455 -247.089618) (xy 63.499012 -247.156938) (xy 63.514882 -247.226473)
			(xy 63.522868 -247.297347) (xy 63.523368 -247.333008) (xy 63.522868 -247.368669) (xy 64.156836 -247.368669)
			(xy 64.156836 -247.297347) (xy 64.164822 -247.226473) (xy 64.180692 -247.156938) (xy 64.204249 -247.089618)
			(xy 64.235194 -247.025359) (xy 64.27314 -246.964968) (xy 64.317609 -246.909206) (xy 64.368042 -246.858773)
			(xy 64.423804 -246.814304) (xy 64.484195 -246.776358) (xy 64.548454 -246.745413) (xy 64.615774 -246.721856)
			(xy 64.685309 -246.705986) (xy 64.756183 -246.698) (xy 64.827505 -246.698) (xy 64.898379 -246.705986)
			(xy 64.967914 -246.721856) (xy 65.035234 -246.745413) (xy 65.099493 -246.776358) (xy 65.159884 -246.814304)
			(xy 65.215646 -246.858773) (xy 65.266079 -246.909206) (xy 65.310548 -246.964968) (xy 65.348494 -247.025359)
			(xy 65.379439 -247.089618) (xy 65.402996 -247.156938) (xy 65.418866 -247.226473) (xy 65.426852 -247.297347)
			(xy 65.427352 -247.333008) (xy 65.426852 -247.368669) (xy 65.418866 -247.439543) (xy 65.402996 -247.509078)
			(xy 65.379439 -247.576398) (xy 65.348494 -247.640657) (xy 65.310548 -247.701048) (xy 65.266079 -247.75681)
			(xy 65.215646 -247.807243) (xy 65.159884 -247.851712) (xy 65.099493 -247.889658) (xy 65.035234 -247.920603)
			(xy 64.967914 -247.94416) (xy 64.898379 -247.96003) (xy 64.827505 -247.968016) (xy 64.756183 -247.968016)
			(xy 64.685309 -247.96003) (xy 64.615774 -247.94416) (xy 64.548454 -247.920603) (xy 64.484195 -247.889658)
			(xy 64.423804 -247.851712) (xy 64.368042 -247.807243) (xy 64.317609 -247.75681) (xy 64.27314 -247.701048)
			(xy 64.235194 -247.640657) (xy 64.204249 -247.576398) (xy 64.180692 -247.509078) (xy 64.164822 -247.439543)
			(xy 64.156836 -247.368669) (xy 63.522868 -247.368669) (xy 63.514882 -247.439543) (xy 63.499012 -247.509078)
			(xy 63.475455 -247.576398) (xy 63.44451 -247.640657) (xy 63.406564 -247.701048) (xy 63.362095 -247.75681)
			(xy 63.311662 -247.807243) (xy 63.2559 -247.851712) (xy 63.195509 -247.889658) (xy 63.13125 -247.920603)
			(xy 63.06393 -247.94416) (xy 62.994395 -247.96003) (xy 62.923521 -247.968016) (xy 62.852199 -247.968016)
			(xy 62.781325 -247.96003) (xy 62.71179 -247.94416) (xy 62.64447 -247.920603) (xy 62.580211 -247.889658)
			(xy 62.51982 -247.851712) (xy 62.464058 -247.807243) (xy 62.413625 -247.75681) (xy 62.369156 -247.701048)
			(xy 62.33121 -247.640657) (xy 62.300265 -247.576398) (xy 62.276708 -247.509078) (xy 62.260838 -247.439543)
			(xy 62.252852 -247.368669) (xy 61.281826 -247.368669) (xy 61.27384 -247.439543) (xy 61.25797 -247.509078)
			(xy 61.234413 -247.576398) (xy 61.203468 -247.640657) (xy 61.165522 -247.701048) (xy 61.121053 -247.75681)
			(xy 61.07062 -247.807243) (xy 61.014858 -247.851712) (xy 60.954467 -247.889658) (xy 60.890208 -247.920603)
			(xy 60.822888 -247.94416) (xy 60.753353 -247.96003) (xy 60.682479 -247.968016) (xy 60.611157 -247.968016)
			(xy 60.540283 -247.96003) (xy 60.470748 -247.94416) (xy 60.403428 -247.920603) (xy 60.339169 -247.889658)
			(xy 60.278778 -247.851712) (xy 60.223016 -247.807243) (xy 60.172583 -247.75681) (xy 60.128114 -247.701048)
			(xy 60.090168 -247.640657) (xy 60.059223 -247.576398) (xy 60.035666 -247.509078) (xy 60.019796 -247.439543)
			(xy 60.01181 -247.368669) (xy 59.395114 -247.368669) (xy 59.387128 -247.439543) (xy 59.371258 -247.509078)
			(xy 59.347701 -247.576398) (xy 59.316756 -247.640657) (xy 59.27881 -247.701048) (xy 59.234341 -247.75681)
			(xy 59.183908 -247.807243) (xy 59.128146 -247.851712) (xy 59.067755 -247.889658) (xy 59.003496 -247.920603)
			(xy 58.936176 -247.94416) (xy 58.866641 -247.96003) (xy 58.795767 -247.968016) (xy 58.724445 -247.968016)
			(xy 58.653571 -247.96003) (xy 58.584036 -247.94416) (xy 58.516716 -247.920603) (xy 58.452457 -247.889658)
			(xy 58.392066 -247.851712) (xy 58.336304 -247.807243) (xy 58.285871 -247.75681) (xy 58.241402 -247.701048)
			(xy 58.203456 -247.640657) (xy 58.172511 -247.576398) (xy 58.148954 -247.509078) (xy 58.133084 -247.439543)
			(xy 58.125098 -247.368669) (xy 46.548262 -247.368669) (xy 46.547862 -247.371889) (xy 46.533227 -247.429825)
			(xy 46.511554 -247.485513) (xy 46.483177 -247.538101) (xy 46.448527 -247.586785) (xy 46.42866 -247.609106)
			(xy 46.42866 -247.664224) (xy 46.37151 -247.664224) (xy 46.33976 -247.685306) (xy 46.315954 -247.700603)
			(xy 46.26547 -247.72617) (xy 46.212342 -247.745659) (xy 46.157301 -247.758802) (xy 46.1011 -247.765419)
			(xy 46.072806 -247.765824) (xy 44.554394 -247.765824) (xy 44.14266 -247.35409) (xy 44.120658 -247.331357)
			(xy 44.082145 -247.281165) (xy 44.050512 -247.226376) (xy 44.026301 -247.167926) (xy 44.009927 -247.106817)
			(xy 44.001669 -247.044093) (xy 28.942538 -247.044093) (xy 28.942538 -249.023007) (xy 43.972967 -249.023007)
			(xy 43.972967 -248.959741) (xy 43.981225 -248.897017) (xy 43.997599 -248.835908) (xy 44.02181 -248.777458)
			(xy 44.053443 -248.722669) (xy 44.091956 -248.672477) (xy 44.113958 -248.649744) (xy 44.541694 -248.222008)
			(xy 46.096428 -248.222008) (xy 46.124696 -248.222437) (xy 46.180839 -248.22909) (xy 46.235823 -248.242242)
			(xy 46.2889 -248.261715) (xy 46.339345 -248.287243) (xy 46.363128 -248.302526) (xy 46.395132 -248.323608)
			(xy 46.557946 -248.323608) (xy 46.591728 -248.298208) (xy 46.618202 -248.27901) (xy 46.675137 -248.246839)
			(xy 46.735728 -248.222234) (xy 46.798974 -248.205601) (xy 46.86383 -248.197216) (xy 46.929226 -248.197216)
			(xy 46.994082 -248.205601) (xy 47.057328 -248.222234) (xy 47.117919 -248.246839) (xy 47.174854 -248.27901)
			(xy 47.201328 -248.298208) (xy 47.23511 -248.323608) (xy 47.252636 -248.323608) (xy 47.252636 -248.342404)
			(xy 47.276312 -248.366362) (xy 47.317749 -248.419464) (xy 47.35181 -248.477574) (xy 47.377899 -248.539673)
			(xy 47.395557 -248.604674) (xy 47.404477 -248.671438) (xy 47.405036 -248.705116) (xy 47.405036 -249.379841)
			(xy 58.081664 -249.379841) (xy 58.081664 -249.308519) (xy 58.08965 -249.237645) (xy 58.10552 -249.16811)
			(xy 58.129077 -249.10079) (xy 58.160022 -249.036531) (xy 58.197968 -248.97614) (xy 58.242437 -248.920378)
			(xy 58.29287 -248.869945) (xy 58.348632 -248.825476) (xy 58.409023 -248.78753) (xy 58.473282 -248.756585)
			(xy 58.540602 -248.733028) (xy 58.610137 -248.717158) (xy 58.681011 -248.709172) (xy 58.752333 -248.709172)
			(xy 58.823207 -248.717158) (xy 58.892742 -248.733028) (xy 58.960062 -248.756585) (xy 59.024321 -248.78753)
			(xy 59.084712 -248.825476) (xy 59.140474 -248.869945) (xy 59.190907 -248.920378) (xy 59.235376 -248.97614)
			(xy 59.273322 -249.036531) (xy 59.304267 -249.10079) (xy 59.327824 -249.16811) (xy 59.343694 -249.237645)
			(xy 59.35168 -249.308519) (xy 59.35218 -249.34418) (xy 59.35168 -249.379841) (xy 59.968376 -249.379841)
			(xy 59.968376 -249.308519) (xy 59.976362 -249.237645) (xy 59.992232 -249.16811) (xy 60.015789 -249.10079)
			(xy 60.046734 -249.036531) (xy 60.08468 -248.97614) (xy 60.129149 -248.920378) (xy 60.179582 -248.869945)
			(xy 60.235344 -248.825476) (xy 60.295735 -248.78753) (xy 60.359994 -248.756585) (xy 60.427314 -248.733028)
			(xy 60.496849 -248.717158) (xy 60.567723 -248.709172) (xy 60.639045 -248.709172) (xy 60.709919 -248.717158)
			(xy 60.779454 -248.733028) (xy 60.846774 -248.756585) (xy 60.911033 -248.78753) (xy 60.971424 -248.825476)
			(xy 61.027186 -248.869945) (xy 61.077619 -248.920378) (xy 61.122088 -248.97614) (xy 61.160034 -249.036531)
			(xy 61.190979 -249.10079) (xy 61.214536 -249.16811) (xy 61.230406 -249.237645) (xy 61.238392 -249.308519)
			(xy 61.238892 -249.34418) (xy 61.238392 -249.379841) (xy 62.209418 -249.379841) (xy 62.209418 -249.308519)
			(xy 62.217404 -249.237645) (xy 62.233274 -249.16811) (xy 62.256831 -249.10079) (xy 62.287776 -249.036531)
			(xy 62.325722 -248.97614) (xy 62.370191 -248.920378) (xy 62.420624 -248.869945) (xy 62.476386 -248.825476)
			(xy 62.536777 -248.78753) (xy 62.601036 -248.756585) (xy 62.668356 -248.733028) (xy 62.737891 -248.717158)
			(xy 62.808765 -248.709172) (xy 62.880087 -248.709172) (xy 62.950961 -248.717158) (xy 63.020496 -248.733028)
			(xy 63.087816 -248.756585) (xy 63.152075 -248.78753) (xy 63.212466 -248.825476) (xy 63.268228 -248.869945)
			(xy 63.318661 -248.920378) (xy 63.36313 -248.97614) (xy 63.401076 -249.036531) (xy 63.432021 -249.10079)
			(xy 63.455578 -249.16811) (xy 63.471448 -249.237645) (xy 63.479434 -249.308519) (xy 63.479934 -249.34418)
			(xy 63.479434 -249.379841) (xy 64.113402 -249.379841) (xy 64.113402 -249.308519) (xy 64.121388 -249.237645)
			(xy 64.137258 -249.16811) (xy 64.160815 -249.10079) (xy 64.19176 -249.036531) (xy 64.229706 -248.97614)
			(xy 64.274175 -248.920378) (xy 64.324608 -248.869945) (xy 64.38037 -248.825476) (xy 64.440761 -248.78753)
			(xy 64.50502 -248.756585) (xy 64.57234 -248.733028) (xy 64.641875 -248.717158) (xy 64.712749 -248.709172)
			(xy 64.784071 -248.709172) (xy 64.854945 -248.717158) (xy 64.92448 -248.733028) (xy 64.9918 -248.756585)
			(xy 65.056059 -248.78753) (xy 65.11645 -248.825476) (xy 65.172212 -248.869945) (xy 65.222645 -248.920378)
			(xy 65.267114 -248.97614) (xy 65.30506 -249.036531) (xy 65.336005 -249.10079) (xy 65.359562 -249.16811)
			(xy 65.375432 -249.237645) (xy 65.383418 -249.308519) (xy 65.383918 -249.34418) (xy 65.383418 -249.379841)
			(xy 65.375432 -249.450715) (xy 65.359562 -249.52025) (xy 65.336005 -249.58757) (xy 65.30506 -249.651829)
			(xy 65.267114 -249.71222) (xy 65.222645 -249.767982) (xy 65.172212 -249.818415) (xy 65.11645 -249.862884)
			(xy 65.056059 -249.90083) (xy 64.9918 -249.931775) (xy 64.92448 -249.955332) (xy 64.854945 -249.971202)
			(xy 64.784071 -249.979188) (xy 64.712749 -249.979188) (xy 64.641875 -249.971202) (xy 64.57234 -249.955332)
			(xy 64.50502 -249.931775) (xy 64.440761 -249.90083) (xy 64.38037 -249.862884) (xy 64.324608 -249.818415)
			(xy 64.274175 -249.767982) (xy 64.229706 -249.71222) (xy 64.19176 -249.651829) (xy 64.160815 -249.58757)
			(xy 64.137258 -249.52025) (xy 64.121388 -249.450715) (xy 64.113402 -249.379841) (xy 63.479434 -249.379841)
			(xy 63.471448 -249.450715) (xy 63.455578 -249.52025) (xy 63.432021 -249.58757) (xy 63.401076 -249.651829)
			(xy 63.36313 -249.71222) (xy 63.318661 -249.767982) (xy 63.268228 -249.818415) (xy 63.212466 -249.862884)
			(xy 63.152075 -249.90083) (xy 63.087816 -249.931775) (xy 63.020496 -249.955332) (xy 62.950961 -249.971202)
			(xy 62.880087 -249.979188) (xy 62.808765 -249.979188) (xy 62.737891 -249.971202) (xy 62.668356 -249.955332)
			(xy 62.601036 -249.931775) (xy 62.536777 -249.90083) (xy 62.476386 -249.862884) (xy 62.420624 -249.818415)
			(xy 62.370191 -249.767982) (xy 62.325722 -249.71222) (xy 62.287776 -249.651829) (xy 62.256831 -249.58757)
			(xy 62.233274 -249.52025) (xy 62.217404 -249.450715) (xy 62.209418 -249.379841) (xy 61.238392 -249.379841)
			(xy 61.230406 -249.450715) (xy 61.214536 -249.52025) (xy 61.190979 -249.58757) (xy 61.160034 -249.651829)
			(xy 61.122088 -249.71222) (xy 61.077619 -249.767982) (xy 61.027186 -249.818415) (xy 60.971424 -249.862884)
			(xy 60.911033 -249.90083) (xy 60.846774 -249.931775) (xy 60.779454 -249.955332) (xy 60.709919 -249.971202)
			(xy 60.639045 -249.979188) (xy 60.567723 -249.979188) (xy 60.496849 -249.971202) (xy 60.427314 -249.955332)
			(xy 60.359994 -249.931775) (xy 60.295735 -249.90083) (xy 60.235344 -249.862884) (xy 60.179582 -249.818415)
			(xy 60.129149 -249.767982) (xy 60.08468 -249.71222) (xy 60.046734 -249.651829) (xy 60.015789 -249.58757)
			(xy 59.992232 -249.52025) (xy 59.976362 -249.450715) (xy 59.968376 -249.379841) (xy 59.35168 -249.379841)
			(xy 59.343694 -249.450715) (xy 59.327824 -249.52025) (xy 59.304267 -249.58757) (xy 59.273322 -249.651829)
			(xy 59.235376 -249.71222) (xy 59.190907 -249.767982) (xy 59.140474 -249.818415) (xy 59.084712 -249.862884)
			(xy 59.024321 -249.90083) (xy 58.960062 -249.931775) (xy 58.892742 -249.955332) (xy 58.823207 -249.971202)
			(xy 58.752333 -249.979188) (xy 58.681011 -249.979188) (xy 58.610137 -249.971202) (xy 58.540602 -249.955332)
			(xy 58.473282 -249.931775) (xy 58.409023 -249.90083) (xy 58.348632 -249.862884) (xy 58.29287 -249.818415)
			(xy 58.242437 -249.767982) (xy 58.197968 -249.71222) (xy 58.160022 -249.651829) (xy 58.129077 -249.58757)
			(xy 58.10552 -249.52025) (xy 58.08965 -249.450715) (xy 58.081664 -249.379841) (xy 47.405036 -249.379841)
			(xy 47.405036 -249.789442) (xy 47.404534 -249.821403) (xy 47.396523 -249.884821) (xy 47.380626 -249.946735)
			(xy 47.357094 -250.006168) (xy 47.3263 -250.062183) (xy 47.288727 -250.113898) (xy 47.24497 -250.160495)
			(xy 47.195717 -250.20124) (xy 47.141746 -250.235491) (xy 47.083907 -250.262708) (xy 47.023114 -250.282461)
			(xy 46.960324 -250.294439) (xy 46.896528 -250.298453) (xy 46.832732 -250.294439) (xy 46.769942 -250.282461)
			(xy 46.709149 -250.262708) (xy 46.65131 -250.235491) (xy 46.597339 -250.20124) (xy 46.548086 -250.160495)
			(xy 46.504329 -250.113898) (xy 46.466756 -250.062183) (xy 46.435962 -250.006168) (xy 46.41243 -249.946735)
			(xy 46.396533 -249.884821) (xy 46.388522 -249.821403) (xy 46.38802 -249.789442) (xy 46.38802 -249.441208)
			(xy 46.387593 -249.418296) (xy 46.379396 -249.373212) (xy 46.363247 -249.330328) (xy 46.339671 -249.291035)
			(xy 46.309431 -249.256607) (xy 46.273508 -249.228158) (xy 46.233066 -249.206612) (xy 46.189416 -249.192667)
			(xy 46.143973 -249.186775) (xy 46.121066 -249.187462) (xy 46.096428 -249.188224) (xy 44.941998 -249.188224)
			(xy 44.797218 -249.333004) (xy 44.774485 -249.355006) (xy 44.724293 -249.393519) (xy 44.669504 -249.425152)
			(xy 44.611054 -249.449363) (xy 44.549945 -249.465737) (xy 44.487221 -249.473995) (xy 44.423955 -249.473995)
			(xy 44.361231 -249.465737) (xy 44.300122 -249.449363) (xy 44.241672 -249.425152) (xy 44.186883 -249.393519)
			(xy 44.136691 -249.355006) (xy 44.091956 -249.310271) (xy 44.053443 -249.260079) (xy 44.02181 -249.20529)
			(xy 43.997599 -249.14684) (xy 43.981225 -249.085731) (xy 43.972967 -249.023007) (xy 28.942538 -249.023007)
			(xy 28.942538 -251.480965) (xy 44.155847 -251.480965) (xy 44.155847 -251.417699) (xy 44.164105 -251.354975)
			(xy 44.180479 -251.293866) (xy 44.20469 -251.235416) (xy 44.236323 -251.180627) (xy 44.274836 -251.130435)
			(xy 44.319571 -251.0857) (xy 44.369763 -251.047187) (xy 44.424552 -251.015554) (xy 44.483002 -250.991343)
			(xy 44.544111 -250.974969) (xy 44.606835 -250.966711) (xy 44.670101 -250.966711) (xy 44.732825 -250.974969)
			(xy 44.793934 -250.991343) (xy 44.852384 -251.015554) (xy 44.907173 -251.047187) (xy 44.957365 -251.0857)
			(xy 44.980098 -251.107702) (xy 45.09262 -251.220224) (xy 46.036738 -251.220224) (xy 46.065032 -251.220639)
			(xy 46.121232 -251.227257) (xy 46.176274 -251.240397) (xy 46.229403 -251.259879) (xy 46.250113 -251.270363)
			(xy 58.081664 -251.270363) (xy 58.081664 -251.199041) (xy 58.08965 -251.128167) (xy 58.10552 -251.058632)
			(xy 58.129077 -250.991312) (xy 58.160022 -250.927053) (xy 58.197968 -250.866662) (xy 58.242437 -250.8109)
			(xy 58.29287 -250.760467) (xy 58.348632 -250.715998) (xy 58.409023 -250.678052) (xy 58.473282 -250.647107)
			(xy 58.540602 -250.62355) (xy 58.610137 -250.60768) (xy 58.681011 -250.599694) (xy 58.752333 -250.599694)
			(xy 58.823207 -250.60768) (xy 58.892742 -250.62355) (xy 58.960062 -250.647107) (xy 59.024321 -250.678052)
			(xy 59.084712 -250.715998) (xy 59.140474 -250.760467) (xy 59.190907 -250.8109) (xy 59.235376 -250.866662)
			(xy 59.273322 -250.927053) (xy 59.304267 -250.991312) (xy 59.327824 -251.058632) (xy 59.343694 -251.128167)
			(xy 59.35168 -251.199041) (xy 59.35218 -251.234702) (xy 59.35168 -251.270363) (xy 59.968376 -251.270363)
			(xy 59.968376 -251.199041) (xy 59.976362 -251.128167) (xy 59.992232 -251.058632) (xy 60.015789 -250.991312)
			(xy 60.046734 -250.927053) (xy 60.08468 -250.866662) (xy 60.129149 -250.8109) (xy 60.179582 -250.760467)
			(xy 60.235344 -250.715998) (xy 60.295735 -250.678052) (xy 60.359994 -250.647107) (xy 60.427314 -250.62355)
			(xy 60.496849 -250.60768) (xy 60.567723 -250.599694) (xy 60.639045 -250.599694) (xy 60.709919 -250.60768)
			(xy 60.779454 -250.62355) (xy 60.846774 -250.647107) (xy 60.911033 -250.678052) (xy 60.971424 -250.715998)
			(xy 61.027186 -250.760467) (xy 61.077619 -250.8109) (xy 61.122088 -250.866662) (xy 61.160034 -250.927053)
			(xy 61.190979 -250.991312) (xy 61.214536 -251.058632) (xy 61.230406 -251.128167) (xy 61.238392 -251.199041)
			(xy 61.238892 -251.234702) (xy 61.238392 -251.270363) (xy 62.209418 -251.270363) (xy 62.209418 -251.199041)
			(xy 62.217404 -251.128167) (xy 62.233274 -251.058632) (xy 62.256831 -250.991312) (xy 62.287776 -250.927053)
			(xy 62.325722 -250.866662) (xy 62.370191 -250.8109) (xy 62.420624 -250.760467) (xy 62.476386 -250.715998)
			(xy 62.536777 -250.678052) (xy 62.601036 -250.647107) (xy 62.668356 -250.62355) (xy 62.737891 -250.60768)
			(xy 62.808765 -250.599694) (xy 62.880087 -250.599694) (xy 62.950961 -250.60768) (xy 63.020496 -250.62355)
			(xy 63.087816 -250.647107) (xy 63.152075 -250.678052) (xy 63.212466 -250.715998) (xy 63.268228 -250.760467)
			(xy 63.318661 -250.8109) (xy 63.36313 -250.866662) (xy 63.401076 -250.927053) (xy 63.432021 -250.991312)
			(xy 63.455578 -251.058632) (xy 63.471448 -251.128167) (xy 63.479434 -251.199041) (xy 63.479934 -251.234702)
			(xy 63.479434 -251.270363) (xy 64.113402 -251.270363) (xy 64.113402 -251.199041) (xy 64.121388 -251.128167)
			(xy 64.137258 -251.058632) (xy 64.160815 -250.991312) (xy 64.19176 -250.927053) (xy 64.229706 -250.866662)
			(xy 64.274175 -250.8109) (xy 64.324608 -250.760467) (xy 64.38037 -250.715998) (xy 64.440761 -250.678052)
			(xy 64.50502 -250.647107) (xy 64.57234 -250.62355) (xy 64.641875 -250.60768) (xy 64.712749 -250.599694)
			(xy 64.784071 -250.599694) (xy 64.854945 -250.60768) (xy 64.92448 -250.62355) (xy 64.9918 -250.647107)
			(xy 65.056059 -250.678052) (xy 65.11645 -250.715998) (xy 65.172212 -250.760467) (xy 65.222645 -250.8109)
			(xy 65.267114 -250.866662) (xy 65.30506 -250.927053) (xy 65.336005 -250.991312) (xy 65.359562 -251.058632)
			(xy 65.375432 -251.128167) (xy 65.383418 -251.199041) (xy 65.383918 -251.234702) (xy 65.383418 -251.270363)
			(xy 65.375432 -251.341237) (xy 65.359562 -251.410772) (xy 65.336005 -251.478092) (xy 65.30506 -251.542351)
			(xy 65.267114 -251.602742) (xy 65.222645 -251.658504) (xy 65.172212 -251.708937) (xy 65.11645 -251.753406)
			(xy 65.056059 -251.791352) (xy 64.9918 -251.822297) (xy 64.92448 -251.845854) (xy 64.854945 -251.861724)
			(xy 64.784071 -251.86971) (xy 64.712749 -251.86971) (xy 64.641875 -251.861724) (xy 64.57234 -251.845854)
			(xy 64.50502 -251.822297) (xy 64.440761 -251.791352) (xy 64.38037 -251.753406) (xy 64.324608 -251.708937)
			(xy 64.274175 -251.658504) (xy 64.229706 -251.602742) (xy 64.19176 -251.542351) (xy 64.160815 -251.478092)
			(xy 64.137258 -251.410772) (xy 64.121388 -251.341237) (xy 64.113402 -251.270363) (xy 63.479434 -251.270363)
			(xy 63.471448 -251.341237) (xy 63.455578 -251.410772) (xy 63.432021 -251.478092) (xy 63.401076 -251.542351)
			(xy 63.36313 -251.602742) (xy 63.318661 -251.658504) (xy 63.268228 -251.708937) (xy 63.212466 -251.753406)
			(xy 63.152075 -251.791352) (xy 63.087816 -251.822297) (xy 63.020496 -251.845854) (xy 62.950961 -251.861724)
			(xy 62.880087 -251.86971) (xy 62.808765 -251.86971) (xy 62.737891 -251.861724) (xy 62.668356 -251.845854)
			(xy 62.601036 -251.822297) (xy 62.536777 -251.791352) (xy 62.476386 -251.753406) (xy 62.420624 -251.708937)
			(xy 62.370191 -251.658504) (xy 62.325722 -251.602742) (xy 62.287776 -251.542351) (xy 62.256831 -251.478092)
			(xy 62.233274 -251.410772) (xy 62.217404 -251.341237) (xy 62.209418 -251.270363) (xy 61.238392 -251.270363)
			(xy 61.230406 -251.341237) (xy 61.214536 -251.410772) (xy 61.190979 -251.478092) (xy 61.160034 -251.542351)
			(xy 61.122088 -251.602742) (xy 61.077619 -251.658504) (xy 61.027186 -251.708937) (xy 60.971424 -251.753406)
			(xy 60.911033 -251.791352) (xy 60.846774 -251.822297) (xy 60.779454 -251.845854) (xy 60.709919 -251.861724)
			(xy 60.639045 -251.86971) (xy 60.567723 -251.86971) (xy 60.496849 -251.861724) (xy 60.427314 -251.845854)
			(xy 60.359994 -251.822297) (xy 60.295735 -251.791352) (xy 60.235344 -251.753406) (xy 60.179582 -251.708937)
			(xy 60.129149 -251.658504) (xy 60.08468 -251.602742) (xy 60.046734 -251.542351) (xy 60.015789 -251.478092)
			(xy 59.992232 -251.410772) (xy 59.976362 -251.341237) (xy 59.968376 -251.270363) (xy 59.35168 -251.270363)
			(xy 59.343694 -251.341237) (xy 59.327824 -251.410772) (xy 59.304267 -251.478092) (xy 59.273322 -251.542351)
			(xy 59.235376 -251.602742) (xy 59.190907 -251.658504) (xy 59.140474 -251.708937) (xy 59.084712 -251.753406)
			(xy 59.024321 -251.791352) (xy 58.960062 -251.822297) (xy 58.892742 -251.845854) (xy 58.823207 -251.861724)
			(xy 58.752333 -251.86971) (xy 58.681011 -251.86971) (xy 58.610137 -251.861724) (xy 58.540602 -251.845854)
			(xy 58.473282 -251.822297) (xy 58.409023 -251.791352) (xy 58.348632 -251.753406) (xy 58.29287 -251.708937)
			(xy 58.242437 -251.658504) (xy 58.197968 -251.602742) (xy 58.160022 -251.542351) (xy 58.129077 -251.478092)
			(xy 58.10552 -251.410772) (xy 58.08965 -251.341237) (xy 58.081664 -251.270363) (xy 46.250113 -251.270363)
			(xy 46.279891 -251.285437) (xy 46.303692 -251.300742) (xy 46.335442 -251.321824) (xy 46.392592 -251.321824)
			(xy 46.392592 -251.376942) (xy 46.412488 -251.399236) (xy 46.447133 -251.447925) (xy 46.475506 -251.500516)
			(xy 46.497173 -251.556207) (xy 46.511803 -251.614145) (xy 46.519173 -251.673445) (xy 46.51917 -251.733202)
			(xy 46.511795 -251.792502) (xy 46.497159 -251.850438) (xy 46.475486 -251.906127) (xy 46.447108 -251.958715)
			(xy 46.412459 -252.007401) (xy 46.392592 -252.029722) (xy 46.392592 -252.08484) (xy 46.335442 -252.08484)
			(xy 46.303692 -252.105922) (xy 46.279905 -252.12125) (xy 46.229415 -252.146811) (xy 46.176283 -252.166293)
			(xy 46.121238 -252.179429) (xy 46.065034 -252.186039) (xy 46.036738 -252.18644) (xy 44.692316 -252.18644)
			(xy 44.296838 -251.790962) (xy 44.274836 -251.768229) (xy 44.236323 -251.718037) (xy 44.20469 -251.663248)
			(xy 44.180479 -251.604798) (xy 44.164105 -251.543689) (xy 44.155847 -251.480965) (xy 28.942538 -251.480965)
			(xy 28.942538 -253.40564) (xy 44.081192 -253.40564) (xy 44.081192 -253.399544) (xy 44.08164 -253.367918)
			(xy 44.089852 -253.305201) (xy 44.106182 -253.244094) (xy 44.13035 -253.185641) (xy 44.161941 -253.130844)
			(xy 44.200416 -253.08064) (xy 44.222416 -253.057914) (xy 44.637706 -252.642624) (xy 46.025562 -252.642624)
			(xy 46.05383 -252.643034) (xy 46.109974 -252.649691) (xy 46.164959 -252.662847) (xy 46.218035 -252.682324)
			(xy 46.268479 -252.707856) (xy 46.292262 -252.723142) (xy 46.324266 -252.744224) (xy 46.48708 -252.744224)
			(xy 46.520862 -252.718824) (xy 46.547336 -252.699626) (xy 46.604271 -252.667455) (xy 46.664862 -252.64285)
			(xy 46.728108 -252.626217) (xy 46.792964 -252.617832) (xy 46.85836 -252.617832) (xy 46.923216 -252.626217)
			(xy 46.986462 -252.64285) (xy 47.047053 -252.667455) (xy 47.103988 -252.699626) (xy 47.130462 -252.718824)
			(xy 47.164244 -252.744224) (xy 47.18177 -252.744224) (xy 47.18177 -252.76302) (xy 47.205403 -252.787006)
			(xy 47.246797 -252.840118) (xy 47.280816 -252.89823) (xy 47.306864 -252.960325) (xy 47.324486 -253.025315)
			(xy 47.333372 -253.092063) (xy 47.333916 -253.125732) (xy 47.333916 -253.311507) (xy 58.081664 -253.311507)
			(xy 58.081664 -253.240185) (xy 58.08965 -253.169311) (xy 58.10552 -253.099776) (xy 58.129077 -253.032456)
			(xy 58.160022 -252.968197) (xy 58.197968 -252.907806) (xy 58.242437 -252.852044) (xy 58.29287 -252.801611)
			(xy 58.348632 -252.757142) (xy 58.409023 -252.719196) (xy 58.473282 -252.688251) (xy 58.540602 -252.664694)
			(xy 58.610137 -252.648824) (xy 58.681011 -252.640838) (xy 58.752333 -252.640838) (xy 58.823207 -252.648824)
			(xy 58.892742 -252.664694) (xy 58.960062 -252.688251) (xy 59.024321 -252.719196) (xy 59.084712 -252.757142)
			(xy 59.140474 -252.801611) (xy 59.190907 -252.852044) (xy 59.235376 -252.907806) (xy 59.273322 -252.968197)
			(xy 59.304267 -253.032456) (xy 59.327824 -253.099776) (xy 59.343694 -253.169311) (xy 59.35168 -253.240185)
			(xy 59.35218 -253.275846) (xy 59.35168 -253.311507) (xy 59.968376 -253.311507) (xy 59.968376 -253.240185)
			(xy 59.976362 -253.169311) (xy 59.992232 -253.099776) (xy 60.015789 -253.032456) (xy 60.046734 -252.968197)
			(xy 60.08468 -252.907806) (xy 60.129149 -252.852044) (xy 60.179582 -252.801611) (xy 60.235344 -252.757142)
			(xy 60.295735 -252.719196) (xy 60.359994 -252.688251) (xy 60.427314 -252.664694) (xy 60.496849 -252.648824)
			(xy 60.567723 -252.640838) (xy 60.639045 -252.640838) (xy 60.709919 -252.648824) (xy 60.779454 -252.664694)
			(xy 60.846774 -252.688251) (xy 60.911033 -252.719196) (xy 60.971424 -252.757142) (xy 61.027186 -252.801611)
			(xy 61.077619 -252.852044) (xy 61.122088 -252.907806) (xy 61.160034 -252.968197) (xy 61.190979 -253.032456)
			(xy 61.214536 -253.099776) (xy 61.230406 -253.169311) (xy 61.238392 -253.240185) (xy 61.238892 -253.275846)
			(xy 61.238392 -253.311507) (xy 62.209418 -253.311507) (xy 62.209418 -253.240185) (xy 62.217404 -253.169311)
			(xy 62.233274 -253.099776) (xy 62.256831 -253.032456) (xy 62.287776 -252.968197) (xy 62.325722 -252.907806)
			(xy 62.370191 -252.852044) (xy 62.420624 -252.801611) (xy 62.476386 -252.757142) (xy 62.536777 -252.719196)
			(xy 62.601036 -252.688251) (xy 62.668356 -252.664694) (xy 62.737891 -252.648824) (xy 62.808765 -252.640838)
			(xy 62.880087 -252.640838) (xy 62.950961 -252.648824) (xy 63.020496 -252.664694) (xy 63.087816 -252.688251)
			(xy 63.152075 -252.719196) (xy 63.212466 -252.757142) (xy 63.268228 -252.801611) (xy 63.318661 -252.852044)
			(xy 63.36313 -252.907806) (xy 63.401076 -252.968197) (xy 63.432021 -253.032456) (xy 63.455578 -253.099776)
			(xy 63.471448 -253.169311) (xy 63.479434 -253.240185) (xy 63.479934 -253.275846) (xy 63.479434 -253.311507)
			(xy 64.113402 -253.311507) (xy 64.113402 -253.240185) (xy 64.121388 -253.169311) (xy 64.137258 -253.099776)
			(xy 64.160815 -253.032456) (xy 64.19176 -252.968197) (xy 64.229706 -252.907806) (xy 64.274175 -252.852044)
			(xy 64.324608 -252.801611) (xy 64.38037 -252.757142) (xy 64.440761 -252.719196) (xy 64.50502 -252.688251)
			(xy 64.57234 -252.664694) (xy 64.641875 -252.648824) (xy 64.712749 -252.640838) (xy 64.784071 -252.640838)
			(xy 64.854945 -252.648824) (xy 64.92448 -252.664694) (xy 64.9918 -252.688251) (xy 65.056059 -252.719196)
			(xy 65.11645 -252.757142) (xy 65.172212 -252.801611) (xy 65.222645 -252.852044) (xy 65.267114 -252.907806)
			(xy 65.30506 -252.968197) (xy 65.336005 -253.032456) (xy 65.359562 -253.099776) (xy 65.375432 -253.169311)
			(xy 65.383418 -253.240185) (xy 65.383918 -253.275846) (xy 65.383418 -253.311507) (xy 65.375432 -253.382381)
			(xy 65.359562 -253.451916) (xy 65.336005 -253.519236) (xy 65.30506 -253.583495) (xy 65.267114 -253.643886)
			(xy 65.222645 -253.699648) (xy 65.172212 -253.750081) (xy 65.11645 -253.79455) (xy 65.056059 -253.832496)
			(xy 64.9918 -253.863441) (xy 64.92448 -253.886998) (xy 64.854945 -253.902868) (xy 64.784071 -253.910854)
			(xy 64.712749 -253.910854) (xy 64.641875 -253.902868) (xy 64.57234 -253.886998) (xy 64.50502 -253.863441)
			(xy 64.440761 -253.832496) (xy 64.38037 -253.79455) (xy 64.324608 -253.750081) (xy 64.274175 -253.699648)
			(xy 64.229706 -253.643886) (xy 64.19176 -253.583495) (xy 64.160815 -253.519236) (xy 64.137258 -253.451916)
			(xy 64.121388 -253.382381) (xy 64.113402 -253.311507) (xy 63.479434 -253.311507) (xy 63.471448 -253.382381)
			(xy 63.455578 -253.451916) (xy 63.432021 -253.519236) (xy 63.401076 -253.583495) (xy 63.36313 -253.643886)
			(xy 63.318661 -253.699648) (xy 63.268228 -253.750081) (xy 63.212466 -253.79455) (xy 63.152075 -253.832496)
			(xy 63.087816 -253.863441) (xy 63.020496 -253.886998) (xy 62.950961 -253.902868) (xy 62.880087 -253.910854)
			(xy 62.808765 -253.910854) (xy 62.737891 -253.902868) (xy 62.668356 -253.886998) (xy 62.601036 -253.863441)
			(xy 62.536777 -253.832496) (xy 62.476386 -253.79455) (xy 62.420624 -253.750081) (xy 62.370191 -253.699648)
			(xy 62.325722 -253.643886) (xy 62.287776 -253.583495) (xy 62.256831 -253.519236) (xy 62.233274 -253.451916)
			(xy 62.217404 -253.382381) (xy 62.209418 -253.311507) (xy 61.238392 -253.311507) (xy 61.230406 -253.382381)
			(xy 61.214536 -253.451916) (xy 61.190979 -253.519236) (xy 61.160034 -253.583495) (xy 61.122088 -253.643886)
			(xy 61.077619 -253.699648) (xy 61.027186 -253.750081) (xy 60.971424 -253.79455) (xy 60.911033 -253.832496)
			(xy 60.846774 -253.863441) (xy 60.779454 -253.886998) (xy 60.709919 -253.902868) (xy 60.639045 -253.910854)
			(xy 60.567723 -253.910854) (xy 60.496849 -253.902868) (xy 60.427314 -253.886998) (xy 60.359994 -253.863441)
			(xy 60.295735 -253.832496) (xy 60.235344 -253.79455) (xy 60.179582 -253.750081) (xy 60.129149 -253.699648)
			(xy 60.08468 -253.643886) (xy 60.046734 -253.583495) (xy 60.015789 -253.519236) (xy 59.992232 -253.451916)
			(xy 59.976362 -253.382381) (xy 59.968376 -253.311507) (xy 59.35168 -253.311507) (xy 59.343694 -253.382381)
			(xy 59.327824 -253.451916) (xy 59.304267 -253.519236) (xy 59.273322 -253.583495) (xy 59.235376 -253.643886)
			(xy 59.190907 -253.699648) (xy 59.140474 -253.750081) (xy 59.084712 -253.79455) (xy 59.024321 -253.832496)
			(xy 58.960062 -253.863441) (xy 58.892742 -253.886998) (xy 58.823207 -253.902868) (xy 58.752333 -253.910854)
			(xy 58.681011 -253.910854) (xy 58.610137 -253.902868) (xy 58.540602 -253.886998) (xy 58.473282 -253.863441)
			(xy 58.409023 -253.832496) (xy 58.348632 -253.79455) (xy 58.29287 -253.750081) (xy 58.242437 -253.699648)
			(xy 58.197968 -253.643886) (xy 58.160022 -253.583495) (xy 58.129077 -253.519236) (xy 58.10552 -253.451916)
			(xy 58.08965 -253.382381) (xy 58.081664 -253.311507) (xy 47.333916 -253.311507) (xy 47.333916 -254.395224)
			(xy 47.333415 -254.427169) (xy 47.325407 -254.490555) (xy 47.309518 -254.552438) (xy 47.285999 -254.611842)
			(xy 47.255219 -254.667829) (xy 47.217666 -254.719518) (xy 47.17393 -254.766092) (xy 47.124702 -254.806817)
			(xy 47.070757 -254.841051) (xy 47.012948 -254.868254) (xy 46.952185 -254.887997) (xy 46.889426 -254.899969)
			(xy 46.825662 -254.903981) (xy 46.761898 -254.899969) (xy 46.699139 -254.887997) (xy 46.638376 -254.868254)
			(xy 46.580567 -254.841051) (xy 46.526622 -254.806817) (xy 46.477394 -254.766092) (xy 46.433658 -254.719518)
			(xy 46.396105 -254.667829) (xy 46.365325 -254.611842) (xy 46.341806 -254.552438) (xy 46.325917 -254.490555)
			(xy 46.317909 -254.427169) (xy 46.317408 -254.395224) (xy 46.317408 -253.861824) (xy 46.316991 -253.838897)
			(xy 46.308785 -253.793782) (xy 46.292618 -253.750873) (xy 46.269013 -253.711561) (xy 46.238738 -253.677122)
			(xy 46.202775 -253.648674) (xy 46.162291 -253.627141) (xy 46.118601 -253.613222) (xy 46.073121 -253.607367)
			(xy 46.0502 -253.608078) (xy 46.025562 -253.60884) (xy 45.03801 -253.60884) (xy 44.948348 -253.698248)
			(xy 44.943776 -253.70409) (xy 44.923888 -253.728482) (xy 44.878894 -253.772486) (xy 44.828565 -253.810271)
			(xy 44.773754 -253.841198) (xy 44.715389 -253.864743) (xy 44.654461 -253.880506) (xy 44.592 -253.88822)
			(xy 44.529068 -253.887755) (xy 44.466728 -253.879118) (xy 44.406039 -253.862456) (xy 44.348029 -253.838051)
			(xy 44.293681 -253.806317) (xy 44.243916 -253.767792) (xy 44.199577 -253.723128) (xy 44.161417 -253.673083)
			(xy 44.130081 -253.618504) (xy 44.106101 -253.560317) (xy 44.089883 -253.499508) (xy 44.081702 -253.437107)
			(xy 44.081192 -253.40564) (xy 28.942538 -253.40564) (xy 28.942538 -255.221333) (xy 58.081664 -255.221333)
			(xy 58.081664 -255.150011) (xy 58.08965 -255.079137) (xy 58.10552 -255.009602) (xy 58.129077 -254.942282)
			(xy 58.160022 -254.878023) (xy 58.197968 -254.817632) (xy 58.242437 -254.76187) (xy 58.29287 -254.711437)
			(xy 58.348632 -254.666968) (xy 58.409023 -254.629022) (xy 58.473282 -254.598077) (xy 58.540602 -254.57452)
			(xy 58.610137 -254.55865) (xy 58.681011 -254.550664) (xy 58.752333 -254.550664) (xy 58.823207 -254.55865)
			(xy 58.892742 -254.57452) (xy 58.960062 -254.598077) (xy 59.024321 -254.629022) (xy 59.084712 -254.666968)
			(xy 59.140474 -254.711437) (xy 59.190907 -254.76187) (xy 59.235376 -254.817632) (xy 59.273322 -254.878023)
			(xy 59.304267 -254.942282) (xy 59.327824 -255.009602) (xy 59.343694 -255.079137) (xy 59.35168 -255.150011)
			(xy 59.35218 -255.185672) (xy 59.35168 -255.221333) (xy 59.968376 -255.221333) (xy 59.968376 -255.150011)
			(xy 59.976362 -255.079137) (xy 59.992232 -255.009602) (xy 60.015789 -254.942282) (xy 60.046734 -254.878023)
			(xy 60.08468 -254.817632) (xy 60.129149 -254.76187) (xy 60.179582 -254.711437) (xy 60.235344 -254.666968)
			(xy 60.295735 -254.629022) (xy 60.359994 -254.598077) (xy 60.427314 -254.57452) (xy 60.496849 -254.55865)
			(xy 60.567723 -254.550664) (xy 60.639045 -254.550664) (xy 60.709919 -254.55865) (xy 60.779454 -254.57452)
			(xy 60.846774 -254.598077) (xy 60.911033 -254.629022) (xy 60.971424 -254.666968) (xy 61.027186 -254.711437)
			(xy 61.077619 -254.76187) (xy 61.122088 -254.817632) (xy 61.160034 -254.878023) (xy 61.190979 -254.942282)
			(xy 61.214536 -255.009602) (xy 61.230406 -255.079137) (xy 61.238392 -255.150011) (xy 61.238892 -255.185672)
			(xy 61.238392 -255.221333) (xy 62.209418 -255.221333) (xy 62.209418 -255.150011) (xy 62.217404 -255.079137)
			(xy 62.233274 -255.009602) (xy 62.256831 -254.942282) (xy 62.287776 -254.878023) (xy 62.325722 -254.817632)
			(xy 62.370191 -254.76187) (xy 62.420624 -254.711437) (xy 62.476386 -254.666968) (xy 62.536777 -254.629022)
			(xy 62.601036 -254.598077) (xy 62.668356 -254.57452) (xy 62.737891 -254.55865) (xy 62.808765 -254.550664)
			(xy 62.880087 -254.550664) (xy 62.950961 -254.55865) (xy 63.020496 -254.57452) (xy 63.087816 -254.598077)
			(xy 63.152075 -254.629022) (xy 63.212466 -254.666968) (xy 63.268228 -254.711437) (xy 63.318661 -254.76187)
			(xy 63.36313 -254.817632) (xy 63.401076 -254.878023) (xy 63.432021 -254.942282) (xy 63.455578 -255.009602)
			(xy 63.471448 -255.079137) (xy 63.479434 -255.150011) (xy 63.479934 -255.185672) (xy 63.479434 -255.221333)
			(xy 64.113402 -255.221333) (xy 64.113402 -255.150011) (xy 64.121388 -255.079137) (xy 64.137258 -255.009602)
			(xy 64.160815 -254.942282) (xy 64.19176 -254.878023) (xy 64.229706 -254.817632) (xy 64.274175 -254.76187)
			(xy 64.324608 -254.711437) (xy 64.38037 -254.666968) (xy 64.440761 -254.629022) (xy 64.50502 -254.598077)
			(xy 64.57234 -254.57452) (xy 64.641875 -254.55865) (xy 64.712749 -254.550664) (xy 64.784071 -254.550664)
			(xy 64.854945 -254.55865) (xy 64.92448 -254.57452) (xy 64.9918 -254.598077) (xy 65.056059 -254.629022)
			(xy 65.11645 -254.666968) (xy 65.172212 -254.711437) (xy 65.222645 -254.76187) (xy 65.267114 -254.817632)
			(xy 65.30506 -254.878023) (xy 65.336005 -254.942282) (xy 65.359562 -255.009602) (xy 65.375432 -255.079137)
			(xy 65.383418 -255.150011) (xy 65.383918 -255.185672) (xy 65.383418 -255.221333) (xy 65.375432 -255.292207)
			(xy 65.359562 -255.361742) (xy 65.336005 -255.429062) (xy 65.30506 -255.493321) (xy 65.267114 -255.553712)
			(xy 65.222645 -255.609474) (xy 65.172212 -255.659907) (xy 65.11645 -255.704376) (xy 65.056059 -255.742322)
			(xy 64.9918 -255.773267) (xy 64.92448 -255.796824) (xy 64.854945 -255.812694) (xy 64.784071 -255.82068)
			(xy 64.712749 -255.82068) (xy 64.641875 -255.812694) (xy 64.57234 -255.796824) (xy 64.50502 -255.773267)
			(xy 64.440761 -255.742322) (xy 64.38037 -255.704376) (xy 64.324608 -255.659907) (xy 64.274175 -255.609474)
			(xy 64.229706 -255.553712) (xy 64.19176 -255.493321) (xy 64.160815 -255.429062) (xy 64.137258 -255.361742)
			(xy 64.121388 -255.292207) (xy 64.113402 -255.221333) (xy 63.479434 -255.221333) (xy 63.471448 -255.292207)
			(xy 63.455578 -255.361742) (xy 63.432021 -255.429062) (xy 63.401076 -255.493321) (xy 63.36313 -255.553712)
			(xy 63.318661 -255.609474) (xy 63.268228 -255.659907) (xy 63.212466 -255.704376) (xy 63.152075 -255.742322)
			(xy 63.087816 -255.773267) (xy 63.020496 -255.796824) (xy 62.950961 -255.812694) (xy 62.880087 -255.82068)
			(xy 62.808765 -255.82068) (xy 62.737891 -255.812694) (xy 62.668356 -255.796824) (xy 62.601036 -255.773267)
			(xy 62.536777 -255.742322) (xy 62.476386 -255.704376) (xy 62.420624 -255.659907) (xy 62.370191 -255.609474)
			(xy 62.325722 -255.553712) (xy 62.287776 -255.493321) (xy 62.256831 -255.429062) (xy 62.233274 -255.361742)
			(xy 62.217404 -255.292207) (xy 62.209418 -255.221333) (xy 61.238392 -255.221333) (xy 61.230406 -255.292207)
			(xy 61.214536 -255.361742) (xy 61.190979 -255.429062) (xy 61.160034 -255.493321) (xy 61.122088 -255.553712)
			(xy 61.077619 -255.609474) (xy 61.027186 -255.659907) (xy 60.971424 -255.704376) (xy 60.911033 -255.742322)
			(xy 60.846774 -255.773267) (xy 60.779454 -255.796824) (xy 60.709919 -255.812694) (xy 60.639045 -255.82068)
			(xy 60.567723 -255.82068) (xy 60.496849 -255.812694) (xy 60.427314 -255.796824) (xy 60.359994 -255.773267)
			(xy 60.295735 -255.742322) (xy 60.235344 -255.704376) (xy 60.179582 -255.659907) (xy 60.129149 -255.609474)
			(xy 60.08468 -255.553712) (xy 60.046734 -255.493321) (xy 60.015789 -255.429062) (xy 59.992232 -255.361742)
			(xy 59.976362 -255.292207) (xy 59.968376 -255.221333) (xy 59.35168 -255.221333) (xy 59.343694 -255.292207)
			(xy 59.327824 -255.361742) (xy 59.304267 -255.429062) (xy 59.273322 -255.493321) (xy 59.235376 -255.553712)
			(xy 59.190907 -255.609474) (xy 59.140474 -255.659907) (xy 59.084712 -255.704376) (xy 59.024321 -255.742322)
			(xy 58.960062 -255.773267) (xy 58.892742 -255.796824) (xy 58.823207 -255.812694) (xy 58.752333 -255.82068)
			(xy 58.681011 -255.82068) (xy 58.610137 -255.812694) (xy 58.540602 -255.796824) (xy 58.473282 -255.773267)
			(xy 58.409023 -255.742322) (xy 58.348632 -255.704376) (xy 58.29287 -255.659907) (xy 58.242437 -255.609474)
			(xy 58.197968 -255.553712) (xy 58.160022 -255.493321) (xy 58.129077 -255.429062) (xy 58.10552 -255.361742)
			(xy 58.08965 -255.292207) (xy 58.081664 -255.221333) (xy 28.942538 -255.221333) (xy 28.942538 -256.249053)
			(xy 44.144671 -256.249053) (xy 44.144671 -256.185787) (xy 44.152929 -256.123063) (xy 44.169303 -256.061954)
			(xy 44.193514 -256.003504) (xy 44.225147 -255.948715) (xy 44.26366 -255.898523) (xy 44.308395 -255.853788)
			(xy 44.358587 -255.815275) (xy 44.413376 -255.783642) (xy 44.471826 -255.759431) (xy 44.532935 -255.743057)
			(xy 44.595659 -255.734799) (xy 44.658925 -255.734799) (xy 44.721649 -255.743057) (xy 44.782758 -255.759431)
			(xy 44.841208 -255.783642) (xy 44.895997 -255.815275) (xy 44.946189 -255.853788) (xy 44.968922 -255.87579)
			(xy 45.039788 -255.94691) (xy 45.051929 -255.958364) (xy 45.080799 -255.975089) (xy 45.113021 -255.983748)
			(xy 45.129704 -255.984248) (xy 45.96511 -255.984248) (xy 45.993398 -255.984627) (xy 46.049594 -255.991179)
			(xy 46.104636 -256.004264) (xy 46.157768 -256.023701) (xy 46.208261 -256.049222) (xy 46.232064 -256.064512)
			(xy 46.263814 -256.085848) (xy 46.320964 -256.085848) (xy 46.320964 -256.140712) (xy 46.340832 -256.163031)
			(xy 46.375479 -256.211716) (xy 46.403855 -256.264303) (xy 46.425525 -256.31999) (xy 46.440158 -256.377926)
			(xy 46.447531 -256.437224) (xy 46.447531 -256.496979) (xy 46.440158 -256.556277) (xy 46.425524 -256.614212)
			(xy 46.403854 -256.669899) (xy 46.375478 -256.722487) (xy 46.34083 -256.771171) (xy 46.320964 -256.793492)
			(xy 46.320964 -256.848356) (xy 46.263814 -256.848356) (xy 46.232064 -256.869692) (xy 46.208261 -256.884979)
			(xy 46.157757 -256.91047) (xy 46.104623 -256.929895) (xy 46.049586 -256.942986) (xy 45.993397 -256.949565)
			(xy 45.96511 -256.949956) (xy 44.676822 -256.949956) (xy 44.285662 -256.55905) (xy 44.26366 -256.536317)
			(xy 44.225147 -256.486125) (xy 44.193514 -256.431336) (xy 44.169303 -256.372886) (xy 44.152929 -256.311777)
			(xy 44.144671 -256.249053) (xy 28.942538 -256.249053) (xy 28.942538 -258.170817) (xy 44.087521 -258.170817)
			(xy 44.087521 -258.107551) (xy 44.095779 -258.044827) (xy 44.112153 -257.983718) (xy 44.136364 -257.925268)
			(xy 44.167997 -257.870479) (xy 44.20651 -257.820287) (xy 44.228512 -257.797554) (xy 44.619672 -257.406648)
			(xy 45.965872 -257.406648) (xy 45.994135 -257.407036) (xy 46.050277 -257.413607) (xy 46.105266 -257.426699)
			(xy 46.158346 -257.44613) (xy 46.208791 -257.471635) (xy 46.232572 -257.486912) (xy 46.264576 -257.507994)
			(xy 46.42739 -257.507994) (xy 46.461172 -257.482594) (xy 46.487646 -257.463396) (xy 46.544581 -257.431225)
			(xy 46.605172 -257.40662) (xy 46.668418 -257.389987) (xy 46.733274 -257.381602) (xy 46.79867 -257.381602)
			(xy 46.863526 -257.389987) (xy 46.926772 -257.40662) (xy 46.987363 -257.431225) (xy 47.044298 -257.463396)
			(xy 47.070772 -257.482594) (xy 47.104554 -257.507994) (xy 47.12208 -257.507994) (xy 47.12208 -257.52679)
			(xy 47.145757 -257.550746) (xy 47.187193 -257.60385) (xy 47.221253 -257.661961) (xy 47.247341 -257.72406)
			(xy 47.265 -257.789061) (xy 47.27392 -257.855824) (xy 47.27448 -257.889502) (xy 47.27448 -258.594352)
			(xy 47.274992 -258.61752) (xy 47.283401 -258.663088) (xy 47.29993 -258.706376) (xy 47.324032 -258.745952)
			(xy 47.354909 -258.780502) (xy 47.391537 -258.808884) (xy 47.432702 -258.830156) (xy 47.477042 -258.843614)
			(xy 47.523086 -258.848811) (xy 47.56931 -258.845576) (xy 47.614182 -258.834016) (xy 47.635414 -258.82473)
			(xy 47.664867 -258.811555) (xy 47.726349 -258.791978) (xy 47.789813 -258.780338) (xy 47.854241 -258.776822)
			(xy 47.918596 -258.781487) (xy 47.981843 -258.794258) (xy 48.042966 -258.814929) (xy 48.100981 -258.843168)
			(xy 48.154958 -258.878521) (xy 48.204027 -258.92042) (xy 48.2474 -258.968191) (xy 48.284379 -259.021066)
			(xy 48.314371 -259.078196) (xy 48.336893 -259.138661) (xy 48.351582 -259.20149) (xy 48.358204 -259.265673)
			(xy 48.356651 -259.330178) (xy 48.346948 -259.393968) (xy 48.329251 -259.456017) (xy 48.303845 -259.515328)
			(xy 48.271139 -259.570948) (xy 48.231657 -259.621982) (xy 48.2092 -259.64515) (xy 46.990508 -260.864096)
			(xy 46.311566 -260.864096) (xy 46.278864 -260.863588) (xy 46.214001 -260.855191) (xy 46.150752 -260.83854)
			(xy 46.090162 -260.81391) (xy 46.033233 -260.78171) (xy 46.006766 -260.762496) (xy 45.972984 -260.737096)
			(xy 45.81017 -260.737096) (xy 45.778166 -260.758178) (xy 45.75439 -260.773476) (xy 45.703953 -260.799028)
			(xy 45.650876 -260.81851) (xy 45.595886 -260.831655) (xy 45.539736 -260.838283) (xy 45.511466 -260.838696)
			(xy 44.738036 -260.838696) (xy 44.336208 -260.436868) (xy 44.314206 -260.414135) (xy 44.275693 -260.363943)
			(xy 44.24406 -260.309154) (xy 44.219849 -260.250704) (xy 44.203475 -260.189595) (xy 44.195217 -260.126871)
			(xy 44.195217 -260.063605) (xy 44.203475 -260.000881) (xy 44.219849 -259.939772) (xy 44.24406 -259.881322)
			(xy 44.275693 -259.826533) (xy 44.314206 -259.776341) (xy 44.358941 -259.731606) (xy 44.409133 -259.693093)
			(xy 44.463922 -259.66146) (xy 44.522372 -259.637249) (xy 44.583481 -259.620875) (xy 44.646205 -259.612617)
			(xy 44.709471 -259.612617) (xy 44.772195 -259.620875) (xy 44.833304 -259.637249) (xy 44.891754 -259.66146)
			(xy 44.946543 -259.693093) (xy 44.996735 -259.731606) (xy 45.019468 -259.753608) (xy 45.13834 -259.87248)
			(xy 45.511466 -259.87248) (xy 45.539733 -259.872928) (xy 45.595876 -259.879574) (xy 45.650861 -259.892722)
			(xy 45.703938 -259.912191) (xy 45.754382 -259.937716) (xy 45.778166 -259.952998) (xy 45.81017 -259.97408)
			(xy 45.972984 -259.97408) (xy 46.006766 -259.94868) (xy 46.03324 -259.929478) (xy 46.090177 -259.897301)
			(xy 46.150766 -259.872681) (xy 46.21401 -259.856025) (xy 46.278866 -259.847606) (xy 46.311566 -259.84708)
			(xy 46.569376 -259.84708) (xy 46.641004 -259.775706) (xy 46.656585 -259.759491) (xy 46.682298 -259.722602)
			(xy 46.701117 -259.681764) (xy 46.712454 -259.63825) (xy 46.715955 -259.593421) (xy 46.711511 -259.548675)
			(xy 46.69926 -259.50541) (xy 46.679585 -259.464976) (xy 46.653101 -259.428637) (xy 46.620634 -259.397527)
			(xy 46.583198 -259.372618) (xy 46.562772 -259.36321) (xy 46.532922 -259.349669) (xy 46.476693 -259.315981)
			(xy 46.425261 -259.275345) (xy 46.379479 -259.228435) (xy 46.340107 -259.176029) (xy 46.307797 -259.118997)
			(xy 46.283087 -259.058285) (xy 46.266385 -258.9949) (xy 46.25797 -258.929894) (xy 46.257464 -258.89712)
			(xy 46.257464 -258.625594) (xy 46.257004 -258.602684) (xy 46.248806 -258.557605) (xy 46.232659 -258.514725)
			(xy 46.209085 -258.475435) (xy 46.17885 -258.441009) (xy 46.142932 -258.41256) (xy 46.102496 -258.391012)
			(xy 46.058852 -258.377063) (xy 46.013415 -258.371165) (xy 45.99051 -258.371848) (xy 45.965872 -258.372356)
			(xy 45.072554 -258.372356) (xy 45.055874 -258.372887) (xy 45.023654 -258.381539) (xy 44.994774 -258.39824)
			(xy 44.982638 -258.409694) (xy 44.911772 -258.480814) (xy 44.889039 -258.502816) (xy 44.838847 -258.541329)
			(xy 44.784058 -258.572962) (xy 44.725608 -258.597173) (xy 44.664499 -258.613547) (xy 44.601775 -258.621805)
			(xy 44.538509 -258.621805) (xy 44.475785 -258.613547) (xy 44.414676 -258.597173) (xy 44.356226 -258.572962)
			(xy 44.301437 -258.541329) (xy 44.251245 -258.502816) (xy 44.20651 -258.458081) (xy 44.167997 -258.407889)
			(xy 44.136364 -258.3531) (xy 44.112153 -258.29465) (xy 44.095779 -258.233541) (xy 44.087521 -258.170817)
			(xy 28.942538 -258.170817) (xy 28.942538 -260.328156) (xy 30.714579 -262.100197) (xy 44.081171 -262.100197)
			(xy 44.081171 -262.036931) (xy 44.089429 -261.974207) (xy 44.105803 -261.913098) (xy 44.130014 -261.854648)
			(xy 44.161647 -261.799859) (xy 44.20016 -261.749667) (xy 44.222162 -261.726934) (xy 44.520866 -261.42823)
			(xy 44.544395 -261.405451) (xy 44.596551 -261.365843) (xy 44.653581 -261.333648) (xy 44.714439 -261.309455)
			(xy 44.778008 -261.293709) (xy 44.843122 -261.286699) (xy 44.908586 -261.288553) (xy 44.940982 -261.293356)
			(xy 44.951396 -261.29488) (xy 45.510958 -261.29488) (xy 45.539253 -261.295276) (xy 45.595454 -261.301897)
			(xy 45.650496 -261.315041) (xy 45.703625 -261.334527) (xy 45.754112 -261.36009) (xy 45.777912 -261.375398)
			(xy 45.809662 -261.39648) (xy 45.866812 -261.39648) (xy 45.866812 -261.451598) (xy 45.886668 -261.473928)
			(xy 45.921319 -261.52261) (xy 45.949698 -261.575195) (xy 45.971372 -261.630881) (xy 45.986008 -261.688816)
			(xy 45.993383 -261.748114) (xy 45.993384 -261.807869) (xy 45.986011 -261.867167) (xy 45.971377 -261.925102)
			(xy 45.949706 -261.980789) (xy 45.921329 -262.033375) (xy 45.886679 -262.082058) (xy 45.866812 -262.104378)
			(xy 45.866812 -262.159496) (xy 45.809662 -262.159496) (xy 45.777912 -262.180578) (xy 45.754116 -262.195892)
			(xy 45.703629 -262.221457) (xy 45.6505 -262.240942) (xy 45.595456 -262.254081) (xy 45.539253 -262.260694)
			(xy 45.510958 -262.261096) (xy 45.05452 -262.261096) (xy 45.008885 -262.306731) (xy 48.835554 -262.306731)
			(xy 48.835554 -262.225621) (xy 48.843504 -262.144902) (xy 48.859327 -262.065351) (xy 48.882872 -261.987735)
			(xy 48.913911 -261.912799) (xy 48.952146 -261.841267) (xy 48.997208 -261.773827) (xy 49.048663 -261.711128)
			(xy 49.106016 -261.653775) (xy 49.168715 -261.60232) (xy 49.236155 -261.557258) (xy 49.307687 -261.519023)
			(xy 49.382623 -261.487984) (xy 49.460239 -261.464439) (xy 49.53979 -261.448616) (xy 49.620509 -261.440666)
			(xy 49.701619 -261.440666) (xy 49.782338 -261.448616) (xy 49.861889 -261.464439) (xy 49.939505 -261.487984)
			(xy 50.014441 -261.519023) (xy 50.085973 -261.557258) (xy 50.153413 -261.60232) (xy 50.216112 -261.653775)
			(xy 50.273465 -261.711128) (xy 50.32492 -261.773827) (xy 50.369982 -261.841267) (xy 50.408217 -261.912799)
			(xy 50.439256 -261.987735) (xy 50.462801 -262.065351) (xy 50.478624 -262.144902) (xy 50.486574 -262.225621)
			(xy 50.487072 -262.266176) (xy 50.486574 -262.306731) (xy 50.478624 -262.38745) (xy 50.462801 -262.467001)
			(xy 50.439256 -262.544617) (xy 50.408217 -262.619553) (xy 50.369982 -262.691085) (xy 50.32492 -262.758525)
			(xy 50.273465 -262.821224) (xy 50.234661 -262.860028) (xy 70.896988 -262.860028) (xy 70.896988 -261.915148)
			(xy 70.897568 -261.882647) (xy 70.905872 -261.818177) (xy 70.922325 -261.755292) (xy 70.946658 -261.695016)
			(xy 70.978475 -261.638333) (xy 71.017257 -261.586167) (xy 71.062371 -261.53937) (xy 71.113082 -261.498704)
			(xy 71.168562 -261.464832) (xy 71.227906 -261.438308) (xy 71.290147 -261.419564) (xy 71.354269 -261.408905)
			(xy 71.419227 -261.406505) (xy 71.483961 -261.412404) (xy 71.547415 -261.426505) (xy 71.608555 -261.448578)
			(xy 71.666383 -261.478263) (xy 71.719956 -261.515077) (xy 71.7684 -261.558418) (xy 71.790052 -261.582662)
			(xy 71.804661 -261.598881) (xy 71.838417 -261.626549) (xy 71.876403 -261.648045) (xy 71.917502 -261.662736)
			(xy 71.960507 -261.670192) (xy 72.004153 -261.670192) (xy 72.047158 -261.662736) (xy 72.088257 -261.648045)
			(xy 72.126243 -261.626549) (xy 72.159999 -261.598881) (xy 72.174608 -261.582662) (xy 72.196685 -261.558028)
			(xy 72.246049 -261.513999) (xy 72.300709 -261.476747) (xy 72.359739 -261.446901) (xy 72.422143 -261.424966)
			(xy 72.486865 -261.411312) (xy 72.552812 -261.406171) (xy 72.618868 -261.409629) (xy 72.683918 -261.421627)
			(xy 72.74686 -261.441964) (xy 72.806633 -261.470295) (xy 72.862225 -261.506141) (xy 72.912696 -261.548896)
			(xy 72.935338 -261.57301) (xy 72.951549 -261.590038) (xy 72.989064 -261.618368) (xy 73.031146 -261.639322)
			(xy 73.076361 -261.652187) (xy 73.123171 -261.656525) (xy 73.169981 -261.652187) (xy 73.215196 -261.639322)
			(xy 73.257278 -261.618368) (xy 73.294793 -261.590038) (xy 73.311004 -261.57301) (xy 73.333494 -261.54896)
			(xy 73.383725 -261.506382) (xy 73.439031 -261.470643) (xy 73.498488 -261.442342) (xy 73.5611 -261.421953)
			(xy 73.62582 -261.409815) (xy 73.691566 -261.406133) (xy 73.757236 -261.410968) (xy 73.821734 -261.424239)
			(xy 73.883979 -261.445724) (xy 73.94293 -261.475063) (xy 73.9976 -261.511767) (xy 74.047076 -261.55522)
			(xy 74.069194 -261.579614) (xy 74.083776 -261.59555) (xy 74.117365 -261.622703) (xy 74.155062 -261.643784)
			(xy 74.195783 -261.658184) (xy 74.238352 -261.66549) (xy 74.281544 -261.66549) (xy 74.324113 -261.658184)
			(xy 74.364834 -261.643784) (xy 74.402531 -261.622703) (xy 74.43612 -261.59555) (xy 74.450702 -261.579614)
			(xy 74.472533 -261.55568) (xy 74.521135 -261.512852) (xy 74.574783 -261.476546) (xy 74.632609 -261.447349)
			(xy 74.693675 -261.425734) (xy 74.756993 -261.412052) (xy 74.821536 -261.406525) (xy 74.886258 -261.409241)
			(xy 74.95011 -261.420158) (xy 75.012059 -261.439097) (xy 75.071099 -261.465753) (xy 75.126275 -261.499693)
			(xy 75.176693 -261.540367) (xy 75.221534 -261.587116) (xy 75.260074 -261.639183) (xy 75.291687 -261.695725)
			(xy 75.315862 -261.755824) (xy 75.332206 -261.818507) (xy 75.340454 -261.882759) (xy 75.340972 -261.915148)
			(xy 75.340972 -262.860028) (xy 75.340498 -262.892755) (xy 75.332099 -262.957669) (xy 75.315443 -263.020969)
			(xy 75.290806 -263.08161) (xy 75.258594 -263.138589) (xy 75.239372 -263.165082) (xy 75.213972 -263.198864)
			(xy 75.213972 -263.216136) (xy 75.198732 -263.216136) (xy 75.162918 -263.246362) (xy 75.137741 -263.267215)
			(xy 75.083009 -263.302966) (xy 75.024144 -263.331405) (xy 74.962119 -263.35206) (xy 74.897957 -263.364591)
			(xy 74.832718 -263.368791) (xy 74.767479 -263.364591) (xy 74.703317 -263.35206) (xy 74.641292 -263.331405)
			(xy 74.582427 -263.302966) (xy 74.527695 -263.267215) (xy 74.502518 -263.246362) (xy 74.466704 -263.216136)
			(xy 74.451464 -263.216136) (xy 74.451464 -263.198864) (xy 74.426064 -263.165082) (xy 74.411371 -263.144954)
			(xy 74.385545 -263.102332) (xy 74.374502 -263.079992) (xy 74.367181 -263.065898) (xy 74.346779 -263.041571)
			(xy 74.321004 -263.023033) (xy 74.291451 -263.01143) (xy 74.259948 -263.007481) (xy 74.228445 -263.01143)
			(xy 74.198892 -263.023033) (xy 74.173117 -263.041571) (xy 74.152715 -263.065898) (xy 74.145394 -263.079992)
			(xy 74.134361 -263.102337) (xy 74.108535 -263.144961) (xy 74.093832 -263.165082) (xy 74.068432 -263.198864)
			(xy 74.068432 -263.216136) (xy 74.053192 -263.216136) (xy 74.017378 -263.246362) (xy 73.992201 -263.267215)
			(xy 73.937469 -263.302966) (xy 73.878604 -263.331405) (xy 73.816579 -263.35206) (xy 73.752417 -263.364591)
			(xy 73.687178 -263.368791) (xy 73.621939 -263.364591) (xy 73.557777 -263.35206) (xy 73.495752 -263.331405)
			(xy 73.436887 -263.302966) (xy 73.382155 -263.267215) (xy 73.356978 -263.246362) (xy 73.321164 -263.216136)
			(xy 73.305924 -263.216136) (xy 73.305924 -263.198864) (xy 73.280524 -263.165082) (xy 73.268088 -263.148191)
			(xy 73.245706 -263.112715) (xy 73.23582 -263.094216) (xy 73.228348 -263.080704) (xy 73.207993 -263.057498)
			(xy 73.182651 -263.039873) (xy 73.153812 -263.028866) (xy 73.123171 -263.025123) (xy 73.09253 -263.028866)
			(xy 73.063691 -263.039873) (xy 73.038349 -263.057498) (xy 73.017994 -263.080704) (xy 73.010522 -263.094216)
			(xy 73.00065 -263.112723) (xy 72.978268 -263.148201) (xy 72.965818 -263.165082) (xy 72.940672 -263.198864)
			(xy 72.940672 -263.216136) (xy 72.925178 -263.216136) (xy 72.889364 -263.246362) (xy 72.864187 -263.267215)
			(xy 72.809455 -263.302966) (xy 72.75059 -263.331405) (xy 72.688565 -263.35206) (xy 72.624403 -263.364591)
			(xy 72.559164 -263.368791) (xy 72.493925 -263.364591) (xy 72.429763 -263.35206) (xy 72.367738 -263.331405)
			(xy 72.308873 -263.302966) (xy 72.254141 -263.267215) (xy 72.228964 -263.246362) (xy 72.19315 -263.216136)
			(xy 72.177656 -263.216136) (xy 72.177656 -263.198864) (xy 72.15251 -263.165082) (xy 72.1367 -263.143409)
			(xy 72.109208 -263.097341) (xy 72.097646 -263.073134) (xy 72.090467 -263.058732) (xy 72.070087 -263.033839)
			(xy 72.04413 -263.014835) (xy 72.014244 -263.002927) (xy 71.98233 -262.998871) (xy 71.950416 -263.002927)
			(xy 71.92053 -263.014835) (xy 71.894573 -263.033839) (xy 71.874193 -263.058732) (xy 71.867014 -263.073134)
			(xy 71.855464 -263.097347) (xy 71.827971 -263.143417) (xy 71.81215 -263.165082) (xy 71.787004 -263.198864)
			(xy 71.787004 -263.216136) (xy 71.77151 -263.216136) (xy 71.735696 -263.246362) (xy 71.710519 -263.267215)
			(xy 71.655787 -263.302966) (xy 71.596922 -263.331405) (xy 71.534897 -263.35206) (xy 71.470735 -263.364591)
			(xy 71.405496 -263.368791) (xy 71.340257 -263.364591) (xy 71.276095 -263.35206) (xy 71.21407 -263.331405)
			(xy 71.155205 -263.302966) (xy 71.100473 -263.267215) (xy 71.075296 -263.246362) (xy 71.039482 -263.216136)
			(xy 71.023988 -263.216136) (xy 71.023988 -263.198864) (xy 70.998842 -263.165082) (xy 70.979582 -263.138607)
			(xy 70.947321 -263.081636) (xy 70.922638 -263.020996) (xy 70.905943 -262.957689) (xy 70.897511 -262.892763)
			(xy 70.896988 -262.860028) (xy 50.234661 -262.860028) (xy 50.216112 -262.878577) (xy 50.153413 -262.930032)
			(xy 50.085973 -262.975094) (xy 50.014441 -263.013329) (xy 49.939505 -263.044368) (xy 49.861889 -263.067913)
			(xy 49.782338 -263.083736) (xy 49.701619 -263.091686) (xy 49.620509 -263.091686) (xy 49.53979 -263.083736)
			(xy 49.460239 -263.067913) (xy 49.382623 -263.044368) (xy 49.307687 -263.013329) (xy 49.236155 -262.975094)
			(xy 49.168715 -262.930032) (xy 49.106016 -262.878577) (xy 49.048663 -262.821224) (xy 48.997208 -262.758525)
			(xy 48.952146 -262.691085) (xy 48.913911 -262.619553) (xy 48.882872 -262.544617) (xy 48.859327 -262.467001)
			(xy 48.843504 -262.38745) (xy 48.835554 -262.306731) (xy 45.008885 -262.306731) (xy 44.905422 -262.410194)
			(xy 44.882689 -262.432196) (xy 44.832497 -262.470709) (xy 44.777708 -262.502342) (xy 44.719258 -262.526553)
			(xy 44.658149 -262.542927) (xy 44.595425 -262.551185) (xy 44.532159 -262.551185) (xy 44.469435 -262.542927)
			(xy 44.408326 -262.526553) (xy 44.349876 -262.502342) (xy 44.295087 -262.470709) (xy 44.244895 -262.432196)
			(xy 44.20016 -262.387461) (xy 44.161647 -262.337269) (xy 44.130014 -262.28248) (xy 44.105803 -262.22403)
			(xy 44.089429 -262.162921) (xy 44.081171 -262.100197) (xy 30.714579 -262.100197) (xy 35.035998 -266.421616)
			(xy 84.87994 -266.421616) (xy 84.884011 -266.365994) (xy 84.896137 -266.311557) (xy 84.91606 -266.259466)
			(xy 84.943356 -266.210831) (xy 84.977442 -266.166688) (xy 85.017591 -266.127979) (xy 85.062949 -266.095528)
			(xy 85.112549 -266.070027) (xy 85.165333 -266.05202) (xy 85.220176 -266.04189) (xy 85.27591 -266.039853)
			(xy 85.331347 -266.045953) (xy 85.385304 -266.060059) (xy 85.436633 -266.081871) (xy 85.484239 -266.110925)
			(xy 85.527107 -266.1466) (xy 85.532282 -266.152376) (xy 87.394794 -266.152376) (xy 87.398865 -266.096754)
			(xy 87.410991 -266.042317) (xy 87.430914 -265.990226) (xy 87.45821 -265.941591) (xy 87.492296 -265.897448)
			(xy 87.532445 -265.858739) (xy 87.577803 -265.826288) (xy 87.627403 -265.800787) (xy 87.680187 -265.78278)
			(xy 87.73503 -265.77265) (xy 87.790764 -265.770613) (xy 87.846201 -265.776713) (xy 87.900158 -265.790819)
			(xy 87.951487 -265.812631) (xy 87.999093 -265.841685) (xy 88.041961 -265.87736) (xy 88.079178 -265.918897)
			(xy 88.109951 -265.96541) (xy 88.133623 -266.015907) (xy 88.149691 -266.069314) (xy 88.157811 -266.12449)
			(xy 88.15832 -266.152376) (xy 88.157811 -266.180262) (xy 88.149691 -266.235438) (xy 88.133623 -266.288845)
			(xy 88.109951 -266.339342) (xy 88.079178 -266.385855) (xy 88.041961 -266.427392) (xy 87.999093 -266.463067)
			(xy 87.951487 -266.492121) (xy 87.900158 -266.513933) (xy 87.846201 -266.528039) (xy 87.790764 -266.534139)
			(xy 87.73503 -266.532102) (xy 87.680187 -266.521972) (xy 87.627403 -266.503965) (xy 87.577803 -266.478464)
			(xy 87.532445 -266.446013) (xy 87.492296 -266.407304) (xy 87.45821 -266.363161) (xy 87.430914 -266.314526)
			(xy 87.410991 -266.262435) (xy 87.398865 -266.207998) (xy 87.394794 -266.152376) (xy 85.532282 -266.152376)
			(xy 85.564324 -266.188137) (xy 85.595097 -266.23465) (xy 85.618769 -266.285147) (xy 85.634837 -266.338554)
			(xy 85.642957 -266.39373) (xy 85.643466 -266.421616) (xy 85.642957 -266.449502) (xy 85.634837 -266.504678)
			(xy 85.618769 -266.558085) (xy 85.595097 -266.608582) (xy 85.564324 -266.655095) (xy 85.527107 -266.696632)
			(xy 85.484239 -266.732307) (xy 85.436633 -266.761361) (xy 85.385304 -266.783173) (xy 85.331347 -266.797279)
			(xy 85.27591 -266.803379) (xy 85.220176 -266.801342) (xy 85.165333 -266.791212) (xy 85.112549 -266.773205)
			(xy 85.062949 -266.747704) (xy 85.017591 -266.715253) (xy 84.977442 -266.676544) (xy 84.943356 -266.632401)
			(xy 84.91606 -266.583766) (xy 84.896137 -266.531675) (xy 84.884011 -266.477238) (xy 84.87994 -266.421616)
			(xy 35.035998 -266.421616) (xy 36.14293 -267.528548) (xy 78.276194 -267.528548) (xy 78.280265 -267.472926)
			(xy 78.292391 -267.418489) (xy 78.312314 -267.366398) (xy 78.33961 -267.317763) (xy 78.373696 -267.27362)
			(xy 78.413845 -267.234911) (xy 78.459203 -267.20246) (xy 78.508803 -267.176959) (xy 78.561587 -267.158952)
			(xy 78.61643 -267.148822) (xy 78.672164 -267.146785) (xy 78.727601 -267.152885) (xy 78.781558 -267.166991)
			(xy 78.832887 -267.188803) (xy 78.880493 -267.217857) (xy 78.923361 -267.253532) (xy 78.960578 -267.295069)
			(xy 78.991351 -267.341582) (xy 79.015023 -267.392079) (xy 79.031091 -267.445486) (xy 79.03539 -267.4747)
			(xy 80.28635 -267.4747) (xy 80.290421 -267.419078) (xy 80.302547 -267.364641) (xy 80.32247 -267.31255)
			(xy 80.349766 -267.263915) (xy 80.383852 -267.219772) (xy 80.424001 -267.181063) (xy 80.469359 -267.148612)
			(xy 80.518959 -267.123111) (xy 80.571743 -267.105104) (xy 80.626586 -267.094974) (xy 80.68232 -267.092937)
			(xy 80.737757 -267.099037) (xy 80.791714 -267.113143) (xy 80.843043 -267.134955) (xy 80.873666 -267.153644)
			(xy 81.976466 -267.153644) (xy 81.980537 -267.098022) (xy 81.992663 -267.043585) (xy 82.012586 -266.991494)
			(xy 82.039882 -266.942859) (xy 82.073968 -266.898716) (xy 82.114117 -266.860007) (xy 82.159475 -266.827556)
			(xy 82.209075 -266.802055) (xy 82.261859 -266.784048) (xy 82.316702 -266.773918) (xy 82.372436 -266.771881)
			(xy 82.427873 -266.777981) (xy 82.48183 -266.792087) (xy 82.533159 -266.813899) (xy 82.580765 -266.842953)
			(xy 82.623633 -266.878628) (xy 82.66085 -266.920165) (xy 82.691623 -266.966678) (xy 82.715295 -267.017175)
			(xy 82.731363 -267.070582) (xy 82.739483 -267.125758) (xy 82.739992 -267.153644) (xy 82.739483 -267.18153)
			(xy 82.731363 -267.236706) (xy 82.715295 -267.290113) (xy 82.691623 -267.34061) (xy 82.66085 -267.387123)
			(xy 82.623633 -267.42866) (xy 82.580765 -267.464335) (xy 82.533159 -267.493389) (xy 82.48183 -267.515201)
			(xy 82.427873 -267.529307) (xy 82.372436 -267.535407) (xy 82.316702 -267.53337) (xy 82.261859 -267.52324)
			(xy 82.209075 -267.505233) (xy 82.159475 -267.479732) (xy 82.114117 -267.447281) (xy 82.073968 -267.408572)
			(xy 82.039882 -267.364429) (xy 82.012586 -267.315794) (xy 81.992663 -267.263703) (xy 81.980537 -267.209266)
			(xy 81.976466 -267.153644) (xy 80.873666 -267.153644) (xy 80.890649 -267.164009) (xy 80.933517 -267.199684)
			(xy 80.970734 -267.241221) (xy 81.001507 -267.287734) (xy 81.025179 -267.338231) (xy 81.041247 -267.391638)
			(xy 81.049367 -267.446814) (xy 81.049876 -267.4747) (xy 81.049367 -267.502586) (xy 81.041247 -267.557762)
			(xy 81.025179 -267.611169) (xy 81.001507 -267.661666) (xy 80.970734 -267.708179) (xy 80.933517 -267.749716)
			(xy 80.890649 -267.785391) (xy 80.843043 -267.814445) (xy 80.791714 -267.836257) (xy 80.737757 -267.850363)
			(xy 80.68232 -267.856463) (xy 80.626586 -267.854426) (xy 80.571743 -267.844296) (xy 80.518959 -267.826289)
			(xy 80.469359 -267.800788) (xy 80.424001 -267.768337) (xy 80.383852 -267.729628) (xy 80.349766 -267.685485)
			(xy 80.32247 -267.63685) (xy 80.302547 -267.584759) (xy 80.290421 -267.530322) (xy 80.28635 -267.4747)
			(xy 79.03539 -267.4747) (xy 79.039211 -267.500662) (xy 79.03972 -267.528548) (xy 79.039211 -267.556434)
			(xy 79.031091 -267.61161) (xy 79.015023 -267.665017) (xy 78.991351 -267.715514) (xy 78.960578 -267.762027)
			(xy 78.923361 -267.803564) (xy 78.880493 -267.839239) (xy 78.832887 -267.868293) (xy 78.781558 -267.890105)
			(xy 78.727601 -267.904211) (xy 78.672164 -267.910311) (xy 78.61643 -267.908274) (xy 78.561587 -267.898144)
			(xy 78.508803 -267.880137) (xy 78.459203 -267.854636) (xy 78.413845 -267.822185) (xy 78.373696 -267.783476)
			(xy 78.33961 -267.739333) (xy 78.312314 -267.690698) (xy 78.292391 -267.638607) (xy 78.280265 -267.58417)
			(xy 78.276194 -267.528548) (xy 36.14293 -267.528548) (xy 36.596828 -267.982446) (xy 36.596828 -273.61007)
			(xy 39.818063 -273.61007) (xy 39.82207 -273.494046) (xy 39.834072 -273.378574) (xy 39.854012 -273.264206)
			(xy 39.881795 -273.151486) (xy 39.917289 -273.040952) (xy 39.960324 -272.933129) (xy 40.010695 -272.828532)
			(xy 40.068162 -272.72766) (xy 40.132452 -272.630993) (xy 40.203257 -272.538992) (xy 40.280241 -272.452095)
			(xy 40.363037 -272.370716) (xy 40.45125 -272.295243) (xy 40.54446 -272.226036) (xy 40.642223 -272.163424)
			(xy 40.744072 -272.107707) (xy 40.849522 -272.059149) (xy 40.958071 -272.017981) (xy 41.069202 -271.984401)
			(xy 41.182385 -271.958568) (xy 41.29708 -271.940605) (xy 41.412742 -271.930597) (xy 41.528818 -271.928594)
			(xy 41.644756 -271.934603) (xy 41.760003 -271.948596) (xy 41.874009 -271.970507) (xy 41.986233 -272.000232)
			(xy 42.096139 -272.037628) (xy 42.203202 -272.082517) (xy 42.306914 -272.134686) (xy 42.406779 -272.193886)
			(xy 42.502322 -272.259835) (xy 42.502604 -272.26006) (xy 43.327577 -272.26006) (xy 43.331612 -272.184356)
			(xy 43.343671 -272.109511) (xy 43.363617 -272.03637) (xy 43.391224 -271.965765) (xy 43.42618 -271.898494)
			(xy 43.468088 -271.835319) (xy 43.516474 -271.776957) (xy 43.57079 -271.724069) (xy 43.630419 -271.677254)
			(xy 43.694687 -271.637042) (xy 43.762864 -271.60389) (xy 43.83418 -271.578172) (xy 43.907825 -271.56018)
			(xy 43.982965 -271.550118) (xy 44.058749 -271.548099) (xy 44.134319 -271.554148) (xy 44.208817 -271.568195)
			(xy 44.2814 -271.590081) (xy 44.351246 -271.619558) (xy 44.417563 -271.656293) (xy 44.479599 -271.699868)
			(xy 44.536652 -271.74979) (xy 44.588076 -271.805494) (xy 44.633287 -271.866349) (xy 44.671774 -271.931664)
			(xy 44.7031 -272.0007) (xy 44.72691 -272.072675) (xy 44.742935 -272.146773) (xy 44.750994 -272.222154)
			(xy 44.751498 -272.26006) (xy 45.867577 -272.26006) (xy 45.871612 -272.184356) (xy 45.883671 -272.109511)
			(xy 45.903617 -272.03637) (xy 45.931224 -271.965765) (xy 45.96618 -271.898494) (xy 46.008088 -271.835319)
			(xy 46.056474 -271.776957) (xy 46.11079 -271.724069) (xy 46.170419 -271.677254) (xy 46.234687 -271.637042)
			(xy 46.302864 -271.60389) (xy 46.37418 -271.578172) (xy 46.447825 -271.56018) (xy 46.522965 -271.550118)
			(xy 46.598749 -271.548099) (xy 46.674319 -271.554148) (xy 46.748817 -271.568195) (xy 46.8214 -271.590081)
			(xy 46.891246 -271.619558) (xy 46.957563 -271.656293) (xy 47.019599 -271.699868) (xy 47.076652 -271.74979)
			(xy 47.128076 -271.805494) (xy 47.173287 -271.866349) (xy 47.211774 -271.931664) (xy 47.2431 -272.0007)
			(xy 47.26691 -272.072675) (xy 47.282935 -272.146773) (xy 47.290994 -272.222154) (xy 47.291498 -272.26006)
			(xy 48.407577 -272.26006) (xy 48.411612 -272.184356) (xy 48.423671 -272.109511) (xy 48.443617 -272.03637)
			(xy 48.471224 -271.965765) (xy 48.50618 -271.898494) (xy 48.548088 -271.835319) (xy 48.596474 -271.776957)
			(xy 48.65079 -271.724069) (xy 48.710419 -271.677254) (xy 48.774687 -271.637042) (xy 48.842864 -271.60389)
			(xy 48.91418 -271.578172) (xy 48.987825 -271.56018) (xy 49.062965 -271.550118) (xy 49.138749 -271.548099)
			(xy 49.214319 -271.554148) (xy 49.288817 -271.568195) (xy 49.3614 -271.590081) (xy 49.431246 -271.619558)
			(xy 49.497563 -271.656293) (xy 49.559599 -271.699868) (xy 49.616652 -271.74979) (xy 49.668076 -271.805494)
			(xy 49.713287 -271.866349) (xy 49.751774 -271.931664) (xy 49.7831 -272.0007) (xy 49.80691 -272.072675)
			(xy 49.822935 -272.146773) (xy 49.830994 -272.222154) (xy 49.831498 -272.26006) (xy 50.947577 -272.26006)
			(xy 50.951612 -272.184356) (xy 50.963671 -272.109511) (xy 50.983617 -272.03637) (xy 51.011224 -271.965765)
			(xy 51.04618 -271.898494) (xy 51.088088 -271.835319) (xy 51.136474 -271.776957) (xy 51.19079 -271.724069)
			(xy 51.250419 -271.677254) (xy 51.314687 -271.637042) (xy 51.382864 -271.60389) (xy 51.45418 -271.578172)
			(xy 51.527825 -271.56018) (xy 51.602965 -271.550118) (xy 51.678749 -271.548099) (xy 51.754319 -271.554148)
			(xy 51.828817 -271.568195) (xy 51.9014 -271.590081) (xy 51.971246 -271.619558) (xy 52.037563 -271.656293)
			(xy 52.099599 -271.699868) (xy 52.156652 -271.74979) (xy 52.208076 -271.805494) (xy 52.253287 -271.866349)
			(xy 52.291774 -271.931664) (xy 52.3231 -272.0007) (xy 52.34691 -272.072675) (xy 52.362935 -272.146773)
			(xy 52.370994 -272.222154) (xy 52.371498 -272.26006) (xy 53.487577 -272.26006) (xy 53.491612 -272.184356)
			(xy 53.503671 -272.109511) (xy 53.523617 -272.03637) (xy 53.551224 -271.965765) (xy 53.58618 -271.898494)
			(xy 53.628088 -271.835319) (xy 53.676474 -271.776957) (xy 53.73079 -271.724069) (xy 53.790419 -271.677254)
			(xy 53.854687 -271.637042) (xy 53.922864 -271.60389) (xy 53.99418 -271.578172) (xy 54.067825 -271.56018)
			(xy 54.142965 -271.550118) (xy 54.218749 -271.548099) (xy 54.294319 -271.554148) (xy 54.368817 -271.568195)
			(xy 54.4414 -271.590081) (xy 54.511246 -271.619558) (xy 54.577563 -271.656293) (xy 54.639599 -271.699868)
			(xy 54.696652 -271.74979) (xy 54.748076 -271.805494) (xy 54.793287 -271.866349) (xy 54.831774 -271.931664)
			(xy 54.8631 -272.0007) (xy 54.88691 -272.072675) (xy 54.902935 -272.146773) (xy 54.910994 -272.222154)
			(xy 54.911498 -272.26006) (xy 56.027577 -272.26006) (xy 56.031612 -272.184356) (xy 56.043671 -272.109511)
			(xy 56.063617 -272.03637) (xy 56.091224 -271.965765) (xy 56.12618 -271.898494) (xy 56.168088 -271.835319)
			(xy 56.216474 -271.776957) (xy 56.27079 -271.724069) (xy 56.330419 -271.677254) (xy 56.394687 -271.637042)
			(xy 56.462864 -271.60389) (xy 56.53418 -271.578172) (xy 56.607825 -271.56018) (xy 56.682965 -271.550118)
			(xy 56.758749 -271.548099) (xy 56.834319 -271.554148) (xy 56.908817 -271.568195) (xy 56.9814 -271.590081)
			(xy 57.051246 -271.619558) (xy 57.117563 -271.656293) (xy 57.179599 -271.699868) (xy 57.236652 -271.74979)
			(xy 57.288076 -271.805494) (xy 57.333287 -271.866349) (xy 57.371774 -271.931664) (xy 57.4031 -272.0007)
			(xy 57.42691 -272.072675) (xy 57.442935 -272.146773) (xy 57.450994 -272.222154) (xy 57.451498 -272.26006)
			(xy 58.567577 -272.26006) (xy 58.571612 -272.184356) (xy 58.583671 -272.109511) (xy 58.603617 -272.03637)
			(xy 58.631224 -271.965765) (xy 58.66618 -271.898494) (xy 58.708088 -271.835319) (xy 58.756474 -271.776957)
			(xy 58.81079 -271.724069) (xy 58.870419 -271.677254) (xy 58.934687 -271.637042) (xy 59.002864 -271.60389)
			(xy 59.07418 -271.578172) (xy 59.147825 -271.56018) (xy 59.222965 -271.550118) (xy 59.298749 -271.548099)
			(xy 59.374319 -271.554148) (xy 59.448817 -271.568195) (xy 59.5214 -271.590081) (xy 59.591246 -271.619558)
			(xy 59.657563 -271.656293) (xy 59.719599 -271.699868) (xy 59.776652 -271.74979) (xy 59.828076 -271.805494)
			(xy 59.873287 -271.866349) (xy 59.911774 -271.931664) (xy 59.9431 -272.0007) (xy 59.96691 -272.072675)
			(xy 59.982935 -272.146773) (xy 59.990994 -272.222154) (xy 59.991498 -272.26006) (xy 61.107577 -272.26006)
			(xy 61.111612 -272.184356) (xy 61.123671 -272.109511) (xy 61.143617 -272.03637) (xy 61.171224 -271.965765)
			(xy 61.20618 -271.898494) (xy 61.248088 -271.835319) (xy 61.296474 -271.776957) (xy 61.35079 -271.724069)
			(xy 61.410419 -271.677254) (xy 61.474687 -271.637042) (xy 61.542864 -271.60389) (xy 61.61418 -271.578172)
			(xy 61.687825 -271.56018) (xy 61.762965 -271.550118) (xy 61.838749 -271.548099) (xy 61.914319 -271.554148)
			(xy 61.988817 -271.568195) (xy 62.0614 -271.590081) (xy 62.131246 -271.619558) (xy 62.197563 -271.656293)
			(xy 62.259599 -271.699868) (xy 62.265544 -271.70507) (xy 86.197697 -271.70507) (xy 86.201732 -271.629366)
			(xy 86.213791 -271.554521) (xy 86.233737 -271.48138) (xy 86.261344 -271.410775) (xy 86.2963 -271.343504)
			(xy 86.338208 -271.280329) (xy 86.386594 -271.221967) (xy 86.44091 -271.169079) (xy 86.500539 -271.122264)
			(xy 86.564807 -271.082052) (xy 86.632984 -271.0489) (xy 86.7043 -271.023182) (xy 86.777945 -271.00519)
			(xy 86.853085 -270.995128) (xy 86.928869 -270.993109) (xy 87.004439 -270.999158) (xy 87.078937 -271.013205)
			(xy 87.15152 -271.035091) (xy 87.221366 -271.064568) (xy 87.287683 -271.101303) (xy 87.349719 -271.144878)
			(xy 87.406772 -271.1948) (xy 87.458196 -271.250504) (xy 87.503407 -271.311359) (xy 87.541894 -271.376674)
			(xy 87.57322 -271.44571) (xy 87.59703 -271.517685) (xy 87.613055 -271.591783) (xy 87.621114 -271.667164)
			(xy 87.621618 -271.70507) (xy 88.737697 -271.70507) (xy 88.741732 -271.629366) (xy 88.753791 -271.554521)
			(xy 88.773737 -271.48138) (xy 88.801344 -271.410775) (xy 88.8363 -271.343504) (xy 88.878208 -271.280329)
			(xy 88.926594 -271.221967) (xy 88.98091 -271.169079) (xy 89.040539 -271.122264) (xy 89.104807 -271.082052)
			(xy 89.172984 -271.0489) (xy 89.2443 -271.023182) (xy 89.317945 -271.00519) (xy 89.393085 -270.995128)
			(xy 89.468869 -270.993109) (xy 89.544439 -270.999158) (xy 89.618937 -271.013205) (xy 89.69152 -271.035091)
			(xy 89.761366 -271.064568) (xy 89.827683 -271.101303) (xy 89.889719 -271.144878) (xy 89.946772 -271.1948)
			(xy 89.998196 -271.250504) (xy 90.043407 -271.311359) (xy 90.081894 -271.376674) (xy 90.11322 -271.44571)
			(xy 90.13703 -271.517685) (xy 90.153055 -271.591783) (xy 90.161114 -271.667164) (xy 90.161618 -271.70507)
			(xy 91.277697 -271.70507) (xy 91.281732 -271.629366) (xy 91.293791 -271.554521) (xy 91.313737 -271.48138)
			(xy 91.341344 -271.410775) (xy 91.3763 -271.343504) (xy 91.418208 -271.280329) (xy 91.466594 -271.221967)
			(xy 91.52091 -271.169079) (xy 91.580539 -271.122264) (xy 91.644807 -271.082052) (xy 91.712984 -271.0489)
			(xy 91.7843 -271.023182) (xy 91.857945 -271.00519) (xy 91.933085 -270.995128) (xy 92.008869 -270.993109)
			(xy 92.084439 -270.999158) (xy 92.158937 -271.013205) (xy 92.23152 -271.035091) (xy 92.301366 -271.064568)
			(xy 92.367683 -271.101303) (xy 92.429719 -271.144878) (xy 92.486772 -271.1948) (xy 92.538196 -271.250504)
			(xy 92.583407 -271.311359) (xy 92.621894 -271.376674) (xy 92.65322 -271.44571) (xy 92.67703 -271.517685)
			(xy 92.693055 -271.591783) (xy 92.701114 -271.667164) (xy 92.701618 -271.70507) (xy 92.701114 -271.742976)
			(xy 92.693055 -271.818357) (xy 92.67703 -271.892455) (xy 92.65322 -271.96443) (xy 92.621894 -272.033466)
			(xy 92.583407 -272.098781) (xy 92.538196 -272.159636) (xy 92.486772 -272.21534) (xy 92.429719 -272.265262)
			(xy 92.367683 -272.308837) (xy 92.301366 -272.345572) (xy 92.23152 -272.375049) (xy 92.158937 -272.396935)
			(xy 92.084439 -272.410982) (xy 92.008869 -272.417031) (xy 91.933085 -272.415012) (xy 91.857945 -272.40495)
			(xy 91.7843 -272.386958) (xy 91.712984 -272.36124) (xy 91.644807 -272.328088) (xy 91.580539 -272.287876)
			(xy 91.52091 -272.241061) (xy 91.466594 -272.188173) (xy 91.418208 -272.129811) (xy 91.3763 -272.066636)
			(xy 91.341344 -271.999365) (xy 91.313737 -271.92876) (xy 91.293791 -271.855619) (xy 91.281732 -271.780774)
			(xy 91.277697 -271.70507) (xy 90.161618 -271.70507) (xy 90.161114 -271.742976) (xy 90.153055 -271.818357)
			(xy 90.13703 -271.892455) (xy 90.11322 -271.96443) (xy 90.081894 -272.033466) (xy 90.043407 -272.098781)
			(xy 89.998196 -272.159636) (xy 89.946772 -272.21534) (xy 89.889719 -272.265262) (xy 89.827683 -272.308837)
			(xy 89.761366 -272.345572) (xy 89.69152 -272.375049) (xy 89.618937 -272.396935) (xy 89.544439 -272.410982)
			(xy 89.468869 -272.417031) (xy 89.393085 -272.415012) (xy 89.317945 -272.40495) (xy 89.2443 -272.386958)
			(xy 89.172984 -272.36124) (xy 89.104807 -272.328088) (xy 89.040539 -272.287876) (xy 88.98091 -272.241061)
			(xy 88.926594 -272.188173) (xy 88.878208 -272.129811) (xy 88.8363 -272.066636) (xy 88.801344 -271.999365)
			(xy 88.773737 -271.92876) (xy 88.753791 -271.855619) (xy 88.741732 -271.780774) (xy 88.737697 -271.70507)
			(xy 87.621618 -271.70507) (xy 87.621114 -271.742976) (xy 87.613055 -271.818357) (xy 87.59703 -271.892455)
			(xy 87.57322 -271.96443) (xy 87.541894 -272.033466) (xy 87.503407 -272.098781) (xy 87.458196 -272.159636)
			(xy 87.406772 -272.21534) (xy 87.349719 -272.265262) (xy 87.287683 -272.308837) (xy 87.221366 -272.345572)
			(xy 87.15152 -272.375049) (xy 87.078937 -272.396935) (xy 87.004439 -272.410982) (xy 86.928869 -272.417031)
			(xy 86.853085 -272.415012) (xy 86.777945 -272.40495) (xy 86.7043 -272.386958) (xy 86.632984 -272.36124)
			(xy 86.564807 -272.328088) (xy 86.500539 -272.287876) (xy 86.44091 -272.241061) (xy 86.386594 -272.188173)
			(xy 86.338208 -272.129811) (xy 86.2963 -272.066636) (xy 86.261344 -271.999365) (xy 86.233737 -271.92876)
			(xy 86.213791 -271.855619) (xy 86.201732 -271.780774) (xy 86.197697 -271.70507) (xy 62.265544 -271.70507)
			(xy 62.316652 -271.74979) (xy 62.368076 -271.805494) (xy 62.413287 -271.866349) (xy 62.451774 -271.931664)
			(xy 62.4831 -272.0007) (xy 62.50691 -272.072675) (xy 62.522935 -272.146773) (xy 62.530994 -272.222154)
			(xy 62.531498 -272.26006) (xy 62.530994 -272.297966) (xy 62.522935 -272.373347) (xy 62.50691 -272.447445)
			(xy 62.4831 -272.51942) (xy 62.451774 -272.588456) (xy 62.413287 -272.653771) (xy 62.368076 -272.714626)
			(xy 62.316652 -272.77033) (xy 62.259599 -272.820252) (xy 62.197563 -272.863827) (xy 62.131246 -272.900562)
			(xy 62.0614 -272.930039) (xy 61.988817 -272.951925) (xy 61.914319 -272.965972) (xy 61.838749 -272.972021)
			(xy 61.762965 -272.970002) (xy 61.687825 -272.95994) (xy 61.61418 -272.941948) (xy 61.542864 -272.91623)
			(xy 61.474687 -272.883078) (xy 61.410419 -272.842866) (xy 61.35079 -272.796051) (xy 61.296474 -272.743163)
			(xy 61.248088 -272.684801) (xy 61.20618 -272.621626) (xy 61.171224 -272.554355) (xy 61.143617 -272.48375)
			(xy 61.123671 -272.410609) (xy 61.111612 -272.335764) (xy 61.107577 -272.26006) (xy 59.991498 -272.26006)
			(xy 59.990994 -272.297966) (xy 59.982935 -272.373347) (xy 59.96691 -272.447445) (xy 59.9431 -272.51942)
			(xy 59.911774 -272.588456) (xy 59.873287 -272.653771) (xy 59.828076 -272.714626) (xy 59.776652 -272.77033)
			(xy 59.719599 -272.820252) (xy 59.657563 -272.863827) (xy 59.591246 -272.900562) (xy 59.5214 -272.930039)
			(xy 59.448817 -272.951925) (xy 59.374319 -272.965972) (xy 59.298749 -272.972021) (xy 59.222965 -272.970002)
			(xy 59.147825 -272.95994) (xy 59.07418 -272.941948) (xy 59.002864 -272.91623) (xy 58.934687 -272.883078)
			(xy 58.870419 -272.842866) (xy 58.81079 -272.796051) (xy 58.756474 -272.743163) (xy 58.708088 -272.684801)
			(xy 58.66618 -272.621626) (xy 58.631224 -272.554355) (xy 58.603617 -272.48375) (xy 58.583671 -272.410609)
			(xy 58.571612 -272.335764) (xy 58.567577 -272.26006) (xy 57.451498 -272.26006) (xy 57.450994 -272.297966)
			(xy 57.442935 -272.373347) (xy 57.42691 -272.447445) (xy 57.4031 -272.51942) (xy 57.371774 -272.588456)
			(xy 57.333287 -272.653771) (xy 57.288076 -272.714626) (xy 57.236652 -272.77033) (xy 57.179599 -272.820252)
			(xy 57.117563 -272.863827) (xy 57.051246 -272.900562) (xy 56.9814 -272.930039) (xy 56.908817 -272.951925)
			(xy 56.834319 -272.965972) (xy 56.758749 -272.972021) (xy 56.682965 -272.970002) (xy 56.607825 -272.95994)
			(xy 56.53418 -272.941948) (xy 56.462864 -272.91623) (xy 56.394687 -272.883078) (xy 56.330419 -272.842866)
			(xy 56.27079 -272.796051) (xy 56.216474 -272.743163) (xy 56.168088 -272.684801) (xy 56.12618 -272.621626)
			(xy 56.091224 -272.554355) (xy 56.063617 -272.48375) (xy 56.043671 -272.410609) (xy 56.031612 -272.335764)
			(xy 56.027577 -272.26006) (xy 54.911498 -272.26006) (xy 54.910994 -272.297966) (xy 54.902935 -272.373347)
			(xy 54.88691 -272.447445) (xy 54.8631 -272.51942) (xy 54.831774 -272.588456) (xy 54.793287 -272.653771)
			(xy 54.748076 -272.714626) (xy 54.696652 -272.77033) (xy 54.639599 -272.820252) (xy 54.577563 -272.863827)
			(xy 54.511246 -272.900562) (xy 54.4414 -272.930039) (xy 54.368817 -272.951925) (xy 54.294319 -272.965972)
			(xy 54.218749 -272.972021) (xy 54.142965 -272.970002) (xy 54.067825 -272.95994) (xy 53.99418 -272.941948)
			(xy 53.922864 -272.91623) (xy 53.854687 -272.883078) (xy 53.790419 -272.842866) (xy 53.73079 -272.796051)
			(xy 53.676474 -272.743163) (xy 53.628088 -272.684801) (xy 53.58618 -272.621626) (xy 53.551224 -272.554355)
			(xy 53.523617 -272.48375) (xy 53.503671 -272.410609) (xy 53.491612 -272.335764) (xy 53.487577 -272.26006)
			(xy 52.371498 -272.26006) (xy 52.370994 -272.297966) (xy 52.362935 -272.373347) (xy 52.34691 -272.447445)
			(xy 52.3231 -272.51942) (xy 52.291774 -272.588456) (xy 52.253287 -272.653771) (xy 52.208076 -272.714626)
			(xy 52.156652 -272.77033) (xy 52.099599 -272.820252) (xy 52.037563 -272.863827) (xy 51.971246 -272.900562)
			(xy 51.9014 -272.930039) (xy 51.828817 -272.951925) (xy 51.754319 -272.965972) (xy 51.678749 -272.972021)
			(xy 51.602965 -272.970002) (xy 51.527825 -272.95994) (xy 51.45418 -272.941948) (xy 51.382864 -272.91623)
			(xy 51.314687 -272.883078) (xy 51.250419 -272.842866) (xy 51.19079 -272.796051) (xy 51.136474 -272.743163)
			(xy 51.088088 -272.684801) (xy 51.04618 -272.621626) (xy 51.011224 -272.554355) (xy 50.983617 -272.48375)
			(xy 50.963671 -272.410609) (xy 50.951612 -272.335764) (xy 50.947577 -272.26006) (xy 49.831498 -272.26006)
			(xy 49.830994 -272.297966) (xy 49.822935 -272.373347) (xy 49.80691 -272.447445) (xy 49.7831 -272.51942)
			(xy 49.751774 -272.588456) (xy 49.713287 -272.653771) (xy 49.668076 -272.714626) (xy 49.616652 -272.77033)
			(xy 49.559599 -272.820252) (xy 49.497563 -272.863827) (xy 49.431246 -272.900562) (xy 49.3614 -272.930039)
			(xy 49.288817 -272.951925) (xy 49.214319 -272.965972) (xy 49.138749 -272.972021) (xy 49.062965 -272.970002)
			(xy 48.987825 -272.95994) (xy 48.91418 -272.941948) (xy 48.842864 -272.91623) (xy 48.774687 -272.883078)
			(xy 48.710419 -272.842866) (xy 48.65079 -272.796051) (xy 48.596474 -272.743163) (xy 48.548088 -272.684801)
			(xy 48.50618 -272.621626) (xy 48.471224 -272.554355) (xy 48.443617 -272.48375) (xy 48.423671 -272.410609)
			(xy 48.411612 -272.335764) (xy 48.407577 -272.26006) (xy 47.291498 -272.26006) (xy 47.290994 -272.297966)
			(xy 47.282935 -272.373347) (xy 47.26691 -272.447445) (xy 47.2431 -272.51942) (xy 47.211774 -272.588456)
			(xy 47.173287 -272.653771) (xy 47.128076 -272.714626) (xy 47.076652 -272.77033) (xy 47.019599 -272.820252)
			(xy 46.957563 -272.863827) (xy 46.891246 -272.900562) (xy 46.8214 -272.930039) (xy 46.748817 -272.951925)
			(xy 46.674319 -272.965972) (xy 46.598749 -272.972021) (xy 46.522965 -272.970002) (xy 46.447825 -272.95994)
			(xy 46.37418 -272.941948) (xy 46.302864 -272.91623) (xy 46.234687 -272.883078) (xy 46.170419 -272.842866)
			(xy 46.11079 -272.796051) (xy 46.056474 -272.743163) (xy 46.008088 -272.684801) (xy 45.96618 -272.621626)
			(xy 45.931224 -272.554355) (xy 45.903617 -272.48375) (xy 45.883671 -272.410609) (xy 45.871612 -272.335764)
			(xy 45.867577 -272.26006) (xy 44.751498 -272.26006) (xy 44.750994 -272.297966) (xy 44.742935 -272.373347)
			(xy 44.72691 -272.447445) (xy 44.7031 -272.51942) (xy 44.671774 -272.588456) (xy 44.633287 -272.653771)
			(xy 44.588076 -272.714626) (xy 44.536652 -272.77033) (xy 44.479599 -272.820252) (xy 44.417563 -272.863827)
			(xy 44.351246 -272.900562) (xy 44.2814 -272.930039) (xy 44.208817 -272.951925) (xy 44.134319 -272.965972)
			(xy 44.058749 -272.972021) (xy 43.982965 -272.970002) (xy 43.907825 -272.95994) (xy 43.83418 -272.941948)
			(xy 43.762864 -272.91623) (xy 43.694687 -272.883078) (xy 43.630419 -272.842866) (xy 43.57079 -272.796051)
			(xy 43.516474 -272.743163) (xy 43.468088 -272.684801) (xy 43.42618 -272.621626) (xy 43.391224 -272.554355)
			(xy 43.363617 -272.48375) (xy 43.343671 -272.410609) (xy 43.331612 -272.335764) (xy 43.327577 -272.26006)
			(xy 42.502604 -272.26006) (xy 42.593088 -272.332218) (xy 42.678643 -272.410691) (xy 42.758581 -272.494879)
			(xy 42.83252 -272.584381) (xy 42.900108 -272.678772) (xy 42.961022 -272.7776) (xy 43.014974 -272.880396)
			(xy 43.056604 -272.97507) (xy 84.927697 -272.97507) (xy 84.931732 -272.899366) (xy 84.943791 -272.824521)
			(xy 84.963737 -272.75138) (xy 84.991344 -272.680775) (xy 85.0263 -272.613504) (xy 85.068208 -272.550329)
			(xy 85.116594 -272.491967) (xy 85.17091 -272.439079) (xy 85.230539 -272.392264) (xy 85.294807 -272.352052)
			(xy 85.362984 -272.3189) (xy 85.4343 -272.293182) (xy 85.507945 -272.27519) (xy 85.583085 -272.265128)
			(xy 85.658869 -272.263109) (xy 85.734439 -272.269158) (xy 85.808937 -272.283205) (xy 85.88152 -272.305091)
			(xy 85.951366 -272.334568) (xy 86.017683 -272.371303) (xy 86.079719 -272.414878) (xy 86.136772 -272.4648)
			(xy 86.188196 -272.520504) (xy 86.233407 -272.581359) (xy 86.271894 -272.646674) (xy 86.30322 -272.71571)
			(xy 86.32703 -272.787685) (xy 86.343055 -272.861783) (xy 86.351114 -272.937164) (xy 86.351618 -272.97507)
			(xy 87.467697 -272.97507) (xy 87.471732 -272.899366) (xy 87.483791 -272.824521) (xy 87.503737 -272.75138)
			(xy 87.531344 -272.680775) (xy 87.5663 -272.613504) (xy 87.608208 -272.550329) (xy 87.656594 -272.491967)
			(xy 87.71091 -272.439079) (xy 87.770539 -272.392264) (xy 87.834807 -272.352052) (xy 87.902984 -272.3189)
			(xy 87.9743 -272.293182) (xy 88.047945 -272.27519) (xy 88.123085 -272.265128) (xy 88.198869 -272.263109)
			(xy 88.274439 -272.269158) (xy 88.348937 -272.283205) (xy 88.42152 -272.305091) (xy 88.491366 -272.334568)
			(xy 88.557683 -272.371303) (xy 88.619719 -272.414878) (xy 88.676772 -272.4648) (xy 88.728196 -272.520504)
			(xy 88.773407 -272.581359) (xy 88.811894 -272.646674) (xy 88.84322 -272.71571) (xy 88.86703 -272.787685)
			(xy 88.883055 -272.861783) (xy 88.891114 -272.937164) (xy 88.891618 -272.97507) (xy 90.007697 -272.97507)
			(xy 90.011732 -272.899366) (xy 90.023791 -272.824521) (xy 90.043737 -272.75138) (xy 90.071344 -272.680775)
			(xy 90.1063 -272.613504) (xy 90.148208 -272.550329) (xy 90.196594 -272.491967) (xy 90.25091 -272.439079)
			(xy 90.310539 -272.392264) (xy 90.374807 -272.352052) (xy 90.442984 -272.3189) (xy 90.5143 -272.293182)
			(xy 90.587945 -272.27519) (xy 90.663085 -272.265128) (xy 90.738869 -272.263109) (xy 90.814439 -272.269158)
			(xy 90.888937 -272.283205) (xy 90.96152 -272.305091) (xy 91.031366 -272.334568) (xy 91.097683 -272.371303)
			(xy 91.159719 -272.414878) (xy 91.216772 -272.4648) (xy 91.268196 -272.520504) (xy 91.313407 -272.581359)
			(xy 91.351894 -272.646674) (xy 91.38322 -272.71571) (xy 91.40703 -272.787685) (xy 91.423055 -272.861783)
			(xy 91.431114 -272.937164) (xy 91.431618 -272.97507) (xy 91.431114 -273.012976) (xy 91.423055 -273.088357)
			(xy 91.40703 -273.162455) (xy 91.38322 -273.23443) (xy 91.351894 -273.303466) (xy 91.313407 -273.368781)
			(xy 91.268196 -273.429636) (xy 91.216772 -273.48534) (xy 91.159719 -273.535262) (xy 91.097683 -273.578837)
			(xy 91.031366 -273.615572) (xy 90.96152 -273.645049) (xy 90.888937 -273.666935) (xy 90.814439 -273.680982)
			(xy 90.738869 -273.687031) (xy 90.663085 -273.685012) (xy 90.587945 -273.67495) (xy 90.5143 -273.656958)
			(xy 90.442984 -273.63124) (xy 90.374807 -273.598088) (xy 90.310539 -273.557876) (xy 90.25091 -273.511061)
			(xy 90.196594 -273.458173) (xy 90.148208 -273.399811) (xy 90.1063 -273.336636) (xy 90.071344 -273.269365)
			(xy 90.043737 -273.19876) (xy 90.023791 -273.125619) (xy 90.011732 -273.050774) (xy 90.007697 -272.97507)
			(xy 88.891618 -272.97507) (xy 88.891114 -273.012976) (xy 88.883055 -273.088357) (xy 88.86703 -273.162455)
			(xy 88.84322 -273.23443) (xy 88.811894 -273.303466) (xy 88.773407 -273.368781) (xy 88.728196 -273.429636)
			(xy 88.676772 -273.48534) (xy 88.619719 -273.535262) (xy 88.557683 -273.578837) (xy 88.491366 -273.615572)
			(xy 88.42152 -273.645049) (xy 88.348937 -273.666935) (xy 88.274439 -273.680982) (xy 88.198869 -273.687031)
			(xy 88.123085 -273.685012) (xy 88.047945 -273.67495) (xy 87.9743 -273.656958) (xy 87.902984 -273.63124)
			(xy 87.834807 -273.598088) (xy 87.770539 -273.557876) (xy 87.71091 -273.511061) (xy 87.656594 -273.458173)
			(xy 87.608208 -273.399811) (xy 87.5663 -273.336636) (xy 87.531344 -273.269365) (xy 87.503737 -273.19876)
			(xy 87.483791 -273.125619) (xy 87.471732 -273.050774) (xy 87.467697 -272.97507) (xy 86.351618 -272.97507)
			(xy 86.351114 -273.012976) (xy 86.343055 -273.088357) (xy 86.32703 -273.162455) (xy 86.30322 -273.23443)
			(xy 86.271894 -273.303466) (xy 86.233407 -273.368781) (xy 86.188196 -273.429636) (xy 86.136772 -273.48534)
			(xy 86.079719 -273.535262) (xy 86.017683 -273.578837) (xy 85.951366 -273.615572) (xy 85.88152 -273.645049)
			(xy 85.808937 -273.666935) (xy 85.734439 -273.680982) (xy 85.658869 -273.687031) (xy 85.583085 -273.685012)
			(xy 85.507945 -273.67495) (xy 85.4343 -273.656958) (xy 85.362984 -273.63124) (xy 85.294807 -273.598088)
			(xy 85.230539 -273.557876) (xy 85.17091 -273.511061) (xy 85.116594 -273.458173) (xy 85.068208 -273.399811)
			(xy 85.0263 -273.336636) (xy 84.991344 -273.269365) (xy 84.963737 -273.19876) (xy 84.943791 -273.125619)
			(xy 84.931732 -273.050774) (xy 84.927697 -272.97507) (xy 43.056604 -272.97507) (xy 43.061704 -272.986669)
			(xy 43.100992 -273.095913) (xy 43.132649 -273.207606) (xy 43.156525 -273.321218) (xy 43.172506 -273.436206)
			(xy 43.180515 -273.552023) (xy 43.181016 -273.61007) (xy 43.180515 -273.668117) (xy 43.172506 -273.783934)
			(xy 43.156525 -273.898922) (xy 43.132649 -274.012534) (xy 43.100992 -274.124227) (xy 43.061704 -274.233471)
			(xy 43.056604 -274.24507) (xy 86.197697 -274.24507) (xy 86.201732 -274.169366) (xy 86.213791 -274.094521)
			(xy 86.233737 -274.02138) (xy 86.261344 -273.950775) (xy 86.2963 -273.883504) (xy 86.338208 -273.820329)
			(xy 86.386594 -273.761967) (xy 86.44091 -273.709079) (xy 86.500539 -273.662264) (xy 86.564807 -273.622052)
			(xy 86.632984 -273.5889) (xy 86.7043 -273.563182) (xy 86.777945 -273.54519) (xy 86.853085 -273.535128)
			(xy 86.928869 -273.533109) (xy 87.004439 -273.539158) (xy 87.078937 -273.553205) (xy 87.15152 -273.575091)
			(xy 87.221366 -273.604568) (xy 87.287683 -273.641303) (xy 87.349719 -273.684878) (xy 87.406772 -273.7348)
			(xy 87.458196 -273.790504) (xy 87.503407 -273.851359) (xy 87.541894 -273.916674) (xy 87.57322 -273.98571)
			(xy 87.59703 -274.057685) (xy 87.613055 -274.131783) (xy 87.621114 -274.207164) (xy 87.621618 -274.24507)
			(xy 88.737697 -274.24507) (xy 88.741732 -274.169366) (xy 88.753791 -274.094521) (xy 88.773737 -274.02138)
			(xy 88.801344 -273.950775) (xy 88.8363 -273.883504) (xy 88.878208 -273.820329) (xy 88.926594 -273.761967)
			(xy 88.98091 -273.709079) (xy 89.040539 -273.662264) (xy 89.104807 -273.622052) (xy 89.172984 -273.5889)
			(xy 89.2443 -273.563182) (xy 89.317945 -273.54519) (xy 89.393085 -273.535128) (xy 89.468869 -273.533109)
			(xy 89.544439 -273.539158) (xy 89.618937 -273.553205) (xy 89.69152 -273.575091) (xy 89.761366 -273.604568)
			(xy 89.827683 -273.641303) (xy 89.889719 -273.684878) (xy 89.946772 -273.7348) (xy 89.998196 -273.790504)
			(xy 90.043407 -273.851359) (xy 90.081894 -273.916674) (xy 90.11322 -273.98571) (xy 90.13703 -274.057685)
			(xy 90.153055 -274.131783) (xy 90.161114 -274.207164) (xy 90.161618 -274.24507) (xy 91.277697 -274.24507)
			(xy 91.281732 -274.169366) (xy 91.293791 -274.094521) (xy 91.313737 -274.02138) (xy 91.341344 -273.950775)
			(xy 91.3763 -273.883504) (xy 91.418208 -273.820329) (xy 91.466594 -273.761967) (xy 91.52091 -273.709079)
			(xy 91.580539 -273.662264) (xy 91.644807 -273.622052) (xy 91.712984 -273.5889) (xy 91.7843 -273.563182)
			(xy 91.857945 -273.54519) (xy 91.933085 -273.535128) (xy 92.008869 -273.533109) (xy 92.084439 -273.539158)
			(xy 92.158937 -273.553205) (xy 92.23152 -273.575091) (xy 92.301366 -273.604568) (xy 92.367683 -273.641303)
			(xy 92.429719 -273.684878) (xy 92.486772 -273.7348) (xy 92.538196 -273.790504) (xy 92.583407 -273.851359)
			(xy 92.621894 -273.916674) (xy 92.65322 -273.98571) (xy 92.67703 -274.057685) (xy 92.693055 -274.131783)
			(xy 92.701114 -274.207164) (xy 92.701618 -274.24507) (xy 92.701114 -274.282976) (xy 92.693055 -274.358357)
			(xy 92.67703 -274.432455) (xy 92.65322 -274.50443) (xy 92.621894 -274.573466) (xy 92.583407 -274.638781)
			(xy 92.538196 -274.699636) (xy 92.486772 -274.75534) (xy 92.429719 -274.805262) (xy 92.367683 -274.848837)
			(xy 92.301366 -274.885572) (xy 92.23152 -274.915049) (xy 92.158937 -274.936935) (xy 92.084439 -274.950982)
			(xy 92.008869 -274.957031) (xy 91.933085 -274.955012) (xy 91.857945 -274.94495) (xy 91.7843 -274.926958)
			(xy 91.712984 -274.90124) (xy 91.644807 -274.868088) (xy 91.580539 -274.827876) (xy 91.52091 -274.781061)
			(xy 91.466594 -274.728173) (xy 91.418208 -274.669811) (xy 91.3763 -274.606636) (xy 91.341344 -274.539365)
			(xy 91.313737 -274.46876) (xy 91.293791 -274.395619) (xy 91.281732 -274.320774) (xy 91.277697 -274.24507)
			(xy 90.161618 -274.24507) (xy 90.161114 -274.282976) (xy 90.153055 -274.358357) (xy 90.13703 -274.432455)
			(xy 90.11322 -274.50443) (xy 90.081894 -274.573466) (xy 90.043407 -274.638781) (xy 89.998196 -274.699636)
			(xy 89.946772 -274.75534) (xy 89.889719 -274.805262) (xy 89.827683 -274.848837) (xy 89.761366 -274.885572)
			(xy 89.69152 -274.915049) (xy 89.618937 -274.936935) (xy 89.544439 -274.950982) (xy 89.468869 -274.957031)
			(xy 89.393085 -274.955012) (xy 89.317945 -274.94495) (xy 89.2443 -274.926958) (xy 89.172984 -274.90124)
			(xy 89.104807 -274.868088) (xy 89.040539 -274.827876) (xy 88.98091 -274.781061) (xy 88.926594 -274.728173)
			(xy 88.878208 -274.669811) (xy 88.8363 -274.606636) (xy 88.801344 -274.539365) (xy 88.773737 -274.46876)
			(xy 88.753791 -274.395619) (xy 88.741732 -274.320774) (xy 88.737697 -274.24507) (xy 87.621618 -274.24507)
			(xy 87.621114 -274.282976) (xy 87.613055 -274.358357) (xy 87.59703 -274.432455) (xy 87.57322 -274.50443)
			(xy 87.541894 -274.573466) (xy 87.503407 -274.638781) (xy 87.458196 -274.699636) (xy 87.406772 -274.75534)
			(xy 87.349719 -274.805262) (xy 87.287683 -274.848837) (xy 87.221366 -274.885572) (xy 87.15152 -274.915049)
			(xy 87.078937 -274.936935) (xy 87.004439 -274.950982) (xy 86.928869 -274.957031) (xy 86.853085 -274.955012)
			(xy 86.777945 -274.94495) (xy 86.7043 -274.926958) (xy 86.632984 -274.90124) (xy 86.564807 -274.868088)
			(xy 86.500539 -274.827876) (xy 86.44091 -274.781061) (xy 86.386594 -274.728173) (xy 86.338208 -274.669811)
			(xy 86.2963 -274.606636) (xy 86.261344 -274.539365) (xy 86.233737 -274.46876) (xy 86.213791 -274.395619)
			(xy 86.201732 -274.320774) (xy 86.197697 -274.24507) (xy 43.056604 -274.24507) (xy 43.055152 -274.248372)
			(xy 43.328336 -274.248372) (xy 44.751244 -274.248372) (xy 44.751244 -274.96008) (xy 45.867577 -274.96008)
			(xy 45.871612 -274.884376) (xy 45.883671 -274.809531) (xy 45.903617 -274.73639) (xy 45.931224 -274.665785)
			(xy 45.96618 -274.598514) (xy 46.008088 -274.535339) (xy 46.056474 -274.476977) (xy 46.11079 -274.424089)
			(xy 46.170419 -274.377274) (xy 46.234687 -274.337062) (xy 46.302864 -274.30391) (xy 46.37418 -274.278192)
			(xy 46.447825 -274.2602) (xy 46.522965 -274.250138) (xy 46.598749 -274.248119) (xy 46.674319 -274.254168)
			(xy 46.748817 -274.268215) (xy 46.8214 -274.290101) (xy 46.891246 -274.319578) (xy 46.957563 -274.356313)
			(xy 47.019599 -274.399888) (xy 47.076652 -274.44981) (xy 47.128076 -274.505514) (xy 47.173287 -274.566369)
			(xy 47.211774 -274.631684) (xy 47.2431 -274.70072) (xy 47.26691 -274.772695) (xy 47.282935 -274.846793)
			(xy 47.290994 -274.922174) (xy 47.291498 -274.96008) (xy 48.407577 -274.96008) (xy 48.411612 -274.884376)
			(xy 48.423671 -274.809531) (xy 48.443617 -274.73639) (xy 48.471224 -274.665785) (xy 48.50618 -274.598514)
			(xy 48.548088 -274.535339) (xy 48.596474 -274.476977) (xy 48.65079 -274.424089) (xy 48.710419 -274.377274)
			(xy 48.774687 -274.337062) (xy 48.842864 -274.30391) (xy 48.91418 -274.278192) (xy 48.987825 -274.2602)
			(xy 49.062965 -274.250138) (xy 49.138749 -274.248119) (xy 49.214319 -274.254168) (xy 49.288817 -274.268215)
			(xy 49.3614 -274.290101) (xy 49.431246 -274.319578) (xy 49.497563 -274.356313) (xy 49.559599 -274.399888)
			(xy 49.616652 -274.44981) (xy 49.668076 -274.505514) (xy 49.713287 -274.566369) (xy 49.751774 -274.631684)
			(xy 49.7831 -274.70072) (xy 49.80691 -274.772695) (xy 49.822935 -274.846793) (xy 49.830994 -274.922174)
			(xy 49.831498 -274.96008) (xy 50.947577 -274.96008) (xy 50.951612 -274.884376) (xy 50.963671 -274.809531)
			(xy 50.983617 -274.73639) (xy 51.011224 -274.665785) (xy 51.04618 -274.598514) (xy 51.088088 -274.535339)
			(xy 51.136474 -274.476977) (xy 51.19079 -274.424089) (xy 51.250419 -274.377274) (xy 51.314687 -274.337062)
			(xy 51.382864 -274.30391) (xy 51.45418 -274.278192) (xy 51.527825 -274.2602) (xy 51.602965 -274.250138)
			(xy 51.678749 -274.248119) (xy 51.754319 -274.254168) (xy 51.828817 -274.268215) (xy 51.9014 -274.290101)
			(xy 51.971246 -274.319578) (xy 52.037563 -274.356313) (xy 52.099599 -274.399888) (xy 52.156652 -274.44981)
			(xy 52.208076 -274.505514) (xy 52.253287 -274.566369) (xy 52.291774 -274.631684) (xy 52.3231 -274.70072)
			(xy 52.34691 -274.772695) (xy 52.362935 -274.846793) (xy 52.370994 -274.922174) (xy 52.371498 -274.96008)
			(xy 53.487577 -274.96008) (xy 53.491612 -274.884376) (xy 53.503671 -274.809531) (xy 53.523617 -274.73639)
			(xy 53.551224 -274.665785) (xy 53.58618 -274.598514) (xy 53.628088 -274.535339) (xy 53.676474 -274.476977)
			(xy 53.73079 -274.424089) (xy 53.790419 -274.377274) (xy 53.854687 -274.337062) (xy 53.922864 -274.30391)
			(xy 53.99418 -274.278192) (xy 54.067825 -274.2602) (xy 54.142965 -274.250138) (xy 54.218749 -274.248119)
			(xy 54.294319 -274.254168) (xy 54.368817 -274.268215) (xy 54.4414 -274.290101) (xy 54.511246 -274.319578)
			(xy 54.577563 -274.356313) (xy 54.639599 -274.399888) (xy 54.696652 -274.44981) (xy 54.748076 -274.505514)
			(xy 54.793287 -274.566369) (xy 54.831774 -274.631684) (xy 54.8631 -274.70072) (xy 54.88691 -274.772695)
			(xy 54.902935 -274.846793) (xy 54.910994 -274.922174) (xy 54.911498 -274.96008) (xy 56.027577 -274.96008)
			(xy 56.031612 -274.884376) (xy 56.043671 -274.809531) (xy 56.063617 -274.73639) (xy 56.091224 -274.665785)
			(xy 56.12618 -274.598514) (xy 56.168088 -274.535339) (xy 56.216474 -274.476977) (xy 56.27079 -274.424089)
			(xy 56.330419 -274.377274) (xy 56.394687 -274.337062) (xy 56.462864 -274.30391) (xy 56.53418 -274.278192)
			(xy 56.607825 -274.2602) (xy 56.682965 -274.250138) (xy 56.758749 -274.248119) (xy 56.834319 -274.254168)
			(xy 56.908817 -274.268215) (xy 56.9814 -274.290101) (xy 57.051246 -274.319578) (xy 57.117563 -274.356313)
			(xy 57.179599 -274.399888) (xy 57.236652 -274.44981) (xy 57.288076 -274.505514) (xy 57.333287 -274.566369)
			(xy 57.371774 -274.631684) (xy 57.4031 -274.70072) (xy 57.42691 -274.772695) (xy 57.442935 -274.846793)
			(xy 57.450994 -274.922174) (xy 57.451498 -274.96008) (xy 58.567577 -274.96008) (xy 58.571612 -274.884376)
			(xy 58.583671 -274.809531) (xy 58.603617 -274.73639) (xy 58.631224 -274.665785) (xy 58.66618 -274.598514)
			(xy 58.708088 -274.535339) (xy 58.756474 -274.476977) (xy 58.81079 -274.424089) (xy 58.870419 -274.377274)
			(xy 58.934687 -274.337062) (xy 59.002864 -274.30391) (xy 59.07418 -274.278192) (xy 59.147825 -274.2602)
			(xy 59.222965 -274.250138) (xy 59.298749 -274.248119) (xy 59.374319 -274.254168) (xy 59.448817 -274.268215)
			(xy 59.5214 -274.290101) (xy 59.591246 -274.319578) (xy 59.657563 -274.356313) (xy 59.719599 -274.399888)
			(xy 59.776652 -274.44981) (xy 59.828076 -274.505514) (xy 59.873287 -274.566369) (xy 59.911774 -274.631684)
			(xy 59.9431 -274.70072) (xy 59.96691 -274.772695) (xy 59.982935 -274.846793) (xy 59.990994 -274.922174)
			(xy 59.991498 -274.96008) (xy 61.107577 -274.96008) (xy 61.111612 -274.884376) (xy 61.123671 -274.809531)
			(xy 61.143617 -274.73639) (xy 61.171224 -274.665785) (xy 61.20618 -274.598514) (xy 61.248088 -274.535339)
			(xy 61.296474 -274.476977) (xy 61.35079 -274.424089) (xy 61.410419 -274.377274) (xy 61.474687 -274.337062)
			(xy 61.542864 -274.30391) (xy 61.61418 -274.278192) (xy 61.687825 -274.2602) (xy 61.762965 -274.250138)
			(xy 61.838749 -274.248119) (xy 61.914319 -274.254168) (xy 61.988817 -274.268215) (xy 62.0614 -274.290101)
			(xy 62.131246 -274.319578) (xy 62.197563 -274.356313) (xy 62.259599 -274.399888) (xy 62.316652 -274.44981)
			(xy 62.368076 -274.505514) (xy 62.413287 -274.566369) (xy 62.451774 -274.631684) (xy 62.4831 -274.70072)
			(xy 62.50691 -274.772695) (xy 62.522935 -274.846793) (xy 62.530994 -274.922174) (xy 62.531498 -274.96008)
			(xy 62.530994 -274.997986) (xy 62.522935 -275.073367) (xy 62.50691 -275.147465) (xy 62.4831 -275.21944)
			(xy 62.451774 -275.288476) (xy 62.413287 -275.353791) (xy 62.368076 -275.414646) (xy 62.316652 -275.47035)
			(xy 62.265544 -275.51507) (xy 84.927697 -275.51507) (xy 84.931732 -275.439366) (xy 84.943791 -275.364521)
			(xy 84.963737 -275.29138) (xy 84.991344 -275.220775) (xy 85.0263 -275.153504) (xy 85.068208 -275.090329)
			(xy 85.116594 -275.031967) (xy 85.17091 -274.979079) (xy 85.230539 -274.932264) (xy 85.294807 -274.892052)
			(xy 85.362984 -274.8589) (xy 85.4343 -274.833182) (xy 85.507945 -274.81519) (xy 85.583085 -274.805128)
			(xy 85.658869 -274.803109) (xy 85.734439 -274.809158) (xy 85.808937 -274.823205) (xy 85.88152 -274.845091)
			(xy 85.951366 -274.874568) (xy 86.017683 -274.911303) (xy 86.079719 -274.954878) (xy 86.136772 -275.0048)
			(xy 86.188196 -275.060504) (xy 86.233407 -275.121359) (xy 86.271894 -275.186674) (xy 86.30322 -275.25571)
			(xy 86.32703 -275.327685) (xy 86.343055 -275.401783) (xy 86.351114 -275.477164) (xy 86.351618 -275.51507)
			(xy 87.467697 -275.51507) (xy 87.471732 -275.439366) (xy 87.483791 -275.364521) (xy 87.503737 -275.29138)
			(xy 87.531344 -275.220775) (xy 87.5663 -275.153504) (xy 87.608208 -275.090329) (xy 87.656594 -275.031967)
			(xy 87.71091 -274.979079) (xy 87.770539 -274.932264) (xy 87.834807 -274.892052) (xy 87.902984 -274.8589)
			(xy 87.9743 -274.833182) (xy 88.047945 -274.81519) (xy 88.123085 -274.805128) (xy 88.198869 -274.803109)
			(xy 88.274439 -274.809158) (xy 88.348937 -274.823205) (xy 88.42152 -274.845091) (xy 88.491366 -274.874568)
			(xy 88.557683 -274.911303) (xy 88.619719 -274.954878) (xy 88.676772 -275.0048) (xy 88.728196 -275.060504)
			(xy 88.773407 -275.121359) (xy 88.811894 -275.186674) (xy 88.84322 -275.25571) (xy 88.86703 -275.327685)
			(xy 88.883055 -275.401783) (xy 88.891114 -275.477164) (xy 88.891618 -275.51507) (xy 90.007697 -275.51507)
			(xy 90.011732 -275.439366) (xy 90.023791 -275.364521) (xy 90.043737 -275.29138) (xy 90.071344 -275.220775)
			(xy 90.1063 -275.153504) (xy 90.148208 -275.090329) (xy 90.196594 -275.031967) (xy 90.25091 -274.979079)
			(xy 90.310539 -274.932264) (xy 90.374807 -274.892052) (xy 90.442984 -274.8589) (xy 90.5143 -274.833182)
			(xy 90.587945 -274.81519) (xy 90.663085 -274.805128) (xy 90.738869 -274.803109) (xy 90.814439 -274.809158)
			(xy 90.888937 -274.823205) (xy 90.96152 -274.845091) (xy 91.031366 -274.874568) (xy 91.097683 -274.911303)
			(xy 91.159719 -274.954878) (xy 91.165664 -274.96008) (xy 93.154506 -274.96008) (xy 93.158522 -274.84381)
			(xy 93.170549 -274.728095) (xy 93.190531 -274.613485) (xy 93.218373 -274.500526) (xy 93.253942 -274.389758)
			(xy 93.297068 -274.281707) (xy 93.347545 -274.176889) (xy 93.405134 -274.075804) (xy 93.46956 -273.978932)
			(xy 93.540515 -273.886736) (xy 93.617662 -273.799655) (xy 93.700633 -273.718104) (xy 93.789033 -273.642472)
			(xy 93.88244 -273.573118) (xy 93.980409 -273.510375) (xy 94.082473 -273.454539) (xy 94.188147 -273.405878)
			(xy 94.296926 -273.364624) (xy 94.408291 -273.330973) (xy 94.521714 -273.305085) (xy 94.636651 -273.287084)
			(xy 94.752557 -273.277055) (xy 94.868879 -273.275047) (xy 94.985062 -273.281069) (xy 95.100553 -273.295092)
			(xy 95.214801 -273.31705) (xy 95.327262 -273.346837) (xy 95.4374 -273.384312) (xy 95.54469 -273.429297)
			(xy 95.648621 -273.481576) (xy 95.748697 -273.540901) (xy 95.844443 -273.606989) (xy 95.9354 -273.679525)
			(xy 96.021136 -273.758164) (xy 96.101243 -273.84253) (xy 96.175339 -273.932222) (xy 96.243069 -274.026812)
			(xy 96.304113 -274.12585) (xy 96.358178 -274.228863) (xy 96.405008 -274.33536) (xy 96.444379 -274.444835)
			(xy 96.476103 -274.556765) (xy 96.500029 -274.670617) (xy 96.516043 -274.785849) (xy 96.52407 -274.901911)
			(xy 96.524572 -274.96008) (xy 96.52407 -275.018249) (xy 96.516043 -275.134311) (xy 96.500029 -275.249543)
			(xy 96.476103 -275.363395) (xy 96.444379 -275.475325) (xy 96.405008 -275.5848) (xy 96.358178 -275.691297)
			(xy 96.304113 -275.79431) (xy 96.243069 -275.893348) (xy 96.175339 -275.987938) (xy 96.101243 -276.07763)
			(xy 96.021136 -276.161996) (xy 95.9354 -276.240635) (xy 95.844443 -276.313171) (xy 95.748697 -276.379259)
			(xy 95.648621 -276.438584) (xy 95.54469 -276.490863) (xy 95.4374 -276.535848) (xy 95.327262 -276.573323)
			(xy 95.214801 -276.60311) (xy 95.100553 -276.625068) (xy 94.985062 -276.639091) (xy 94.868879 -276.645113)
			(xy 94.752557 -276.643105) (xy 94.636651 -276.633076) (xy 94.521714 -276.615075) (xy 94.408291 -276.589187)
			(xy 94.296926 -276.555536) (xy 94.188147 -276.514282) (xy 94.082473 -276.465621) (xy 93.980409 -276.409785)
			(xy 93.88244 -276.347042) (xy 93.789033 -276.277688) (xy 93.700633 -276.202056) (xy 93.617662 -276.120505)
			(xy 93.540515 -276.033424) (xy 93.46956 -275.941228) (xy 93.405134 -275.844356) (xy 93.347545 -275.743271)
			(xy 93.297068 -275.638453) (xy 93.253942 -275.530402) (xy 93.218373 -275.419634) (xy 93.190531 -275.306675)
			(xy 93.170549 -275.192065) (xy 93.158522 -275.07635) (xy 93.154506 -274.96008) (xy 91.165664 -274.96008)
			(xy 91.216772 -275.0048) (xy 91.268196 -275.060504) (xy 91.313407 -275.121359) (xy 91.351894 -275.186674)
			(xy 91.38322 -275.25571) (xy 91.40703 -275.327685) (xy 91.423055 -275.401783) (xy 91.431114 -275.477164)
			(xy 91.431618 -275.51507) (xy 91.431114 -275.552976) (xy 91.423055 -275.628357) (xy 91.40703 -275.702455)
			(xy 91.38322 -275.77443) (xy 91.351894 -275.843466) (xy 91.313407 -275.908781) (xy 91.268196 -275.969636)
			(xy 91.216772 -276.02534) (xy 91.159719 -276.075262) (xy 91.097683 -276.118837) (xy 91.031366 -276.155572)
			(xy 90.96152 -276.185049) (xy 90.888937 -276.206935) (xy 90.814439 -276.220982) (xy 90.738869 -276.227031)
			(xy 90.663085 -276.225012) (xy 90.587945 -276.21495) (xy 90.5143 -276.196958) (xy 90.442984 -276.17124)
			(xy 90.374807 -276.138088) (xy 90.310539 -276.097876) (xy 90.25091 -276.051061) (xy 90.196594 -275.998173)
			(xy 90.148208 -275.939811) (xy 90.1063 -275.876636) (xy 90.071344 -275.809365) (xy 90.043737 -275.73876)
			(xy 90.023791 -275.665619) (xy 90.011732 -275.590774) (xy 90.007697 -275.51507) (xy 88.891618 -275.51507)
			(xy 88.891114 -275.552976) (xy 88.883055 -275.628357) (xy 88.86703 -275.702455) (xy 88.84322 -275.77443)
			(xy 88.811894 -275.843466) (xy 88.773407 -275.908781) (xy 88.728196 -275.969636) (xy 88.676772 -276.02534)
			(xy 88.619719 -276.075262) (xy 88.557683 -276.118837) (xy 88.491366 -276.155572) (xy 88.42152 -276.185049)
			(xy 88.348937 -276.206935) (xy 88.274439 -276.220982) (xy 88.198869 -276.227031) (xy 88.123085 -276.225012)
			(xy 88.047945 -276.21495) (xy 87.9743 -276.196958) (xy 87.902984 -276.17124) (xy 87.834807 -276.138088)
			(xy 87.770539 -276.097876) (xy 87.71091 -276.051061) (xy 87.656594 -275.998173) (xy 87.608208 -275.939811)
			(xy 87.5663 -275.876636) (xy 87.531344 -275.809365) (xy 87.503737 -275.73876) (xy 87.483791 -275.665619)
			(xy 87.471732 -275.590774) (xy 87.467697 -275.51507) (xy 86.351618 -275.51507) (xy 86.351114 -275.552976)
			(xy 86.343055 -275.628357) (xy 86.32703 -275.702455) (xy 86.30322 -275.77443) (xy 86.271894 -275.843466)
			(xy 86.233407 -275.908781) (xy 86.188196 -275.969636) (xy 86.136772 -276.02534) (xy 86.079719 -276.075262)
			(xy 86.017683 -276.118837) (xy 85.951366 -276.155572) (xy 85.88152 -276.185049) (xy 85.808937 -276.206935)
			(xy 85.734439 -276.220982) (xy 85.658869 -276.227031) (xy 85.583085 -276.225012) (xy 85.507945 -276.21495)
			(xy 85.4343 -276.196958) (xy 85.362984 -276.17124) (xy 85.294807 -276.138088) (xy 85.230539 -276.097876)
			(xy 85.17091 -276.051061) (xy 85.116594 -275.998173) (xy 85.068208 -275.939811) (xy 85.0263 -275.876636)
			(xy 84.991344 -275.809365) (xy 84.963737 -275.73876) (xy 84.943791 -275.665619) (xy 84.931732 -275.590774)
			(xy 84.927697 -275.51507) (xy 62.265544 -275.51507) (xy 62.259599 -275.520272) (xy 62.197563 -275.563847)
			(xy 62.131246 -275.600582) (xy 62.0614 -275.630059) (xy 61.988817 -275.651945) (xy 61.914319 -275.665992)
			(xy 61.838749 -275.672041) (xy 61.762965 -275.670022) (xy 61.687825 -275.65996) (xy 61.61418 -275.641968)
			(xy 61.542864 -275.61625) (xy 61.474687 -275.583098) (xy 61.410419 -275.542886) (xy 61.35079 -275.496071)
			(xy 61.296474 -275.443183) (xy 61.248088 -275.384821) (xy 61.20618 -275.321646) (xy 61.171224 -275.254375)
			(xy 61.143617 -275.18377) (xy 61.123671 -275.110629) (xy 61.111612 -275.035784) (xy 61.107577 -274.96008)
			(xy 59.991498 -274.96008) (xy 59.990994 -274.997986) (xy 59.982935 -275.073367) (xy 59.96691 -275.147465)
			(xy 59.9431 -275.21944) (xy 59.911774 -275.288476) (xy 59.873287 -275.353791) (xy 59.828076 -275.414646)
			(xy 59.776652 -275.47035) (xy 59.719599 -275.520272) (xy 59.657563 -275.563847) (xy 59.591246 -275.600582)
			(xy 59.5214 -275.630059) (xy 59.448817 -275.651945) (xy 59.374319 -275.665992) (xy 59.298749 -275.672041)
			(xy 59.222965 -275.670022) (xy 59.147825 -275.65996) (xy 59.07418 -275.641968) (xy 59.002864 -275.61625)
			(xy 58.934687 -275.583098) (xy 58.870419 -275.542886) (xy 58.81079 -275.496071) (xy 58.756474 -275.443183)
			(xy 58.708088 -275.384821) (xy 58.66618 -275.321646) (xy 58.631224 -275.254375) (xy 58.603617 -275.18377)
			(xy 58.583671 -275.110629) (xy 58.571612 -275.035784) (xy 58.567577 -274.96008) (xy 57.451498 -274.96008)
			(xy 57.450994 -274.997986) (xy 57.442935 -275.073367) (xy 57.42691 -275.147465) (xy 57.4031 -275.21944)
			(xy 57.371774 -275.288476) (xy 57.333287 -275.353791) (xy 57.288076 -275.414646) (xy 57.236652 -275.47035)
			(xy 57.179599 -275.520272) (xy 57.117563 -275.563847) (xy 57.051246 -275.600582) (xy 56.9814 -275.630059)
			(xy 56.908817 -275.651945) (xy 56.834319 -275.665992) (xy 56.758749 -275.672041) (xy 56.682965 -275.670022)
			(xy 56.607825 -275.65996) (xy 56.53418 -275.641968) (xy 56.462864 -275.61625) (xy 56.394687 -275.583098)
			(xy 56.330419 -275.542886) (xy 56.27079 -275.496071) (xy 56.216474 -275.443183) (xy 56.168088 -275.384821)
			(xy 56.12618 -275.321646) (xy 56.091224 -275.254375) (xy 56.063617 -275.18377) (xy 56.043671 -275.110629)
			(xy 56.031612 -275.035784) (xy 56.027577 -274.96008) (xy 54.911498 -274.96008) (xy 54.910994 -274.997986)
			(xy 54.902935 -275.073367) (xy 54.88691 -275.147465) (xy 54.8631 -275.21944) (xy 54.831774 -275.288476)
			(xy 54.793287 -275.353791) (xy 54.748076 -275.414646) (xy 54.696652 -275.47035) (xy 54.639599 -275.520272)
			(xy 54.577563 -275.563847) (xy 54.511246 -275.600582) (xy 54.4414 -275.630059) (xy 54.368817 -275.651945)
			(xy 54.294319 -275.665992) (xy 54.218749 -275.672041) (xy 54.142965 -275.670022) (xy 54.067825 -275.65996)
			(xy 53.99418 -275.641968) (xy 53.922864 -275.61625) (xy 53.854687 -275.583098) (xy 53.790419 -275.542886)
			(xy 53.73079 -275.496071) (xy 53.676474 -275.443183) (xy 53.628088 -275.384821) (xy 53.58618 -275.321646)
			(xy 53.551224 -275.254375) (xy 53.523617 -275.18377) (xy 53.503671 -275.110629) (xy 53.491612 -275.035784)
			(xy 53.487577 -274.96008) (xy 52.371498 -274.96008) (xy 52.370994 -274.997986) (xy 52.362935 -275.073367)
			(xy 52.34691 -275.147465) (xy 52.3231 -275.21944) (xy 52.291774 -275.288476) (xy 52.253287 -275.353791)
			(xy 52.208076 -275.414646) (xy 52.156652 -275.47035) (xy 52.099599 -275.520272) (xy 52.037563 -275.563847)
			(xy 51.971246 -275.600582) (xy 51.9014 -275.630059) (xy 51.828817 -275.651945) (xy 51.754319 -275.665992)
			(xy 51.678749 -275.672041) (xy 51.602965 -275.670022) (xy 51.527825 -275.65996) (xy 51.45418 -275.641968)
			(xy 51.382864 -275.61625) (xy 51.314687 -275.583098) (xy 51.250419 -275.542886) (xy 51.19079 -275.496071)
			(xy 51.136474 -275.443183) (xy 51.088088 -275.384821) (xy 51.04618 -275.321646) (xy 51.011224 -275.254375)
			(xy 50.983617 -275.18377) (xy 50.963671 -275.110629) (xy 50.951612 -275.035784) (xy 50.947577 -274.96008)
			(xy 49.831498 -274.96008) (xy 49.830994 -274.997986) (xy 49.822935 -275.073367) (xy 49.80691 -275.147465)
			(xy 49.7831 -275.21944) (xy 49.751774 -275.288476) (xy 49.713287 -275.353791) (xy 49.668076 -275.414646)
			(xy 49.616652 -275.47035) (xy 49.559599 -275.520272) (xy 49.497563 -275.563847) (xy 49.431246 -275.600582)
			(xy 49.3614 -275.630059) (xy 49.288817 -275.651945) (xy 49.214319 -275.665992) (xy 49.138749 -275.672041)
			(xy 49.062965 -275.670022) (xy 48.987825 -275.65996) (xy 48.91418 -275.641968) (xy 48.842864 -275.61625)
			(xy 48.774687 -275.583098) (xy 48.710419 -275.542886) (xy 48.65079 -275.496071) (xy 48.596474 -275.443183)
			(xy 48.548088 -275.384821) (xy 48.50618 -275.321646) (xy 48.471224 -275.254375) (xy 48.443617 -275.18377)
			(xy 48.423671 -275.110629) (xy 48.411612 -275.035784) (xy 48.407577 -274.96008) (xy 47.291498 -274.96008)
			(xy 47.290994 -274.997986) (xy 47.282935 -275.073367) (xy 47.26691 -275.147465) (xy 47.2431 -275.21944)
			(xy 47.211774 -275.288476) (xy 47.173287 -275.353791) (xy 47.128076 -275.414646) (xy 47.076652 -275.47035)
			(xy 47.019599 -275.520272) (xy 46.957563 -275.563847) (xy 46.891246 -275.600582) (xy 46.8214 -275.630059)
			(xy 46.748817 -275.651945) (xy 46.674319 -275.665992) (xy 46.598749 -275.672041) (xy 46.522965 -275.670022)
			(xy 46.447825 -275.65996) (xy 46.37418 -275.641968) (xy 46.302864 -275.61625) (xy 46.234687 -275.583098)
			(xy 46.170419 -275.542886) (xy 46.11079 -275.496071) (xy 46.056474 -275.443183) (xy 46.008088 -275.384821)
			(xy 45.96618 -275.321646) (xy 45.931224 -275.254375) (xy 45.903617 -275.18377) (xy 45.883671 -275.110629)
			(xy 45.871612 -275.035784) (xy 45.867577 -274.96008) (xy 44.751244 -274.96008) (xy 44.751244 -275.671788)
			(xy 43.328336 -275.671788) (xy 43.328336 -274.248372) (xy 43.055152 -274.248372) (xy 43.014974 -274.339744)
			(xy 42.961022 -274.44254) (xy 42.900108 -274.541368) (xy 42.83252 -274.635759) (xy 42.758581 -274.725261)
			(xy 42.678643 -274.809449) (xy 42.593088 -274.887922) (xy 42.502322 -274.960305) (xy 42.406779 -275.026254)
			(xy 42.306914 -275.085454) (xy 42.203202 -275.137623) (xy 42.096139 -275.182512) (xy 41.986233 -275.219908)
			(xy 41.874009 -275.249633) (xy 41.760003 -275.271544) (xy 41.644756 -275.285537) (xy 41.528818 -275.291546)
			(xy 41.412742 -275.289543) (xy 41.29708 -275.279535) (xy 41.182385 -275.261572) (xy 41.069202 -275.235739)
			(xy 40.958071 -275.202159) (xy 40.849522 -275.160991) (xy 40.744072 -275.112433) (xy 40.642223 -275.056716)
			(xy 40.54446 -274.994104) (xy 40.45125 -274.924897) (xy 40.363037 -274.849424) (xy 40.280241 -274.768045)
			(xy 40.203257 -274.681148) (xy 40.132452 -274.589147) (xy 40.068162 -274.49248) (xy 40.010695 -274.391608)
			(xy 39.960324 -274.287011) (xy 39.917289 -274.179188) (xy 39.881795 -274.068654) (xy 39.854012 -273.955934)
			(xy 39.834072 -273.841566) (xy 39.82207 -273.726094) (xy 39.818063 -273.61007) (xy 36.596828 -273.61007)
			(xy 36.596828 -275.540724) (xy 41.548812 -280.492708) (xy 88.481152 -280.492708) (xy 88.485223 -280.437086)
			(xy 88.497349 -280.382649) (xy 88.517272 -280.330558) (xy 88.544568 -280.281923) (xy 88.578654 -280.23778)
			(xy 88.618803 -280.199071) (xy 88.664161 -280.16662) (xy 88.713761 -280.141119) (xy 88.766545 -280.123112)
			(xy 88.821388 -280.112982) (xy 88.877122 -280.110945) (xy 88.932559 -280.117045) (xy 88.986516 -280.131151)
			(xy 89.037845 -280.152963) (xy 89.085451 -280.182017) (xy 89.128319 -280.217692) (xy 89.165536 -280.259229)
			(xy 89.196309 -280.305742) (xy 89.219981 -280.356239) (xy 89.236049 -280.409646) (xy 89.244169 -280.464822)
			(xy 89.244678 -280.492708) (xy 89.244169 -280.520594) (xy 89.236049 -280.57577) (xy 89.219981 -280.629177)
			(xy 89.196309 -280.679674) (xy 89.165536 -280.726187) (xy 89.128319 -280.767724) (xy 89.085451 -280.803399)
			(xy 89.037845 -280.832453) (xy 88.986516 -280.854265) (xy 88.932559 -280.868371) (xy 88.877122 -280.874471)
			(xy 88.821388 -280.872434) (xy 88.766545 -280.862304) (xy 88.713761 -280.844297) (xy 88.664161 -280.818796)
			(xy 88.618803 -280.786345) (xy 88.578654 -280.747636) (xy 88.544568 -280.703493) (xy 88.517272 -280.654858)
			(xy 88.497349 -280.602767) (xy 88.485223 -280.54833) (xy 88.481152 -280.492708) (xy 41.548812 -280.492708)
			(xy 42.182796 -281.126692) (xy 87.019128 -281.126692) (xy 87.023199 -281.07107) (xy 87.035325 -281.016633)
			(xy 87.055248 -280.964542) (xy 87.082544 -280.915907) (xy 87.11663 -280.871764) (xy 87.156779 -280.833055)
			(xy 87.202137 -280.800604) (xy 87.251737 -280.775103) (xy 87.304521 -280.757096) (xy 87.359364 -280.746966)
			(xy 87.415098 -280.744929) (xy 87.470535 -280.751029) (xy 87.524492 -280.765135) (xy 87.575821 -280.786947)
			(xy 87.623427 -280.816001) (xy 87.666295 -280.851676) (xy 87.703512 -280.893213) (xy 87.734285 -280.939726)
			(xy 87.757957 -280.990223) (xy 87.774025 -281.04363) (xy 87.782145 -281.098806) (xy 87.782654 -281.126692)
			(xy 87.782145 -281.154578) (xy 87.774025 -281.209754) (xy 87.757957 -281.263161) (xy 87.734285 -281.313658)
			(xy 87.703512 -281.360171) (xy 87.666295 -281.401708) (xy 87.623427 -281.437383) (xy 87.575821 -281.466437)
			(xy 87.524492 -281.488249) (xy 87.470535 -281.502355) (xy 87.415098 -281.508455) (xy 87.359364 -281.506418)
			(xy 87.304521 -281.496288) (xy 87.251737 -281.478281) (xy 87.202137 -281.45278) (xy 87.156779 -281.420329)
			(xy 87.11663 -281.38162) (xy 87.082544 -281.337477) (xy 87.055248 -281.288842) (xy 87.035325 -281.236751)
			(xy 87.023199 -281.182314) (xy 87.019128 -281.126692) (xy 42.182796 -281.126692) (xy 42.893996 -281.837892)
			(xy 85.345268 -281.837892) (xy 85.349339 -281.78227) (xy 85.361465 -281.727833) (xy 85.381388 -281.675742)
			(xy 85.408684 -281.627107) (xy 85.44277 -281.582964) (xy 85.482919 -281.544255) (xy 85.528277 -281.511804)
			(xy 85.577877 -281.486303) (xy 85.630661 -281.468296) (xy 85.685504 -281.458166) (xy 85.741238 -281.456129)
			(xy 85.796675 -281.462229) (xy 85.850632 -281.476335) (xy 85.901961 -281.498147) (xy 85.949567 -281.527201)
			(xy 85.992435 -281.562876) (xy 86.029652 -281.604413) (xy 86.060425 -281.650926) (xy 86.084097 -281.701423)
			(xy 86.100165 -281.75483) (xy 86.108285 -281.810006) (xy 86.108794 -281.837892) (xy 86.108285 -281.865778)
			(xy 86.100165 -281.920954) (xy 86.084097 -281.974361) (xy 86.060425 -282.024858) (xy 86.029652 -282.071371)
			(xy 85.992435 -282.112908) (xy 85.949567 -282.148583) (xy 85.901961 -282.177637) (xy 85.850632 -282.199449)
			(xy 85.796675 -282.213555) (xy 85.741238 -282.219655) (xy 85.685504 -282.217618) (xy 85.630661 -282.207488)
			(xy 85.577877 -282.189481) (xy 85.528277 -282.16398) (xy 85.482919 -282.131529) (xy 85.44277 -282.09282)
			(xy 85.408684 -282.048677) (xy 85.381388 -282.000042) (xy 85.361465 -281.947951) (xy 85.349339 -281.893514)
			(xy 85.345268 -281.837892) (xy 42.893996 -281.837892) (xy 44.601892 -283.545788) (xy 44.601892 -284.345634)
			(xy 71.362824 -284.345634) (xy 71.362824 -283.400754) (xy 71.36352 -283.364688) (xy 71.373839 -283.293297)
			(xy 71.383398 -283.258514) (xy 71.388224 -283.240988) (xy 71.388224 -282.8671) (xy 72.35444 -282.8671)
			(xy 72.35444 -283.240988) (xy 72.359266 -283.258514) (xy 72.368805 -283.293301) (xy 72.379134 -283.36469)
			(xy 72.37984 -283.400754) (xy 72.37984 -283.501084) (xy 72.691244 -283.501084) (xy 72.691244 -282.556204)
			(xy 72.691736 -282.523468) (xy 72.700177 -282.458542) (xy 72.716882 -282.395236) (xy 72.741575 -282.334599)
			(xy 72.773846 -282.277632) (xy 72.793098 -282.25115) (xy 72.818244 -282.217368) (xy 72.818244 -282.200096)
			(xy 72.833738 -282.200096) (xy 72.869552 -282.16987) (xy 72.894729 -282.149017) (xy 72.949461 -282.113266)
			(xy 73.008326 -282.084827) (xy 73.070351 -282.064172) (xy 73.134513 -282.051641) (xy 73.199752 -282.047441)
			(xy 73.264991 -282.051641) (xy 73.329153 -282.064172) (xy 73.391178 -282.084827) (xy 73.450043 -282.113266)
			(xy 73.504775 -282.149017) (xy 73.529952 -282.16987) (xy 73.565766 -282.200096) (xy 73.58126 -282.200096)
			(xy 73.58126 -282.217368) (xy 73.606406 -282.25115) (xy 73.62109 -282.271284) (xy 73.646922 -282.313902)
			(xy 73.657968 -282.33624) (xy 73.665289 -282.350334) (xy 73.685691 -282.374661) (xy 73.711466 -282.393199)
			(xy 73.741019 -282.404802) (xy 73.772522 -282.408751) (xy 73.804025 -282.404802) (xy 73.833578 -282.393199)
			(xy 73.859353 -282.374661) (xy 73.879755 -282.350334) (xy 73.887076 -282.33624) (xy 73.898107 -282.313894)
			(xy 73.923934 -282.27127) (xy 73.938638 -282.25115) (xy 73.963784 -282.217368) (xy 73.963784 -282.200096)
			(xy 73.979278 -282.200096) (xy 74.015092 -282.16987) (xy 74.040269 -282.149017) (xy 74.095001 -282.113266)
			(xy 74.153866 -282.084827) (xy 74.215891 -282.064172) (xy 74.280053 -282.051641) (xy 74.345292 -282.047441)
			(xy 74.410531 -282.051641) (xy 74.474693 -282.064172) (xy 74.536718 -282.084827) (xy 74.595583 -282.113266)
			(xy 74.650315 -282.149017) (xy 74.675492 -282.16987) (xy 74.711306 -282.200096) (xy 74.7268 -282.200096)
			(xy 74.7268 -282.217368) (xy 74.751946 -282.25115) (xy 74.771174 -282.277647) (xy 74.803441 -282.334612)
			(xy 74.82813 -282.395246) (xy 74.844833 -282.458548) (xy 74.853273 -282.52347) (xy 74.8538 -282.556204)
			(xy 74.8538 -283.486352) (xy 83.925662 -283.486352) (xy 83.929733 -283.43073) (xy 83.941859 -283.376293)
			(xy 83.961782 -283.324202) (xy 83.989078 -283.275567) (xy 84.023164 -283.231424) (xy 84.063313 -283.192715)
			(xy 84.108671 -283.160264) (xy 84.158271 -283.134763) (xy 84.211055 -283.116756) (xy 84.265898 -283.106626)
			(xy 84.321632 -283.104589) (xy 84.377069 -283.110689) (xy 84.431026 -283.124795) (xy 84.482355 -283.146607)
			(xy 84.529961 -283.175661) (xy 84.572829 -283.211336) (xy 84.610046 -283.252873) (xy 84.640819 -283.299386)
			(xy 84.664491 -283.349883) (xy 84.680559 -283.40329) (xy 84.688679 -283.458466) (xy 84.689188 -283.486352)
			(xy 84.688679 -283.514238) (xy 84.680559 -283.569414) (xy 84.664491 -283.622821) (xy 84.640819 -283.673318)
			(xy 84.610046 -283.719831) (xy 84.572829 -283.761368) (xy 84.529961 -283.797043) (xy 84.482355 -283.826097)
			(xy 84.431026 -283.847909) (xy 84.377069 -283.862015) (xy 84.321632 -283.868115) (xy 84.265898 -283.866078)
			(xy 84.211055 -283.855948) (xy 84.158271 -283.837941) (xy 84.108671 -283.81244) (xy 84.063313 -283.779989)
			(xy 84.023164 -283.74128) (xy 83.989078 -283.697137) (xy 83.961782 -283.648502) (xy 83.941859 -283.596411)
			(xy 83.929733 -283.541974) (xy 83.925662 -283.486352) (xy 74.8538 -283.486352) (xy 74.8538 -283.501084)
			(xy 74.853295 -283.533487) (xy 74.84505 -283.597768) (xy 74.828705 -283.66048) (xy 74.804525 -283.720607)
			(xy 74.772901 -283.777174) (xy 74.734346 -283.829265) (xy 74.689485 -283.876035) (xy 74.639045 -283.916726)
			(xy 74.583844 -283.950679) (xy 74.524776 -283.977343) (xy 74.462799 -283.996286) (xy 74.398918 -284.007201)
			(xy 74.334168 -284.009911) (xy 74.269598 -284.004372) (xy 74.206255 -283.990674) (xy 74.145166 -283.969039)
			(xy 74.087321 -283.939818) (xy 74.033657 -283.903484) (xy 73.985045 -283.860626) (xy 73.963276 -283.836618)
			(xy 73.948694 -283.820682) (xy 73.915105 -283.793529) (xy 73.877408 -283.772448) (xy 73.836687 -283.758048)
			(xy 73.794118 -283.750742) (xy 73.750926 -283.750742) (xy 73.708357 -283.758048) (xy 73.667636 -283.772448)
			(xy 73.629939 -283.793529) (xy 73.59635 -283.820682) (xy 73.581768 -283.836618) (xy 73.559987 -283.860618)
			(xy 73.51138 -283.903487) (xy 73.457719 -283.939833) (xy 73.399875 -283.969064) (xy 73.338784 -283.990708)
			(xy 73.275439 -284.004413) (xy 73.210866 -284.009957) (xy 73.146111 -284.007251) (xy 73.082226 -283.996337)
			(xy 73.020245 -283.977394) (xy 72.961174 -283.950728) (xy 72.90597 -283.916772) (xy 72.855529 -283.876076)
			(xy 72.810669 -283.829299) (xy 72.772116 -283.777202) (xy 72.740497 -283.720627) (xy 72.716323 -283.660494)
			(xy 72.699986 -283.597775) (xy 72.691752 -283.53349) (xy 72.691244 -283.501084) (xy 72.37984 -283.501084)
			(xy 72.37984 -284.345634) (xy 72.379338 -284.377595) (xy 72.371327 -284.441013) (xy 72.35543 -284.502927)
			(xy 72.331898 -284.56236) (xy 72.301104 -284.618375) (xy 72.263531 -284.67009) (xy 72.219774 -284.716687)
			(xy 72.171212 -284.75686) (xy 83.181188 -284.75686) (xy 83.185259 -284.701238) (xy 83.197385 -284.646801)
			(xy 83.217308 -284.59471) (xy 83.244604 -284.546075) (xy 83.27869 -284.501932) (xy 83.318839 -284.463223)
			(xy 83.364197 -284.430772) (xy 83.413797 -284.405271) (xy 83.466581 -284.387264) (xy 83.521424 -284.377134)
			(xy 83.577158 -284.375097) (xy 83.632595 -284.381197) (xy 83.686552 -284.395303) (xy 83.737881 -284.417115)
			(xy 83.785487 -284.446169) (xy 83.828355 -284.481844) (xy 83.865572 -284.523381) (xy 83.896345 -284.569894)
			(xy 83.920017 -284.620391) (xy 83.936085 -284.673798) (xy 83.944205 -284.728974) (xy 83.944714 -284.75686)
			(xy 83.944205 -284.784746) (xy 83.936085 -284.839922) (xy 83.920017 -284.893329) (xy 83.896345 -284.943826)
			(xy 83.865572 -284.990339) (xy 83.828355 -285.031876) (xy 83.785487 -285.067551) (xy 83.737881 -285.096605)
			(xy 83.686552 -285.118417) (xy 83.632595 -285.132523) (xy 83.577158 -285.138623) (xy 83.521424 -285.136586)
			(xy 83.466581 -285.126456) (xy 83.413797 -285.108449) (xy 83.364197 -285.082948) (xy 83.318839 -285.050497)
			(xy 83.27869 -285.011788) (xy 83.244604 -284.967645) (xy 83.217308 -284.91901) (xy 83.197385 -284.866919)
			(xy 83.185259 -284.812482) (xy 83.181188 -284.75686) (xy 72.171212 -284.75686) (xy 72.170521 -284.757432)
			(xy 72.11655 -284.791683) (xy 72.058711 -284.8189) (xy 71.997918 -284.838653) (xy 71.935128 -284.850631)
			(xy 71.871332 -284.854645) (xy 71.807536 -284.850631) (xy 71.744746 -284.838653) (xy 71.683953 -284.8189)
			(xy 71.626114 -284.791683) (xy 71.572143 -284.757432) (xy 71.52289 -284.716687) (xy 71.479133 -284.67009)
			(xy 71.44156 -284.618375) (xy 71.410766 -284.56236) (xy 71.387234 -284.502927) (xy 71.371337 -284.441013)
			(xy 71.363326 -284.377595) (xy 71.362824 -284.345634) (xy 44.601892 -284.345634) (xy 44.601892 -285.245979)
			(xy 47.75199 -285.245979) (xy 47.75199 -285.164869) (xy 47.75994 -285.08415) (xy 47.775763 -285.004599)
			(xy 47.799308 -284.926983) (xy 47.830347 -284.852047) (xy 47.868582 -284.780515) (xy 47.913644 -284.713075)
			(xy 47.965099 -284.650376) (xy 48.022452 -284.593023) (xy 48.085151 -284.541568) (xy 48.152591 -284.496506)
			(xy 48.224123 -284.458271) (xy 48.299059 -284.427232) (xy 48.376675 -284.403687) (xy 48.456226 -284.387864)
			(xy 48.536945 -284.379914) (xy 48.618055 -284.379914) (xy 48.698774 -284.387864) (xy 48.778325 -284.403687)
			(xy 48.855941 -284.427232) (xy 48.930877 -284.458271) (xy 49.002409 -284.496506) (xy 49.069849 -284.541568)
			(xy 49.132548 -284.593023) (xy 49.189901 -284.650376) (xy 49.241356 -284.713075) (xy 49.286418 -284.780515)
			(xy 49.324653 -284.852047) (xy 49.355692 -284.926983) (xy 49.379237 -285.004599) (xy 49.39506 -285.08415)
			(xy 49.40301 -285.164869) (xy 49.403508 -285.205424) (xy 49.40301 -285.245979) (xy 49.39506 -285.326698)
			(xy 49.379237 -285.406249) (xy 49.355692 -285.483865) (xy 49.324653 -285.558801) (xy 49.286418 -285.630333)
			(xy 49.241356 -285.697773) (xy 49.189901 -285.760472) (xy 49.132548 -285.817825) (xy 49.069849 -285.86928)
			(xy 49.002409 -285.914342) (xy 48.930877 -285.952577) (xy 48.855941 -285.983616) (xy 48.778325 -286.007161)
			(xy 48.698774 -286.022984) (xy 48.618055 -286.030934) (xy 48.536945 -286.030934) (xy 48.456226 -286.022984)
			(xy 48.376675 -286.007161) (xy 48.299059 -285.983616) (xy 48.224123 -285.952577) (xy 48.152591 -285.914342)
			(xy 48.085151 -285.86928) (xy 48.022452 -285.817825) (xy 47.965099 -285.760472) (xy 47.913644 -285.697773)
			(xy 47.868582 -285.630333) (xy 47.830347 -285.558801) (xy 47.799308 -285.483865) (xy 47.775763 -285.406249)
			(xy 47.75994 -285.326698) (xy 47.75199 -285.245979) (xy 44.601892 -285.245979) (xy 44.601892 -285.39567)
			(xy 43.90009 -286.097472) (xy 82.563714 -286.097472) (xy 82.567785 -286.04185) (xy 82.579911 -285.987413)
			(xy 82.599834 -285.935322) (xy 82.62713 -285.886687) (xy 82.661216 -285.842544) (xy 82.701365 -285.803835)
			(xy 82.746723 -285.771384) (xy 82.796323 -285.745883) (xy 82.849107 -285.727876) (xy 82.90395 -285.717746)
			(xy 82.959684 -285.715709) (xy 83.015121 -285.721809) (xy 83.069078 -285.735915) (xy 83.120407 -285.757727)
			(xy 83.168013 -285.786781) (xy 83.210881 -285.822456) (xy 83.248098 -285.863993) (xy 83.278871 -285.910506)
			(xy 83.302543 -285.961003) (xy 83.318611 -286.01441) (xy 83.326731 -286.069586) (xy 83.32724 -286.097472)
			(xy 83.326731 -286.125358) (xy 83.318611 -286.180534) (xy 83.302543 -286.233941) (xy 83.278871 -286.284438)
			(xy 83.248098 -286.330951) (xy 83.210881 -286.372488) (xy 83.168013 -286.408163) (xy 83.120407 -286.437217)
			(xy 83.069078 -286.459029) (xy 83.015121 -286.473135) (xy 82.959684 -286.479235) (xy 82.90395 -286.477198)
			(xy 82.849107 -286.467068) (xy 82.796323 -286.449061) (xy 82.746723 -286.42356) (xy 82.701365 -286.391109)
			(xy 82.661216 -286.3524) (xy 82.62713 -286.308257) (xy 82.599834 -286.259622) (xy 82.579911 -286.207531)
			(xy 82.567785 -286.153094) (xy 82.563714 -286.097472) (xy 43.90009 -286.097472) (xy 43.587924 -286.409638)
			(xy 40.976042 -286.409638) (xy 40.954113 -286.410096) (xy 40.910907 -286.41762) (xy 40.869634 -286.432452)
			(xy 40.831521 -286.454151) (xy 40.7977 -286.482072) (xy 40.769176 -286.515386) (xy 40.746797 -286.553104)
			(xy 40.731227 -286.594104) (xy 40.72293 -286.637169) (xy 40.72215 -286.681019) (xy 40.72509 -286.702754)
			(xy 40.726114 -286.71012) (xy 86.39887 -286.71012) (xy 86.402874 -286.510022) (xy 86.414881 -286.310244)
			(xy 86.434872 -286.111107) (xy 86.462814 -285.912929) (xy 86.498662 -285.716027) (xy 86.54236 -285.520718)
			(xy 86.593837 -285.327313) (xy 86.653011 -285.136123) (xy 86.719787 -284.947453) (xy 86.794059 -284.761606)
			(xy 86.875706 -284.578879) (xy 86.964599 -284.399566) (xy 87.060595 -284.223952) (xy 87.16354 -284.05232)
			(xy 87.27327 -283.884944) (xy 87.389608 -283.722093) (xy 87.512369 -283.564026) (xy 87.641356 -283.410998)
			(xy 87.776363 -283.263253) (xy 87.917172 -283.121027) (xy 88.063559 -282.98455) (xy 88.215289 -282.854038)
			(xy 88.37212 -282.729702) (xy 88.533799 -282.61174) (xy 88.700069 -282.500341) (xy 88.870662 -282.395684)
			(xy 89.045306 -282.297936) (xy 89.223722 -282.207253) (xy 89.405622 -282.123782) (xy 89.590717 -282.047655)
			(xy 89.778709 -281.978995) (xy 89.969298 -281.917911) (xy 90.162178 -281.864501) (xy 90.35704 -281.818852)
			(xy 90.553573 -281.781035) (xy 90.751462 -281.751111) (xy 90.950389 -281.729129) (xy 91.150037 -281.715124)
			(xy 91.350085 -281.709118) (xy 91.550213 -281.71112) (xy 91.750101 -281.721128) (xy 91.949428 -281.739125)
			(xy 92.147876 -281.765083) (xy 92.345126 -281.79896) (xy 92.540863 -281.840702) (xy 92.734773 -281.890241)
			(xy 92.926546 -281.947499) (xy 93.115875 -282.012384) (xy 93.302455 -282.084792) (xy 93.48599 -282.164608)
			(xy 93.666184 -282.251702) (xy 93.842749 -282.345936) (xy 94.015402 -282.447159) (xy 94.183867 -282.555209)
			(xy 94.347875 -282.669912) (xy 94.507162 -282.791086) (xy 94.661473 -282.918535) (xy 94.810561 -283.052056)
			(xy 94.954188 -283.191436) (xy 95.092124 -283.33645) (xy 95.224147 -283.486867) (xy 95.350046 -283.642445)
			(xy 95.46962 -283.802937) (xy 95.582676 -283.968083) (xy 95.689035 -284.137621) (xy 95.788526 -284.311279)
			(xy 95.880989 -284.488778) (xy 95.966276 -284.669834) (xy 96.044251 -284.854158) (xy 96.114788 -285.041454)
			(xy 96.177776 -285.231422) (xy 96.233113 -285.423758) (xy 96.28071 -285.618154) (xy 96.320491 -285.814299)
			(xy 96.352393 -286.011878) (xy 96.376364 -286.210575) (xy 96.392366 -286.410073) (xy 96.400373 -286.610051)
			(xy 96.400874 -286.71012) (xy 96.400373 -286.810189) (xy 96.392366 -287.010167) (xy 96.376364 -287.209665)
			(xy 96.352393 -287.408362) (xy 96.320491 -287.605941) (xy 96.28071 -287.802086) (xy 96.233113 -287.996482)
			(xy 96.177776 -288.188818) (xy 96.114788 -288.378786) (xy 96.044251 -288.566082) (xy 95.966276 -288.750406)
			(xy 95.880989 -288.931462) (xy 95.788526 -289.108961) (xy 95.689035 -289.282619) (xy 95.582676 -289.452157)
			(xy 95.46962 -289.617303) (xy 95.350046 -289.777795) (xy 95.224147 -289.933373) (xy 95.092124 -290.08379)
			(xy 94.954188 -290.228804) (xy 94.810561 -290.368184) (xy 94.661473 -290.501705) (xy 94.507162 -290.629154)
			(xy 94.347875 -290.750328) (xy 94.183867 -290.865031) (xy 94.015402 -290.973081) (xy 93.842749 -291.074304)
			(xy 93.666184 -291.168538) (xy 93.48599 -291.255632) (xy 93.302455 -291.335448) (xy 93.115875 -291.407856)
			(xy 92.926546 -291.472741) (xy 92.734773 -291.529999) (xy 92.540863 -291.579538) (xy 92.345126 -291.62128)
			(xy 92.147876 -291.655157) (xy 91.949428 -291.681115) (xy 91.750101 -291.699112) (xy 91.550213 -291.70912)
			(xy 91.350085 -291.711122) (xy 91.150037 -291.705116) (xy 90.950389 -291.691111) (xy 90.751462 -291.669129)
			(xy 90.553573 -291.639205) (xy 90.35704 -291.601388) (xy 90.162178 -291.555739) (xy 89.969298 -291.502329)
			(xy 89.778709 -291.441245) (xy 89.590717 -291.372585) (xy 89.405622 -291.296458) (xy 89.223722 -291.212987)
			(xy 89.045306 -291.122304) (xy 88.870662 -291.024556) (xy 88.700069 -290.919899) (xy 88.533799 -290.8085)
			(xy 88.37212 -290.690538) (xy 88.215289 -290.566202) (xy 88.063559 -290.43569) (xy 87.917172 -290.299213)
			(xy 87.776363 -290.156987) (xy 87.641356 -290.009242) (xy 87.512369 -289.856214) (xy 87.389608 -289.698147)
			(xy 87.27327 -289.535296) (xy 87.16354 -289.36792) (xy 87.060595 -289.196288) (xy 86.964599 -289.020674)
			(xy 86.875706 -288.841361) (xy 86.794059 -288.658634) (xy 86.719787 -288.472787) (xy 86.653011 -288.284117)
			(xy 86.593837 -288.092927) (xy 86.54236 -287.899522) (xy 86.498662 -287.704213) (xy 86.462814 -287.507311)
			(xy 86.434872 -287.309133) (xy 86.414881 -287.109996) (xy 86.402874 -286.910218) (xy 86.39887 -286.71012)
			(xy 40.726114 -286.71012) (xy 40.729507 -286.73452) (xy 40.730905 -286.798641) (xy 40.723807 -286.862382)
			(xy 40.708338 -286.924624) (xy 40.684771 -286.984272) (xy 40.653518 -287.040278) (xy 40.615131 -287.091656)
			(xy 40.570283 -287.137504) (xy 40.519764 -287.177016) (xy 40.464461 -287.209496) (xy 40.405347 -287.234373)
			(xy 40.343461 -287.251211) (xy 40.279892 -287.259712) (xy 40.247824 -287.260284) (xy 40.21836 -287.260284)
			(xy 40.195077 -287.260811) (xy 40.149292 -287.2693) (xy 40.105819 -287.285988) (xy 40.066114 -287.310316)
			(xy 40.031504 -287.341469) (xy 40.003148 -287.378405) (xy 39.981995 -287.419889) (xy 39.968752 -287.464532)
			(xy 39.963864 -287.510841) (xy 39.965122 -287.534096) (xy 39.966908 -287.562157) (xy 39.965022 -287.618356)
			(xy 39.956954 -287.674004) (xy 39.942802 -287.728425) (xy 39.933118 -287.754822) (xy 39.925574 -287.775882)
			(xy 39.917167 -287.819817) (xy 39.916582 -287.864545) (xy 39.923835 -287.908684) (xy 39.938704 -287.950872)
			(xy 39.960728 -287.989806) (xy 39.989228 -288.024283) (xy 40.023324 -288.053238) (xy 40.061962 -288.075777)
			(xy 40.103949 -288.091204) (xy 40.147988 -288.099043) (xy 40.170354 -288.0995) (xy 40.483028 -288.0995)
			(xy 40.514644 -288.100019) (xy 40.577334 -288.108276) (xy 40.638411 -288.124644) (xy 40.696828 -288.148844)
			(xy 40.751587 -288.180462) (xy 40.801751 -288.218957) (xy 40.846461 -288.26367) (xy 40.884953 -288.313836)
			(xy 40.916568 -288.368597) (xy 40.940765 -288.427016) (xy 40.95713 -288.488093) (xy 40.965383 -288.550784)
			(xy 40.965383 -288.614016) (xy 40.95713 -288.676707) (xy 40.940765 -288.737784) (xy 40.916568 -288.796203)
			(xy 40.884953 -288.850964) (xy 40.846461 -288.90113) (xy 40.801751 -288.945843) (xy 40.751587 -288.984338)
			(xy 40.696828 -289.015956) (xy 40.638411 -289.040156) (xy 40.577334 -289.056524) (xy 40.514644 -289.064781)
			(xy 40.483028 -289.065208) (xy 39.441882 -289.065208) (xy 39.110158 -288.733484) (xy 39.055548 -288.733484)
			(xy 39.055548 -288.67608) (xy 39.034466 -288.644076) (xy 39.017641 -288.617779) (xy 38.990162 -288.561723)
			(xy 38.970125 -288.502596) (xy 38.957863 -288.441383) (xy 38.95358 -288.3791) (xy 38.954964 -288.347912)
			(xy 38.955889 -288.324868) (xy 38.950392 -288.279082) (xy 38.936725 -288.235039) (xy 38.915339 -288.194184)
			(xy 38.886933 -288.157857) (xy 38.852441 -288.127249) (xy 38.812993 -288.103366) (xy 38.769885 -288.08699)
			(xy 38.724529 -288.078658) (xy 38.701472 -288.078164) (xy 36.397184 -288.078164) (xy 36.382357 -288.078606)
			(xy 36.353505 -288.085464) (xy 36.327008 -288.098783) (xy 36.304293 -288.117848) (xy 36.295076 -288.129472)
			(xy 36.269277 -288.163482) (xy 36.212443 -288.227187) (xy 36.150067 -288.285476) (xy 36.082665 -288.337871)
			(xy 36.01079 -288.38394) (xy 35.935034 -288.423303) (xy 35.856022 -288.455636) (xy 35.774404 -288.480673)
			(xy 35.690853 -288.498209) (xy 35.606056 -288.508097) (xy 35.520711 -288.510258) (xy 35.435522 -288.504672)
			(xy 35.35119 -288.491387) (xy 35.26841 -288.470512) (xy 35.187864 -288.442218) (xy 35.110213 -288.406738)
			(xy 35.036099 -288.364365) (xy 34.966132 -288.315448) (xy 34.900887 -288.260389) (xy 34.840903 -288.199642)
			(xy 34.786672 -288.133708) (xy 34.738642 -288.063128) (xy 34.697208 -287.988485) (xy 34.662711 -287.910394)
			(xy 34.635436 -287.829496) (xy 34.625026 -287.788096) (xy 34.620546 -287.771697) (xy 34.604197 -287.741906)
			(xy 34.580571 -287.71748) (xy 34.551339 -287.70015) (xy 34.518572 -287.691141) (xy 34.501582 -287.69056)
			(xy 31.497778 -287.69056) (xy 31.480775 -287.691092) (xy 31.447975 -287.700065) (xy 31.418715 -287.717393)
			(xy 31.39508 -287.741841) (xy 31.378751 -287.77167) (xy 31.374334 -287.788096) (xy 31.363737 -287.83039)
			(xy 31.335738 -287.912969) (xy 31.300213 -287.992601) (xy 31.257469 -288.068602) (xy 31.207872 -288.140319)
			(xy 31.151848 -288.207136) (xy 31.089878 -288.26848) (xy 31.022496 -288.323823) (xy 30.950279 -288.372689)
			(xy 30.873848 -288.41466) (xy 30.793859 -288.449375) (xy 30.711001 -288.476535) (xy 30.625983 -288.495907)
			(xy 30.539537 -288.507324) (xy 30.452406 -288.51069) (xy 30.365337 -288.505974) (xy 30.279078 -288.493217)
			(xy 30.194371 -288.472529) (xy 30.111944 -288.444088) (xy 30.032503 -288.408137) (xy 29.994352 -288.387028)
			(xy 29.9749 -288.376527) (xy 29.933268 -288.361677) (xy 29.889696 -288.354253) (xy 29.845495 -288.35448)
			(xy 29.802001 -288.362352) (xy 29.760525 -288.37763) (xy 29.722318 -288.399855) (xy 29.688532 -288.428354)
			(xy 29.660187 -288.46227) (xy 29.638137 -288.500578) (xy 29.623049 -288.542124) (xy 29.615376 -288.585654)
			(xy 29.614876 -288.607754) (xy 29.614876 -289.072066) (xy 29.61535 -289.094174) (xy 29.623 -289.137722)
			(xy 29.638074 -289.179288) (xy 29.660116 -289.217616) (xy 29.688462 -289.25155) (xy 29.722255 -289.280063)
			(xy 29.760474 -289.302294) (xy 29.801966 -289.317573) (xy 29.845475 -289.325438) (xy 29.88969 -289.32565)
			(xy 29.933273 -289.318204) (xy 29.974909 -289.303324) (xy 29.994352 -289.292792) (xy 30.032527 -289.271621)
			(xy 30.112065 -289.235636) (xy 30.194595 -289.207178) (xy 30.279409 -289.186492) (xy 30.365774 -289.173756)
			(xy 30.452948 -289.16908) (xy 30.54018 -289.172504) (xy 30.626719 -289.183999) (xy 30.711821 -289.203466)
			(xy 30.794751 -289.230737) (xy 30.874797 -289.265577) (xy 30.951269 -289.307686) (xy 31.023509 -289.356702)
			(xy 31.090895 -289.412203) (xy 31.152846 -289.473711) (xy 31.208829 -289.540696) (xy 31.258363 -289.612582)
			(xy 31.301021 -289.68875) (xy 31.336435 -289.768543) (xy 31.3643 -289.851276) (xy 31.384377 -289.936235)
			(xy 31.396494 -290.02269) (xy 31.400544 -290.109895) (xy 31.398525 -290.15336) (xy 34.599874 -290.15336)
			(xy 34.599874 -290.06646) (xy 34.607892 -289.979931) (xy 34.62386 -289.894511) (xy 34.647641 -289.810929)
			(xy 34.679033 -289.729897) (xy 34.717767 -289.652108) (xy 34.763514 -289.578224) (xy 34.815883 -289.508877)
			(xy 34.874427 -289.444657) (xy 34.938647 -289.386113) (xy 35.007994 -289.333744) (xy 35.081878 -289.287997)
			(xy 35.159667 -289.249263) (xy 35.240699 -289.217871) (xy 35.324281 -289.19409) (xy 35.409701 -289.178122)
			(xy 35.49623 -289.170104) (xy 35.58313 -289.170104) (xy 35.669659 -289.178122) (xy 35.755079 -289.19409)
			(xy 35.838661 -289.217871) (xy 35.919693 -289.249263) (xy 35.997482 -289.287997) (xy 36.071366 -289.333744)
			(xy 36.140713 -289.386113) (xy 36.204933 -289.444657) (xy 36.263477 -289.508877) (xy 36.315846 -289.578224)
			(xy 36.361593 -289.652108) (xy 36.400327 -289.729897) (xy 36.431719 -289.810929) (xy 36.4555 -289.894511)
			(xy 36.471468 -289.979931) (xy 36.479486 -290.06646) (xy 36.479988 -290.10991) (xy 36.479486 -290.15336)
			(xy 36.471468 -290.239889) (xy 36.4555 -290.325309) (xy 36.431719 -290.408891) (xy 36.400327 -290.489923)
			(xy 36.361593 -290.567712) (xy 36.315846 -290.641596) (xy 36.263477 -290.710943) (xy 36.204933 -290.775163)
			(xy 36.140713 -290.833707) (xy 36.071366 -290.886076) (xy 35.997482 -290.931823) (xy 35.919693 -290.970557)
			(xy 35.838661 -291.001949) (xy 35.755079 -291.02573) (xy 35.669659 -291.041698) (xy 35.58313 -291.049716)
			(xy 35.49623 -291.049716) (xy 35.409701 -291.041698) (xy 35.324281 -291.02573) (xy 35.240699 -291.001949)
			(xy 35.159667 -290.970557) (xy 35.081878 -290.931823) (xy 35.007994 -290.886076) (xy 34.938647 -290.833707)
			(xy 34.874427 -290.775163) (xy 34.815883 -290.710943) (xy 34.763514 -290.641596) (xy 34.717767 -290.567712)
			(xy 34.679033 -290.489923) (xy 34.647641 -290.408891) (xy 34.62386 -290.325309) (xy 34.607892 -290.239889)
			(xy 34.599874 -290.15336) (xy 31.398525 -290.15336) (xy 31.396494 -290.1971) (xy 31.384379 -290.283555)
			(xy 31.364303 -290.368514) (xy 31.336438 -290.451247) (xy 31.301025 -290.531041) (xy 31.258368 -290.60721)
			(xy 31.208835 -290.679096) (xy 31.152853 -290.746082) (xy 31.090902 -290.80759) (xy 31.023517 -290.863092)
			(xy 30.951278 -290.912109) (xy 30.874806 -290.954219) (xy 30.79476 -290.98906) (xy 30.71183 -291.016332)
			(xy 30.626729 -291.035799) (xy 30.54019 -291.047295) (xy 30.452958 -291.05072) (xy 30.365784 -291.046045)
			(xy 30.279418 -291.03331) (xy 30.194605 -291.012625) (xy 30.112074 -290.984168) (xy 30.032536 -290.948183)
			(xy 29.994352 -290.927028) (xy 29.9749 -290.916527) (xy 29.933268 -290.901677) (xy 29.889696 -290.894253)
			(xy 29.845495 -290.89448) (xy 29.802001 -290.902352) (xy 29.760525 -290.91763) (xy 29.722318 -290.939855)
			(xy 29.688532 -290.968354) (xy 29.660187 -291.00227) (xy 29.638137 -291.040578) (xy 29.623049 -291.082124)
			(xy 29.615376 -291.125654) (xy 29.614876 -291.147754) (xy 29.614876 -291.612066) (xy 29.61535 -291.634174)
			(xy 29.623 -291.677722) (xy 29.638074 -291.719288) (xy 29.660116 -291.757616) (xy 29.688462 -291.79155)
			(xy 29.722255 -291.820063) (xy 29.760474 -291.842294) (xy 29.801966 -291.857573) (xy 29.845475 -291.865438)
			(xy 29.88969 -291.86565) (xy 29.933273 -291.858204) (xy 29.974909 -291.843324) (xy 29.994352 -291.832792)
			(xy 30.032527 -291.811621) (xy 30.112065 -291.775636) (xy 30.194595 -291.747178) (xy 30.279409 -291.726492)
			(xy 30.365774 -291.713756) (xy 30.452948 -291.70908) (xy 30.54018 -291.712504) (xy 30.626719 -291.723999)
			(xy 30.711821 -291.743466) (xy 30.794751 -291.770737) (xy 30.874797 -291.805577) (xy 30.951269 -291.847686)
			(xy 31.023509 -291.896702) (xy 31.090895 -291.952203) (xy 31.152846 -292.013711) (xy 31.208829 -292.080696)
			(xy 31.258363 -292.152582) (xy 31.301021 -292.22875) (xy 31.336435 -292.308543) (xy 31.3643 -292.391276)
			(xy 31.384377 -292.476235) (xy 31.396494 -292.56269) (xy 31.400544 -292.649895) (xy 31.398525 -292.69336)
			(xy 34.599874 -292.69336) (xy 34.599874 -292.60646) (xy 34.607892 -292.519931) (xy 34.62386 -292.434511)
			(xy 34.647641 -292.350929) (xy 34.679033 -292.269897) (xy 34.717767 -292.192108) (xy 34.763514 -292.118224)
			(xy 34.815883 -292.048877) (xy 34.874427 -291.984657) (xy 34.938647 -291.926113) (xy 35.007994 -291.873744)
			(xy 35.081878 -291.827997) (xy 35.159667 -291.789263) (xy 35.240699 -291.757871) (xy 35.324281 -291.73409)
			(xy 35.409701 -291.718122) (xy 35.49623 -291.710104) (xy 35.58313 -291.710104) (xy 35.669659 -291.718122)
			(xy 35.755079 -291.73409) (xy 35.838661 -291.757871) (xy 35.919693 -291.789263) (xy 35.997482 -291.827997)
			(xy 36.071366 -291.873744) (xy 36.140713 -291.926113) (xy 36.204933 -291.984657) (xy 36.263477 -292.048877)
			(xy 36.315846 -292.118224) (xy 36.361593 -292.192108) (xy 36.400327 -292.269897) (xy 36.431719 -292.350929)
			(xy 36.4555 -292.434511) (xy 36.471468 -292.519931) (xy 36.479486 -292.60646) (xy 36.479988 -292.64991)
			(xy 36.479486 -292.69336) (xy 36.471468 -292.779889) (xy 36.4555 -292.865309) (xy 36.431719 -292.948891)
			(xy 36.400327 -293.029923) (xy 36.361593 -293.107712) (xy 36.315846 -293.181596) (xy 36.263477 -293.250943)
			(xy 36.204933 -293.315163) (xy 36.140713 -293.373707) (xy 36.071366 -293.426076) (xy 35.997482 -293.471823)
			(xy 35.919693 -293.510557) (xy 35.838661 -293.541949) (xy 35.755079 -293.56573) (xy 35.669659 -293.581698)
			(xy 35.58313 -293.589716) (xy 35.49623 -293.589716) (xy 35.409701 -293.581698) (xy 35.324281 -293.56573)
			(xy 35.240699 -293.541949) (xy 35.159667 -293.510557) (xy 35.081878 -293.471823) (xy 35.007994 -293.426076)
			(xy 34.938647 -293.373707) (xy 34.874427 -293.315163) (xy 34.815883 -293.250943) (xy 34.763514 -293.181596)
			(xy 34.717767 -293.107712) (xy 34.679033 -293.029923) (xy 34.647641 -292.948891) (xy 34.62386 -292.865309)
			(xy 34.607892 -292.779889) (xy 34.599874 -292.69336) (xy 31.398525 -292.69336) (xy 31.396494 -292.7371)
			(xy 31.384379 -292.823555) (xy 31.364303 -292.908514) (xy 31.336438 -292.991247) (xy 31.301025 -293.071041)
			(xy 31.258368 -293.14721) (xy 31.208835 -293.219096) (xy 31.152853 -293.286082) (xy 31.090902 -293.34759)
			(xy 31.023517 -293.403092) (xy 30.951278 -293.452109) (xy 30.874806 -293.494219) (xy 30.79476 -293.52906)
			(xy 30.71183 -293.556332) (xy 30.626729 -293.575799) (xy 30.54019 -293.587295) (xy 30.452958 -293.59072)
			(xy 30.365784 -293.586045) (xy 30.279418 -293.57331) (xy 30.194605 -293.552625) (xy 30.112074 -293.524168)
			(xy 30.032536 -293.488183) (xy 29.994352 -293.467028) (xy 29.9749 -293.456527) (xy 29.933268 -293.441677)
			(xy 29.889696 -293.434253) (xy 29.845495 -293.43448) (xy 29.802001 -293.442352) (xy 29.760525 -293.45763)
			(xy 29.722318 -293.479855) (xy 29.688532 -293.508354) (xy 29.660187 -293.54227) (xy 29.638137 -293.580578)
			(xy 29.623049 -293.622124) (xy 29.615376 -293.665654) (xy 29.614876 -293.687754) (xy 29.614876 -294.152066)
			(xy 29.61535 -294.174174) (xy 29.623 -294.217722) (xy 29.638074 -294.259288) (xy 29.660116 -294.297616)
			(xy 29.688462 -294.33155) (xy 29.722255 -294.360063) (xy 29.760474 -294.382294) (xy 29.801966 -294.397573)
			(xy 29.845475 -294.405438) (xy 29.88969 -294.40565) (xy 29.933273 -294.398204) (xy 29.974909 -294.383324)
			(xy 29.994352 -294.372792) (xy 30.032527 -294.351621) (xy 30.112065 -294.315636) (xy 30.194595 -294.287178)
			(xy 30.279409 -294.266492) (xy 30.365774 -294.253756) (xy 30.452948 -294.24908) (xy 30.54018 -294.252504)
			(xy 30.626719 -294.263999) (xy 30.711821 -294.283466) (xy 30.794751 -294.310737) (xy 30.874797 -294.345577)
			(xy 30.951269 -294.387686) (xy 31.023509 -294.436702) (xy 31.090895 -294.492203) (xy 31.152846 -294.553711)
			(xy 31.208829 -294.620696) (xy 31.258363 -294.692582) (xy 31.301021 -294.76875) (xy 31.336435 -294.848543)
			(xy 31.3643 -294.931276) (xy 31.384377 -295.016235) (xy 31.396494 -295.10269) (xy 31.400544 -295.189895)
			(xy 31.398525 -295.23336) (xy 34.599874 -295.23336) (xy 34.599874 -295.14646) (xy 34.607892 -295.059931)
			(xy 34.62386 -294.974511) (xy 34.647641 -294.890929) (xy 34.679033 -294.809897) (xy 34.717767 -294.732108)
			(xy 34.763514 -294.658224) (xy 34.815883 -294.588877) (xy 34.874427 -294.524657) (xy 34.938647 -294.466113)
			(xy 35.007994 -294.413744) (xy 35.081878 -294.367997) (xy 35.159667 -294.329263) (xy 35.240699 -294.297871)
			(xy 35.324281 -294.27409) (xy 35.409701 -294.258122) (xy 35.49623 -294.250104) (xy 35.58313 -294.250104)
			(xy 35.669659 -294.258122) (xy 35.755079 -294.27409) (xy 35.838661 -294.297871) (xy 35.919693 -294.329263)
			(xy 35.997482 -294.367997) (xy 36.071366 -294.413744) (xy 36.140713 -294.466113) (xy 36.204933 -294.524657)
			(xy 36.263477 -294.588877) (xy 36.315846 -294.658224) (xy 36.361593 -294.732108) (xy 36.400327 -294.809897)
			(xy 36.431719 -294.890929) (xy 36.4555 -294.974511) (xy 36.471468 -295.059931) (xy 36.479486 -295.14646)
			(xy 36.479988 -295.18991) (xy 36.479486 -295.23336) (xy 36.478201 -295.247231) (xy 78.899273 -295.247231)
			(xy 78.899273 -295.183969) (xy 78.90753 -295.121247) (xy 78.923903 -295.06014) (xy 78.948111 -295.001693)
			(xy 78.979741 -294.946905) (xy 79.018251 -294.896714) (xy 79.062982 -294.851978) (xy 79.11317 -294.813464)
			(xy 79.167955 -294.781829) (xy 79.2264 -294.757616) (xy 79.287506 -294.741238) (xy 79.350227 -294.732976)
			(xy 79.381858 -294.732456) (xy 80.532732 -294.732456) (xy 80.561 -294.732876) (xy 80.617144 -294.739529)
			(xy 80.672129 -294.752683) (xy 80.725205 -294.772158) (xy 80.775649 -294.797689) (xy 80.799432 -294.812974)
			(xy 80.831436 -294.834056) (xy 80.99425 -294.834056) (xy 81.028032 -294.808656) (xy 81.054514 -294.789466)
			(xy 81.111449 -294.757288) (xy 81.172036 -294.732666) (xy 81.235278 -294.716007) (xy 81.300133 -294.707584)
			(xy 81.332832 -294.707056) (xy 82.752184 -294.707056) (xy 82.784145 -294.707608) (xy 82.847562 -294.715618)
			(xy 82.909476 -294.731513) (xy 82.968909 -294.755042) (xy 83.024925 -294.785835) (xy 83.076639 -294.823407)
			(xy 83.123236 -294.867163) (xy 83.163982 -294.916415) (xy 83.198234 -294.970385) (xy 83.225451 -295.028223)
			(xy 83.245204 -295.089015) (xy 83.257182 -295.151805) (xy 83.261196 -295.2156) (xy 83.257182 -295.279395)
			(xy 83.245204 -295.342185) (xy 83.225451 -295.402977) (xy 83.198234 -295.460815) (xy 83.163982 -295.514785)
			(xy 83.123236 -295.564037) (xy 83.076639 -295.607793) (xy 83.024925 -295.645365) (xy 82.968909 -295.676158)
			(xy 82.909476 -295.699687) (xy 82.847562 -295.715582) (xy 82.784145 -295.723592) (xy 82.752184 -295.724072)
			(xy 81.332832 -295.724072) (xy 81.300129 -295.723587) (xy 81.235265 -295.715185) (xy 81.172015 -295.698529)
			(xy 81.111426 -295.673894) (xy 81.054498 -295.641688) (xy 81.028032 -295.622472) (xy 80.99425 -295.597072)
			(xy 80.831436 -295.597072) (xy 80.799432 -295.618154) (xy 80.775663 -295.633464) (xy 80.725225 -295.659015)
			(xy 80.672146 -295.678494) (xy 80.617154 -295.691636) (xy 80.561002 -295.698261) (xy 80.532732 -295.698672)
			(xy 79.381858 -295.698672) (xy 79.350227 -295.698224) (xy 79.287506 -295.689962) (xy 79.2264 -295.673584)
			(xy 79.167955 -295.649371) (xy 79.11317 -295.617736) (xy 79.062982 -295.579222) (xy 79.018251 -295.534486)
			(xy 78.979741 -295.484295) (xy 78.948111 -295.429507) (xy 78.923903 -295.37106) (xy 78.90753 -295.309953)
			(xy 78.899273 -295.247231) (xy 36.478201 -295.247231) (xy 36.471468 -295.319889) (xy 36.4555 -295.405309)
			(xy 36.431719 -295.488891) (xy 36.400327 -295.569923) (xy 36.361593 -295.647712) (xy 36.315846 -295.721596)
			(xy 36.263477 -295.790943) (xy 36.204933 -295.855163) (xy 36.140713 -295.913707) (xy 36.071366 -295.966076)
			(xy 35.997482 -296.011823) (xy 35.919693 -296.050557) (xy 35.838661 -296.081949) (xy 35.755079 -296.10573)
			(xy 35.669659 -296.121698) (xy 35.58313 -296.129716) (xy 35.49623 -296.129716) (xy 35.409701 -296.121698)
			(xy 35.324281 -296.10573) (xy 35.240699 -296.081949) (xy 35.159667 -296.050557) (xy 35.081878 -296.011823)
			(xy 35.007994 -295.966076) (xy 34.938647 -295.913707) (xy 34.874427 -295.855163) (xy 34.815883 -295.790943)
			(xy 34.763514 -295.721596) (xy 34.717767 -295.647712) (xy 34.679033 -295.569923) (xy 34.647641 -295.488891)
			(xy 34.62386 -295.405309) (xy 34.607892 -295.319889) (xy 34.599874 -295.23336) (xy 31.398525 -295.23336)
			(xy 31.396494 -295.2771) (xy 31.384379 -295.363555) (xy 31.364303 -295.448514) (xy 31.336438 -295.531247)
			(xy 31.301025 -295.611041) (xy 31.258368 -295.68721) (xy 31.208835 -295.759096) (xy 31.152853 -295.826082)
			(xy 31.090902 -295.88759) (xy 31.023517 -295.943092) (xy 30.951278 -295.992109) (xy 30.874806 -296.034219)
			(xy 30.79476 -296.06906) (xy 30.71183 -296.096332) (xy 30.626729 -296.115799) (xy 30.54019 -296.127295)
			(xy 30.452958 -296.13072) (xy 30.365784 -296.126045) (xy 30.279418 -296.11331) (xy 30.194605 -296.092625)
			(xy 30.112074 -296.064168) (xy 30.032536 -296.028183) (xy 29.994352 -296.007028) (xy 29.9749 -295.996527)
			(xy 29.933268 -295.981677) (xy 29.889696 -295.974253) (xy 29.845495 -295.97448) (xy 29.802001 -295.982352)
			(xy 29.760525 -295.99763) (xy 29.722318 -296.019855) (xy 29.688532 -296.048354) (xy 29.660187 -296.08227)
			(xy 29.638137 -296.120578) (xy 29.623049 -296.162124) (xy 29.615376 -296.205654) (xy 29.614876 -296.227754)
			(xy 29.614876 -296.692066) (xy 29.61535 -296.714174) (xy 29.623 -296.757722) (xy 29.638074 -296.799288)
			(xy 29.660116 -296.837616) (xy 29.688462 -296.87155) (xy 29.722255 -296.900063) (xy 29.760474 -296.922294)
			(xy 29.801966 -296.937573) (xy 29.845475 -296.945438) (xy 29.88969 -296.94565) (xy 29.933273 -296.938204)
			(xy 29.974909 -296.923324) (xy 29.994352 -296.912792) (xy 30.032527 -296.891621) (xy 30.112065 -296.855636)
			(xy 30.194595 -296.827178) (xy 30.279409 -296.806492) (xy 30.365774 -296.793756) (xy 30.452948 -296.78908)
			(xy 30.54018 -296.792504) (xy 30.626719 -296.803999) (xy 30.711821 -296.823466) (xy 30.794751 -296.850737)
			(xy 30.874797 -296.885577) (xy 30.951269 -296.927686) (xy 31.023509 -296.976702) (xy 31.090895 -297.032203)
			(xy 31.152846 -297.093711) (xy 31.208829 -297.160696) (xy 31.258363 -297.232582) (xy 31.301021 -297.30875)
			(xy 31.336435 -297.388543) (xy 31.3643 -297.471276) (xy 31.384377 -297.556235) (xy 31.396494 -297.64269)
			(xy 31.400544 -297.729895) (xy 31.398525 -297.77336) (xy 34.599874 -297.77336) (xy 34.599874 -297.68646)
			(xy 34.607892 -297.599931) (xy 34.62386 -297.514511) (xy 34.647641 -297.430929) (xy 34.679033 -297.349897)
			(xy 34.717767 -297.272108) (xy 34.763514 -297.198224) (xy 34.815883 -297.128877) (xy 34.874427 -297.064657)
			(xy 34.938647 -297.006113) (xy 35.007994 -296.953744) (xy 35.081878 -296.907997) (xy 35.159667 -296.869263)
			(xy 35.240699 -296.837871) (xy 35.324281 -296.81409) (xy 35.409701 -296.798122) (xy 35.49623 -296.790104)
			(xy 35.58313 -296.790104) (xy 35.669659 -296.798122) (xy 35.755079 -296.81409) (xy 35.838661 -296.837871)
			(xy 35.919693 -296.869263) (xy 35.997482 -296.907997) (xy 36.071366 -296.953744) (xy 36.094295 -296.971059)
			(xy 38.258488 -296.971059) (xy 38.258488 -296.899737) (xy 38.266474 -296.828863) (xy 38.282344 -296.759328)
			(xy 38.305901 -296.692008) (xy 38.336846 -296.627749) (xy 38.374792 -296.567358) (xy 38.419261 -296.511596)
			(xy 38.469694 -296.461163) (xy 38.525456 -296.416694) (xy 38.585847 -296.378748) (xy 38.650106 -296.347803)
			(xy 38.717426 -296.324246) (xy 38.786961 -296.308376) (xy 38.857835 -296.30039) (xy 38.929157 -296.30039)
			(xy 39.000031 -296.308376) (xy 39.069566 -296.324246) (xy 39.136886 -296.347803) (xy 39.201145 -296.378748)
			(xy 39.261536 -296.416694) (xy 39.317298 -296.461163) (xy 39.367731 -296.511596) (xy 39.4122 -296.567358)
			(xy 39.450146 -296.627749) (xy 39.481091 -296.692008) (xy 39.504648 -296.759328) (xy 39.520518 -296.828863)
			(xy 39.528504 -296.899737) (xy 39.529004 -296.935398) (xy 39.528504 -296.971059) (xy 40.1452 -296.971059)
			(xy 40.1452 -296.899737) (xy 40.153186 -296.828863) (xy 40.169056 -296.759328) (xy 40.192613 -296.692008)
			(xy 40.223558 -296.627749) (xy 40.261504 -296.567358) (xy 40.305973 -296.511596) (xy 40.356406 -296.461163)
			(xy 40.412168 -296.416694) (xy 40.472559 -296.378748) (xy 40.536818 -296.347803) (xy 40.604138 -296.324246)
			(xy 40.673673 -296.308376) (xy 40.744547 -296.30039) (xy 40.815869 -296.30039) (xy 40.886743 -296.308376)
			(xy 40.956278 -296.324246) (xy 41.023598 -296.347803) (xy 41.087857 -296.378748) (xy 41.148248 -296.416694)
			(xy 41.20401 -296.461163) (xy 41.254443 -296.511596) (xy 41.298912 -296.567358) (xy 41.336858 -296.627749)
			(xy 41.367803 -296.692008) (xy 41.39136 -296.759328) (xy 41.40723 -296.828863) (xy 41.415216 -296.899737)
			(xy 41.415716 -296.935398) (xy 41.415216 -296.971059) (xy 41.40723 -297.041933) (xy 41.39136 -297.111468)
			(xy 41.367803 -297.178788) (xy 41.336858 -297.243047) (xy 41.298912 -297.303438) (xy 41.254443 -297.3592)
			(xy 41.20401 -297.409633) (xy 41.148248 -297.454102) (xy 41.087857 -297.492048) (xy 41.023598 -297.522993)
			(xy 40.956278 -297.54655) (xy 40.886743 -297.56242) (xy 40.815869 -297.570406) (xy 40.744547 -297.570406)
			(xy 40.673673 -297.56242) (xy 40.604138 -297.54655) (xy 40.536818 -297.522993) (xy 40.472559 -297.492048)
			(xy 40.412168 -297.454102) (xy 40.356406 -297.409633) (xy 40.305973 -297.3592) (xy 40.261504 -297.303438)
			(xy 40.223558 -297.243047) (xy 40.192613 -297.178788) (xy 40.169056 -297.111468) (xy 40.153186 -297.041933)
			(xy 40.1452 -296.971059) (xy 39.528504 -296.971059) (xy 39.520518 -297.041933) (xy 39.504648 -297.111468)
			(xy 39.481091 -297.178788) (xy 39.450146 -297.243047) (xy 39.4122 -297.303438) (xy 39.367731 -297.3592)
			(xy 39.317298 -297.409633) (xy 39.261536 -297.454102) (xy 39.201145 -297.492048) (xy 39.136886 -297.522993)
			(xy 39.069566 -297.54655) (xy 39.000031 -297.56242) (xy 38.929157 -297.570406) (xy 38.857835 -297.570406)
			(xy 38.786961 -297.56242) (xy 38.717426 -297.54655) (xy 38.650106 -297.522993) (xy 38.585847 -297.492048)
			(xy 38.525456 -297.454102) (xy 38.469694 -297.409633) (xy 38.419261 -297.3592) (xy 38.374792 -297.303438)
			(xy 38.336846 -297.243047) (xy 38.305901 -297.178788) (xy 38.282344 -297.111468) (xy 38.266474 -297.041933)
			(xy 38.258488 -296.971059) (xy 36.094295 -296.971059) (xy 36.140713 -297.006113) (xy 36.204933 -297.064657)
			(xy 36.263477 -297.128877) (xy 36.315846 -297.198224) (xy 36.361593 -297.272108) (xy 36.400327 -297.349897)
			(xy 36.431719 -297.430929) (xy 36.4555 -297.514511) (xy 36.471468 -297.599931) (xy 36.479486 -297.68646)
			(xy 36.479988 -297.72991) (xy 36.479486 -297.77336) (xy 36.471468 -297.859889) (xy 36.459515 -297.923829)
			(xy 78.942725 -297.923829) (xy 78.942725 -297.860571) (xy 78.950982 -297.797853) (xy 78.967354 -297.73675)
			(xy 78.991562 -297.678307) (xy 79.023191 -297.623523) (xy 79.0617 -297.573336) (xy 79.10643 -297.528605)
			(xy 79.156616 -297.490095) (xy 79.211399 -297.458465) (xy 79.269842 -297.434257) (xy 79.330945 -297.417883)
			(xy 79.393663 -297.409625) (xy 79.425292 -297.409108) (xy 80.546956 -297.409108) (xy 80.57525 -297.409517)
			(xy 80.631451 -297.416136) (xy 80.686492 -297.429278) (xy 80.739621 -297.448762) (xy 80.790109 -297.474321)
			(xy 80.81391 -297.489626) (xy 80.84566 -297.510708) (xy 80.903064 -297.510708) (xy 80.903064 -297.565826)
			(xy 80.922938 -297.588137) (xy 80.957571 -297.636828) (xy 80.985935 -297.689418) (xy 81.007595 -297.745106)
			(xy 81.02222 -297.80304) (xy 81.029589 -297.862336) (xy 81.029588 -297.922088) (xy 81.022216 -297.981383)
			(xy 81.007587 -298.039316) (xy 80.985925 -298.095003) (xy 80.957559 -298.147592) (xy 80.922923 -298.196282)
			(xy 80.903064 -298.218606) (xy 80.903064 -298.273724) (xy 80.84566 -298.273724) (xy 80.81391 -298.294806)
			(xy 80.790117 -298.310125) (xy 80.739629 -298.335688) (xy 80.686498 -298.355172) (xy 80.631454 -298.36831)
			(xy 80.575251 -298.374922) (xy 80.546956 -298.375324) (xy 79.425292 -298.375324) (xy 79.393663 -298.374775)
			(xy 79.330945 -298.366517) (xy 79.269842 -298.350143) (xy 79.211399 -298.325935) (xy 79.156616 -298.294305)
			(xy 79.10643 -298.255795) (xy 79.0617 -298.211064) (xy 79.023191 -298.160877) (xy 78.991562 -298.106093)
			(xy 78.967354 -298.04765) (xy 78.950982 -297.986547) (xy 78.942725 -297.923829) (xy 36.459515 -297.923829)
			(xy 36.4555 -297.945309) (xy 36.431719 -298.028891) (xy 36.400327 -298.109923) (xy 36.361593 -298.187712)
			(xy 36.315846 -298.261596) (xy 36.263477 -298.330943) (xy 36.204933 -298.395163) (xy 36.140713 -298.453707)
			(xy 36.071366 -298.506076) (xy 35.997482 -298.551823) (xy 35.919693 -298.590557) (xy 35.838661 -298.621949)
			(xy 35.755079 -298.64573) (xy 35.669659 -298.661698) (xy 35.58313 -298.669716) (xy 35.49623 -298.669716)
			(xy 35.409701 -298.661698) (xy 35.324281 -298.64573) (xy 35.240699 -298.621949) (xy 35.159667 -298.590557)
			(xy 35.081878 -298.551823) (xy 35.007994 -298.506076) (xy 34.938647 -298.453707) (xy 34.874427 -298.395163)
			(xy 34.815883 -298.330943) (xy 34.763514 -298.261596) (xy 34.717767 -298.187712) (xy 34.679033 -298.109923)
			(xy 34.647641 -298.028891) (xy 34.62386 -297.945309) (xy 34.607892 -297.859889) (xy 34.599874 -297.77336)
			(xy 31.398525 -297.77336) (xy 31.396494 -297.8171) (xy 31.384379 -297.903555) (xy 31.364303 -297.988514)
			(xy 31.336438 -298.071247) (xy 31.301025 -298.151041) (xy 31.258368 -298.22721) (xy 31.208835 -298.299096)
			(xy 31.152853 -298.366082) (xy 31.090902 -298.42759) (xy 31.023517 -298.483092) (xy 30.951278 -298.532109)
			(xy 30.874806 -298.574219) (xy 30.79476 -298.60906) (xy 30.71183 -298.636332) (xy 30.626729 -298.655799)
			(xy 30.54019 -298.667295) (xy 30.452958 -298.67072) (xy 30.365784 -298.666045) (xy 30.279418 -298.65331)
			(xy 30.194605 -298.632625) (xy 30.112074 -298.604168) (xy 30.032536 -298.568183) (xy 29.994352 -298.547028)
			(xy 29.9749 -298.536527) (xy 29.933268 -298.521677) (xy 29.889696 -298.514253) (xy 29.845495 -298.51448)
			(xy 29.802001 -298.522352) (xy 29.760525 -298.53763) (xy 29.722318 -298.559855) (xy 29.688532 -298.588354)
			(xy 29.660187 -298.62227) (xy 29.638137 -298.660578) (xy 29.623049 -298.702124) (xy 29.615376 -298.745654)
			(xy 29.614876 -298.767754) (xy 29.614876 -298.804685) (xy 38.258488 -298.804685) (xy 38.258488 -298.733363)
			(xy 38.266474 -298.662489) (xy 38.282344 -298.592954) (xy 38.305901 -298.525634) (xy 38.336846 -298.461375)
			(xy 38.374792 -298.400984) (xy 38.419261 -298.345222) (xy 38.469694 -298.294789) (xy 38.525456 -298.25032)
			(xy 38.585847 -298.212374) (xy 38.650106 -298.181429) (xy 38.717426 -298.157872) (xy 38.786961 -298.142002)
			(xy 38.857835 -298.134016) (xy 38.929157 -298.134016) (xy 39.000031 -298.142002) (xy 39.069566 -298.157872)
			(xy 39.136886 -298.181429) (xy 39.201145 -298.212374) (xy 39.261536 -298.25032) (xy 39.317298 -298.294789)
			(xy 39.367731 -298.345222) (xy 39.4122 -298.400984) (xy 39.450146 -298.461375) (xy 39.481091 -298.525634)
			(xy 39.504648 -298.592954) (xy 39.520518 -298.662489) (xy 39.528504 -298.733363) (xy 39.529004 -298.769024)
			(xy 39.528504 -298.804685) (xy 40.1452 -298.804685) (xy 40.1452 -298.733363) (xy 40.153186 -298.662489)
			(xy 40.169056 -298.592954) (xy 40.192613 -298.525634) (xy 40.223558 -298.461375) (xy 40.261504 -298.400984)
			(xy 40.305973 -298.345222) (xy 40.356406 -298.294789) (xy 40.412168 -298.25032) (xy 40.472559 -298.212374)
			(xy 40.536818 -298.181429) (xy 40.604138 -298.157872) (xy 40.673673 -298.142002) (xy 40.744547 -298.134016)
			(xy 40.815869 -298.134016) (xy 40.886743 -298.142002) (xy 40.956278 -298.157872) (xy 41.023598 -298.181429)
			(xy 41.087857 -298.212374) (xy 41.148248 -298.25032) (xy 41.20401 -298.294789) (xy 41.254443 -298.345222)
			(xy 41.298912 -298.400984) (xy 41.336858 -298.461375) (xy 41.367803 -298.525634) (xy 41.39136 -298.592954)
			(xy 41.40723 -298.662489) (xy 41.415216 -298.733363) (xy 41.415716 -298.769024) (xy 41.415216 -298.804685)
			(xy 42.386242 -298.804685) (xy 42.386242 -298.733363) (xy 42.394228 -298.662489) (xy 42.410098 -298.592954)
			(xy 42.433655 -298.525634) (xy 42.4646 -298.461375) (xy 42.502546 -298.400984) (xy 42.547015 -298.345222)
			(xy 42.597448 -298.294789) (xy 42.65321 -298.25032) (xy 42.713601 -298.212374) (xy 42.77786 -298.181429)
			(xy 42.84518 -298.157872) (xy 42.914715 -298.142002) (xy 42.985589 -298.134016) (xy 43.056911 -298.134016)
			(xy 43.127785 -298.142002) (xy 43.19732 -298.157872) (xy 43.26464 -298.181429) (xy 43.328899 -298.212374)
			(xy 43.38929 -298.25032) (xy 43.445052 -298.294789) (xy 43.495485 -298.345222) (xy 43.539954 -298.400984)
			(xy 43.5779 -298.461375) (xy 43.608845 -298.525634) (xy 43.632402 -298.592954) (xy 43.648272 -298.662489)
			(xy 43.656258 -298.733363) (xy 43.656758 -298.769024) (xy 43.656258 -298.804685) (xy 44.290226 -298.804685)
			(xy 44.290226 -298.733363) (xy 44.298212 -298.662489) (xy 44.314082 -298.592954) (xy 44.337639 -298.525634)
			(xy 44.368584 -298.461375) (xy 44.40653 -298.400984) (xy 44.450999 -298.345222) (xy 44.501432 -298.294789)
			(xy 44.557194 -298.25032) (xy 44.617585 -298.212374) (xy 44.681844 -298.181429) (xy 44.749164 -298.157872)
			(xy 44.818699 -298.142002) (xy 44.889573 -298.134016) (xy 44.960895 -298.134016) (xy 45.031769 -298.142002)
			(xy 45.101304 -298.157872) (xy 45.168624 -298.181429) (xy 45.232883 -298.212374) (xy 45.293274 -298.25032)
			(xy 45.349036 -298.294789) (xy 45.399469 -298.345222) (xy 45.443938 -298.400984) (xy 45.481884 -298.461375)
			(xy 45.512829 -298.525634) (xy 45.536386 -298.592954) (xy 45.552256 -298.662489) (xy 45.560242 -298.733363)
			(xy 45.560742 -298.769024) (xy 45.560242 -298.804685) (xy 45.552256 -298.875559) (xy 45.536386 -298.945094)
			(xy 45.512829 -299.012414) (xy 45.481884 -299.076673) (xy 45.443938 -299.137064) (xy 45.399469 -299.192826)
			(xy 45.349036 -299.243259) (xy 45.293274 -299.287728) (xy 45.232883 -299.325674) (xy 45.168624 -299.356619)
			(xy 45.101304 -299.380176) (xy 45.031769 -299.396046) (xy 44.960895 -299.404032) (xy 44.889573 -299.404032)
			(xy 44.818699 -299.396046) (xy 44.749164 -299.380176) (xy 44.681844 -299.356619) (xy 44.617585 -299.325674)
			(xy 44.557194 -299.287728) (xy 44.501432 -299.243259) (xy 44.450999 -299.192826) (xy 44.40653 -299.137064)
			(xy 44.368584 -299.076673) (xy 44.337639 -299.012414) (xy 44.314082 -298.945094) (xy 44.298212 -298.875559)
			(xy 44.290226 -298.804685) (xy 43.656258 -298.804685) (xy 43.648272 -298.875559) (xy 43.632402 -298.945094)
			(xy 43.608845 -299.012414) (xy 43.5779 -299.076673) (xy 43.539954 -299.137064) (xy 43.495485 -299.192826)
			(xy 43.445052 -299.243259) (xy 43.38929 -299.287728) (xy 43.328899 -299.325674) (xy 43.26464 -299.356619)
			(xy 43.19732 -299.380176) (xy 43.127785 -299.396046) (xy 43.056911 -299.404032) (xy 42.985589 -299.404032)
			(xy 42.914715 -299.396046) (xy 42.84518 -299.380176) (xy 42.77786 -299.356619) (xy 42.713601 -299.325674)
			(xy 42.65321 -299.287728) (xy 42.597448 -299.243259) (xy 42.547015 -299.192826) (xy 42.502546 -299.137064)
			(xy 42.4646 -299.076673) (xy 42.433655 -299.012414) (xy 42.410098 -298.945094) (xy 42.394228 -298.875559)
			(xy 42.386242 -298.804685) (xy 41.415216 -298.804685) (xy 41.40723 -298.875559) (xy 41.39136 -298.945094)
			(xy 41.367803 -299.012414) (xy 41.336858 -299.076673) (xy 41.298912 -299.137064) (xy 41.254443 -299.192826)
			(xy 41.20401 -299.243259) (xy 41.148248 -299.287728) (xy 41.087857 -299.325674) (xy 41.023598 -299.356619)
			(xy 40.956278 -299.380176) (xy 40.886743 -299.396046) (xy 40.815869 -299.404032) (xy 40.744547 -299.404032)
			(xy 40.673673 -299.396046) (xy 40.604138 -299.380176) (xy 40.536818 -299.356619) (xy 40.472559 -299.325674)
			(xy 40.412168 -299.287728) (xy 40.356406 -299.243259) (xy 40.305973 -299.192826) (xy 40.261504 -299.137064)
			(xy 40.223558 -299.076673) (xy 40.192613 -299.012414) (xy 40.169056 -298.945094) (xy 40.153186 -298.875559)
			(xy 40.1452 -298.804685) (xy 39.528504 -298.804685) (xy 39.520518 -298.875559) (xy 39.504648 -298.945094)
			(xy 39.481091 -299.012414) (xy 39.450146 -299.076673) (xy 39.4122 -299.137064) (xy 39.367731 -299.192826)
			(xy 39.317298 -299.243259) (xy 39.261536 -299.287728) (xy 39.201145 -299.325674) (xy 39.136886 -299.356619)
			(xy 39.069566 -299.380176) (xy 39.000031 -299.396046) (xy 38.929157 -299.404032) (xy 38.857835 -299.404032)
			(xy 38.786961 -299.396046) (xy 38.717426 -299.380176) (xy 38.650106 -299.356619) (xy 38.585847 -299.325674)
			(xy 38.525456 -299.287728) (xy 38.469694 -299.243259) (xy 38.419261 -299.192826) (xy 38.374792 -299.137064)
			(xy 38.336846 -299.076673) (xy 38.305901 -299.012414) (xy 38.282344 -298.945094) (xy 38.266474 -298.875559)
			(xy 38.258488 -298.804685) (xy 29.614876 -298.804685) (xy 29.614876 -299.232066) (xy 29.61535 -299.254174)
			(xy 29.623 -299.297722) (xy 29.638074 -299.339288) (xy 29.660116 -299.377616) (xy 29.688462 -299.41155)
			(xy 29.722255 -299.440063) (xy 29.760474 -299.462294) (xy 29.801966 -299.477573) (xy 29.845475 -299.485438)
			(xy 29.88969 -299.48565) (xy 29.933273 -299.478204) (xy 29.974909 -299.463324) (xy 29.994352 -299.452792)
			(xy 30.032527 -299.431621) (xy 30.112065 -299.395636) (xy 30.194595 -299.367178) (xy 30.279409 -299.346492)
			(xy 30.365774 -299.333756) (xy 30.452948 -299.32908) (xy 30.54018 -299.332504) (xy 30.626719 -299.343999)
			(xy 30.711821 -299.363466) (xy 30.794751 -299.390737) (xy 30.874797 -299.425577) (xy 30.951269 -299.467686)
			(xy 31.023509 -299.516702) (xy 31.090895 -299.572203) (xy 31.152846 -299.633711) (xy 31.208829 -299.700696)
			(xy 31.258363 -299.772582) (xy 31.301021 -299.84875) (xy 31.336435 -299.928543) (xy 31.3643 -300.011276)
			(xy 31.384377 -300.096235) (xy 31.396494 -300.18269) (xy 31.400544 -300.269895) (xy 31.398525 -300.31336)
			(xy 34.599874 -300.31336) (xy 34.599874 -300.22646) (xy 34.607892 -300.139931) (xy 34.62386 -300.054511)
			(xy 34.647641 -299.970929) (xy 34.679033 -299.889897) (xy 34.717767 -299.812108) (xy 34.763514 -299.738224)
			(xy 34.815883 -299.668877) (xy 34.874427 -299.604657) (xy 34.938647 -299.546113) (xy 35.007994 -299.493744)
			(xy 35.081878 -299.447997) (xy 35.159667 -299.409263) (xy 35.240699 -299.377871) (xy 35.324281 -299.35409)
			(xy 35.409701 -299.338122) (xy 35.49623 -299.330104) (xy 35.58313 -299.330104) (xy 35.669659 -299.338122)
			(xy 35.755079 -299.35409) (xy 35.838661 -299.377871) (xy 35.919693 -299.409263) (xy 35.997482 -299.447997)
			(xy 36.071366 -299.493744) (xy 36.140713 -299.546113) (xy 36.204933 -299.604657) (xy 36.263477 -299.668877)
			(xy 36.271585 -299.679614) (xy 97.869246 -299.679614) (xy 97.873317 -299.623992) (xy 97.885443 -299.569555)
			(xy 97.905366 -299.517464) (xy 97.932662 -299.468829) (xy 97.966748 -299.424686) (xy 98.006897 -299.385977)
			(xy 98.052255 -299.353526) (xy 98.101855 -299.328025) (xy 98.154639 -299.310018) (xy 98.209482 -299.299888)
			(xy 98.265216 -299.297851) (xy 98.320653 -299.303951) (xy 98.37461 -299.318057) (xy 98.425939 -299.339869)
			(xy 98.473545 -299.368923) (xy 98.516413 -299.404598) (xy 98.55363 -299.446135) (xy 98.584403 -299.492648)
			(xy 98.608075 -299.543145) (xy 98.624143 -299.596552) (xy 98.632263 -299.651728) (xy 98.632772 -299.679614)
			(xy 98.632263 -299.7075) (xy 98.624143 -299.762676) (xy 98.608075 -299.816083) (xy 98.584403 -299.86658)
			(xy 98.55363 -299.913093) (xy 98.516413 -299.95463) (xy 98.473545 -299.990305) (xy 98.425939 -300.019359)
			(xy 98.37461 -300.041171) (xy 98.320653 -300.055277) (xy 98.265216 -300.061377) (xy 98.209482 -300.05934)
			(xy 98.154639 -300.04921) (xy 98.101855 -300.031203) (xy 98.052255 -300.005702) (xy 98.006897 -299.973251)
			(xy 97.966748 -299.934542) (xy 97.932662 -299.890399) (xy 97.905366 -299.841764) (xy 97.885443 -299.789673)
			(xy 97.873317 -299.735236) (xy 97.869246 -299.679614) (xy 36.271585 -299.679614) (xy 36.315846 -299.738224)
			(xy 36.361593 -299.812108) (xy 36.400327 -299.889897) (xy 36.431719 -299.970929) (xy 36.4555 -300.054511)
			(xy 36.471468 -300.139931) (xy 36.479486 -300.22646) (xy 36.479988 -300.26991) (xy 36.479486 -300.31336)
			(xy 36.471468 -300.399889) (xy 36.4555 -300.485309) (xy 36.431719 -300.568891) (xy 36.400327 -300.649923)
			(xy 36.372593 -300.705621) (xy 38.258488 -300.705621) (xy 38.258488 -300.634299) (xy 38.266474 -300.563425)
			(xy 38.282344 -300.49389) (xy 38.305901 -300.42657) (xy 38.336846 -300.362311) (xy 38.374792 -300.30192)
			(xy 38.419261 -300.246158) (xy 38.469694 -300.195725) (xy 38.525456 -300.151256) (xy 38.585847 -300.11331)
			(xy 38.650106 -300.082365) (xy 38.717426 -300.058808) (xy 38.786961 -300.042938) (xy 38.857835 -300.034952)
			(xy 38.929157 -300.034952) (xy 39.000031 -300.042938) (xy 39.069566 -300.058808) (xy 39.136886 -300.082365)
			(xy 39.201145 -300.11331) (xy 39.261536 -300.151256) (xy 39.317298 -300.195725) (xy 39.367731 -300.246158)
			(xy 39.4122 -300.30192) (xy 39.450146 -300.362311) (xy 39.481091 -300.42657) (xy 39.504648 -300.49389)
			(xy 39.520518 -300.563425) (xy 39.528504 -300.634299) (xy 39.529004 -300.66996) (xy 39.528504 -300.705621)
			(xy 40.1452 -300.705621) (xy 40.1452 -300.634299) (xy 40.153186 -300.563425) (xy 40.169056 -300.49389)
			(xy 40.192613 -300.42657) (xy 40.223558 -300.362311) (xy 40.261504 -300.30192) (xy 40.305973 -300.246158)
			(xy 40.356406 -300.195725) (xy 40.412168 -300.151256) (xy 40.472559 -300.11331) (xy 40.536818 -300.082365)
			(xy 40.604138 -300.058808) (xy 40.673673 -300.042938) (xy 40.744547 -300.034952) (xy 40.815869 -300.034952)
			(xy 40.886743 -300.042938) (xy 40.956278 -300.058808) (xy 41.023598 -300.082365) (xy 41.087857 -300.11331)
			(xy 41.148248 -300.151256) (xy 41.20401 -300.195725) (xy 41.254443 -300.246158) (xy 41.298912 -300.30192)
			(xy 41.336858 -300.362311) (xy 41.367803 -300.42657) (xy 41.39136 -300.49389) (xy 41.40723 -300.563425)
			(xy 41.415216 -300.634299) (xy 41.415716 -300.66996) (xy 41.415216 -300.705621) (xy 42.386242 -300.705621)
			(xy 42.386242 -300.634299) (xy 42.394228 -300.563425) (xy 42.410098 -300.49389) (xy 42.433655 -300.42657)
			(xy 42.4646 -300.362311) (xy 42.502546 -300.30192) (xy 42.547015 -300.246158) (xy 42.597448 -300.195725)
			(xy 42.65321 -300.151256) (xy 42.713601 -300.11331) (xy 42.77786 -300.082365) (xy 42.84518 -300.058808)
			(xy 42.914715 -300.042938) (xy 42.985589 -300.034952) (xy 43.056911 -300.034952) (xy 43.127785 -300.042938)
			(xy 43.19732 -300.058808) (xy 43.26464 -300.082365) (xy 43.328899 -300.11331) (xy 43.38929 -300.151256)
			(xy 43.445052 -300.195725) (xy 43.495485 -300.246158) (xy 43.539954 -300.30192) (xy 43.5779 -300.362311)
			(xy 43.608845 -300.42657) (xy 43.632402 -300.49389) (xy 43.648272 -300.563425) (xy 43.656258 -300.634299)
			(xy 43.656758 -300.66996) (xy 43.656258 -300.705621) (xy 44.290226 -300.705621) (xy 44.290226 -300.634299)
			(xy 44.298212 -300.563425) (xy 44.314082 -300.49389) (xy 44.337639 -300.42657) (xy 44.368584 -300.362311)
			(xy 44.40653 -300.30192) (xy 44.450999 -300.246158) (xy 44.501432 -300.195725) (xy 44.557194 -300.151256)
			(xy 44.617585 -300.11331) (xy 44.681844 -300.082365) (xy 44.749164 -300.058808) (xy 44.818699 -300.042938)
			(xy 44.889573 -300.034952) (xy 44.960895 -300.034952) (xy 45.031769 -300.042938) (xy 45.101304 -300.058808)
			(xy 45.168624 -300.082365) (xy 45.232883 -300.11331) (xy 45.293274 -300.151256) (xy 45.349036 -300.195725)
			(xy 45.399469 -300.246158) (xy 45.443938 -300.30192) (xy 45.481884 -300.362311) (xy 45.512829 -300.42657)
			(xy 45.536386 -300.49389) (xy 45.552256 -300.563425) (xy 45.560242 -300.634299) (xy 45.560742 -300.66996)
			(xy 45.560242 -300.705621) (xy 45.552927 -300.770544) (xy 96.970086 -300.770544) (xy 96.974157 -300.714922)
			(xy 96.986283 -300.660485) (xy 97.006206 -300.608394) (xy 97.033502 -300.559759) (xy 97.067588 -300.515616)
			(xy 97.107737 -300.476907) (xy 97.153095 -300.444456) (xy 97.202695 -300.418955) (xy 97.255479 -300.400948)
			(xy 97.310322 -300.390818) (xy 97.366056 -300.388781) (xy 97.421493 -300.394881) (xy 97.47545 -300.408987)
			(xy 97.526779 -300.430799) (xy 97.574385 -300.459853) (xy 97.617253 -300.495528) (xy 97.65447 -300.537065)
			(xy 97.685243 -300.583578) (xy 97.708915 -300.634075) (xy 97.724983 -300.687482) (xy 97.733103 -300.742658)
			(xy 97.733612 -300.770544) (xy 97.733103 -300.79843) (xy 97.724983 -300.853606) (xy 97.708915 -300.907013)
			(xy 97.685243 -300.95751) (xy 97.65447 -301.004023) (xy 97.617253 -301.04556) (xy 97.574385 -301.081235)
			(xy 97.526779 -301.110289) (xy 97.47545 -301.132101) (xy 97.421493 -301.146207) (xy 97.366056 -301.152307)
			(xy 97.310322 -301.15027) (xy 97.255479 -301.14014) (xy 97.202695 -301.122133) (xy 97.153095 -301.096632)
			(xy 97.107737 -301.064181) (xy 97.067588 -301.025472) (xy 97.033502 -300.981329) (xy 97.006206 -300.932694)
			(xy 96.986283 -300.880603) (xy 96.974157 -300.826166) (xy 96.970086 -300.770544) (xy 45.552927 -300.770544)
			(xy 45.552256 -300.776495) (xy 45.536386 -300.84603) (xy 45.512829 -300.91335) (xy 45.481884 -300.977609)
			(xy 45.443938 -301.038) (xy 45.399469 -301.093762) (xy 45.349036 -301.144195) (xy 45.293274 -301.188664)
			(xy 45.232883 -301.22661) (xy 45.168624 -301.257555) (xy 45.101304 -301.281112) (xy 45.031769 -301.296982)
			(xy 44.960895 -301.304968) (xy 44.889573 -301.304968) (xy 44.818699 -301.296982) (xy 44.749164 -301.281112)
			(xy 44.681844 -301.257555) (xy 44.617585 -301.22661) (xy 44.557194 -301.188664) (xy 44.501432 -301.144195)
			(xy 44.450999 -301.093762) (xy 44.40653 -301.038) (xy 44.368584 -300.977609) (xy 44.337639 -300.91335)
			(xy 44.314082 -300.84603) (xy 44.298212 -300.776495) (xy 44.290226 -300.705621) (xy 43.656258 -300.705621)
			(xy 43.648272 -300.776495) (xy 43.632402 -300.84603) (xy 43.608845 -300.91335) (xy 43.5779 -300.977609)
			(xy 43.539954 -301.038) (xy 43.495485 -301.093762) (xy 43.445052 -301.144195) (xy 43.38929 -301.188664)
			(xy 43.328899 -301.22661) (xy 43.26464 -301.257555) (xy 43.19732 -301.281112) (xy 43.127785 -301.296982)
			(xy 43.056911 -301.304968) (xy 42.985589 -301.304968) (xy 42.914715 -301.296982) (xy 42.84518 -301.281112)
			(xy 42.77786 -301.257555) (xy 42.713601 -301.22661) (xy 42.65321 -301.188664) (xy 42.597448 -301.144195)
			(xy 42.547015 -301.093762) (xy 42.502546 -301.038) (xy 42.4646 -300.977609) (xy 42.433655 -300.91335)
			(xy 42.410098 -300.84603) (xy 42.394228 -300.776495) (xy 42.386242 -300.705621) (xy 41.415216 -300.705621)
			(xy 41.40723 -300.776495) (xy 41.39136 -300.84603) (xy 41.367803 -300.91335) (xy 41.336858 -300.977609)
			(xy 41.298912 -301.038) (xy 41.254443 -301.093762) (xy 41.20401 -301.144195) (xy 41.148248 -301.188664)
			(xy 41.087857 -301.22661) (xy 41.023598 -301.257555) (xy 40.956278 -301.281112) (xy 40.886743 -301.296982)
			(xy 40.815869 -301.304968) (xy 40.744547 -301.304968) (xy 40.673673 -301.296982) (xy 40.604138 -301.281112)
			(xy 40.536818 -301.257555) (xy 40.472559 -301.22661) (xy 40.412168 -301.188664) (xy 40.356406 -301.144195)
			(xy 40.305973 -301.093762) (xy 40.261504 -301.038) (xy 40.223558 -300.977609) (xy 40.192613 -300.91335)
			(xy 40.169056 -300.84603) (xy 40.153186 -300.776495) (xy 40.1452 -300.705621) (xy 39.528504 -300.705621)
			(xy 39.520518 -300.776495) (xy 39.504648 -300.84603) (xy 39.481091 -300.91335) (xy 39.450146 -300.977609)
			(xy 39.4122 -301.038) (xy 39.367731 -301.093762) (xy 39.317298 -301.144195) (xy 39.261536 -301.188664)
			(xy 39.201145 -301.22661) (xy 39.136886 -301.257555) (xy 39.069566 -301.281112) (xy 39.000031 -301.296982)
			(xy 38.929157 -301.304968) (xy 38.857835 -301.304968) (xy 38.786961 -301.296982) (xy 38.717426 -301.281112)
			(xy 38.650106 -301.257555) (xy 38.585847 -301.22661) (xy 38.525456 -301.188664) (xy 38.469694 -301.144195)
			(xy 38.419261 -301.093762) (xy 38.374792 -301.038) (xy 38.336846 -300.977609) (xy 38.305901 -300.91335)
			(xy 38.282344 -300.84603) (xy 38.266474 -300.776495) (xy 38.258488 -300.705621) (xy 36.372593 -300.705621)
			(xy 36.361593 -300.727712) (xy 36.315846 -300.801596) (xy 36.263477 -300.870943) (xy 36.204933 -300.935163)
			(xy 36.140713 -300.993707) (xy 36.071366 -301.046076) (xy 35.997482 -301.091823) (xy 35.919693 -301.130557)
			(xy 35.838661 -301.161949) (xy 35.755079 -301.18573) (xy 35.669659 -301.201698) (xy 35.58313 -301.209716)
			(xy 35.49623 -301.209716) (xy 35.409701 -301.201698) (xy 35.324281 -301.18573) (xy 35.240699 -301.161949)
			(xy 35.159667 -301.130557) (xy 35.081878 -301.091823) (xy 35.007994 -301.046076) (xy 34.938647 -300.993707)
			(xy 34.874427 -300.935163) (xy 34.815883 -300.870943) (xy 34.763514 -300.801596) (xy 34.717767 -300.727712)
			(xy 34.679033 -300.649923) (xy 34.647641 -300.568891) (xy 34.62386 -300.485309) (xy 34.607892 -300.399889)
			(xy 34.599874 -300.31336) (xy 31.398525 -300.31336) (xy 31.396494 -300.3571) (xy 31.384379 -300.443555)
			(xy 31.364303 -300.528514) (xy 31.336438 -300.611247) (xy 31.301025 -300.691041) (xy 31.258368 -300.76721)
			(xy 31.208835 -300.839096) (xy 31.152853 -300.906082) (xy 31.090902 -300.96759) (xy 31.023517 -301.023092)
			(xy 30.951278 -301.072109) (xy 30.874806 -301.114219) (xy 30.79476 -301.14906) (xy 30.71183 -301.176332)
			(xy 30.626729 -301.195799) (xy 30.54019 -301.207295) (xy 30.452958 -301.21072) (xy 30.365784 -301.206045)
			(xy 30.279418 -301.19331) (xy 30.194605 -301.172625) (xy 30.112074 -301.144168) (xy 30.032536 -301.108183)
			(xy 29.994352 -301.087028) (xy 29.9749 -301.076527) (xy 29.933268 -301.061677) (xy 29.889696 -301.054253)
			(xy 29.845495 -301.05448) (xy 29.802001 -301.062352) (xy 29.760525 -301.07763) (xy 29.722318 -301.099855)
			(xy 29.688532 -301.128354) (xy 29.660187 -301.16227) (xy 29.638137 -301.200578) (xy 29.623049 -301.242124)
			(xy 29.615376 -301.285654) (xy 29.614876 -301.307754) (xy 29.614876 -301.772066) (xy 29.61535 -301.794174)
			(xy 29.623 -301.837722) (xy 29.638074 -301.879288) (xy 29.660116 -301.917616) (xy 29.688462 -301.95155)
			(xy 29.722255 -301.980063) (xy 29.760474 -302.002294) (xy 29.801966 -302.017573) (xy 29.845475 -302.025438)
			(xy 29.88969 -302.02565) (xy 29.933273 -302.018204) (xy 29.974909 -302.003324) (xy 29.994352 -301.992792)
			(xy 30.032527 -301.971621) (xy 30.112065 -301.935636) (xy 30.194595 -301.907178) (xy 30.279409 -301.886492)
			(xy 30.365774 -301.873756) (xy 30.452948 -301.86908) (xy 30.54018 -301.872504) (xy 30.626719 -301.883999)
			(xy 30.711821 -301.903466) (xy 30.794751 -301.930737) (xy 30.874797 -301.965577) (xy 30.951269 -302.007686)
			(xy 31.023509 -302.056702) (xy 31.090895 -302.112203) (xy 31.152846 -302.173711) (xy 31.208829 -302.240696)
			(xy 31.258363 -302.312582) (xy 31.301021 -302.38875) (xy 31.336435 -302.468543) (xy 31.3643 -302.551276)
			(xy 31.384377 -302.636235) (xy 31.396494 -302.72269) (xy 31.400544 -302.809895) (xy 31.398525 -302.85336)
			(xy 34.599874 -302.85336) (xy 34.599874 -302.76646) (xy 34.607892 -302.679931) (xy 34.62386 -302.594511)
			(xy 34.647641 -302.510929) (xy 34.679033 -302.429897) (xy 34.717767 -302.352108) (xy 34.763514 -302.278224)
			(xy 34.815883 -302.208877) (xy 34.874427 -302.144657) (xy 34.938647 -302.086113) (xy 35.007994 -302.033744)
			(xy 35.081878 -301.987997) (xy 35.159667 -301.949263) (xy 35.240699 -301.917871) (xy 35.324281 -301.89409)
			(xy 35.409701 -301.878122) (xy 35.49623 -301.870104) (xy 35.58313 -301.870104) (xy 35.669659 -301.878122)
			(xy 35.755079 -301.89409) (xy 35.838661 -301.917871) (xy 35.919693 -301.949263) (xy 35.997482 -301.987997)
			(xy 36.071366 -302.033744) (xy 36.140713 -302.086113) (xy 36.204933 -302.144657) (xy 36.263477 -302.208877)
			(xy 36.315846 -302.278224) (xy 36.361593 -302.352108) (xy 36.375855 -302.380751) (xy 38.258488 -302.380751)
			(xy 38.258488 -302.309429) (xy 38.266474 -302.238555) (xy 38.282344 -302.16902) (xy 38.305901 -302.1017)
			(xy 38.336846 -302.037441) (xy 38.374792 -301.97705) (xy 38.419261 -301.921288) (xy 38.469694 -301.870855)
			(xy 38.525456 -301.826386) (xy 38.585847 -301.78844) (xy 38.650106 -301.757495) (xy 38.717426 -301.733938)
			(xy 38.786961 -301.718068) (xy 38.857835 -301.710082) (xy 38.929157 -301.710082) (xy 39.000031 -301.718068)
			(xy 39.069566 -301.733938) (xy 39.136886 -301.757495) (xy 39.201145 -301.78844) (xy 39.261536 -301.826386)
			(xy 39.317298 -301.870855) (xy 39.367731 -301.921288) (xy 39.4122 -301.97705) (xy 39.450146 -302.037441)
			(xy 39.481091 -302.1017) (xy 39.504648 -302.16902) (xy 39.520518 -302.238555) (xy 39.528504 -302.309429)
			(xy 39.529004 -302.34509) (xy 39.528504 -302.380751) (xy 40.1452 -302.380751) (xy 40.1452 -302.309429)
			(xy 40.153186 -302.238555) (xy 40.169056 -302.16902) (xy 40.192613 -302.1017) (xy 40.223558 -302.037441)
			(xy 40.261504 -301.97705) (xy 40.305973 -301.921288) (xy 40.356406 -301.870855) (xy 40.412168 -301.826386)
			(xy 40.472559 -301.78844) (xy 40.536818 -301.757495) (xy 40.604138 -301.733938) (xy 40.673673 -301.718068)
			(xy 40.744547 -301.710082) (xy 40.815869 -301.710082) (xy 40.886743 -301.718068) (xy 40.956278 -301.733938)
			(xy 41.023598 -301.757495) (xy 41.087857 -301.78844) (xy 41.148248 -301.826386) (xy 41.20401 -301.870855)
			(xy 41.254443 -301.921288) (xy 41.298912 -301.97705) (xy 41.336858 -302.037441) (xy 41.367803 -302.1017)
			(xy 41.39136 -302.16902) (xy 41.40723 -302.238555) (xy 41.415216 -302.309429) (xy 41.415716 -302.34509)
			(xy 41.415216 -302.380751) (xy 42.386242 -302.380751) (xy 42.386242 -302.309429) (xy 42.394228 -302.238555)
			(xy 42.410098 -302.16902) (xy 42.433655 -302.1017) (xy 42.4646 -302.037441) (xy 42.502546 -301.97705)
			(xy 42.547015 -301.921288) (xy 42.597448 -301.870855) (xy 42.65321 -301.826386) (xy 42.713601 -301.78844)
			(xy 42.77786 -301.757495) (xy 42.84518 -301.733938) (xy 42.914715 -301.718068) (xy 42.985589 -301.710082)
			(xy 43.056911 -301.710082) (xy 43.127785 -301.718068) (xy 43.19732 -301.733938) (xy 43.26464 -301.757495)
			(xy 43.328899 -301.78844) (xy 43.38929 -301.826386) (xy 43.445052 -301.870855) (xy 43.495485 -301.921288)
			(xy 43.539954 -301.97705) (xy 43.5779 -302.037441) (xy 43.608845 -302.1017) (xy 43.632402 -302.16902)
			(xy 43.648272 -302.238555) (xy 43.656258 -302.309429) (xy 43.656758 -302.34509) (xy 43.656258 -302.380751)
			(xy 44.290226 -302.380751) (xy 44.290226 -302.309429) (xy 44.298212 -302.238555) (xy 44.314082 -302.16902)
			(xy 44.337639 -302.1017) (xy 44.368584 -302.037441) (xy 44.40653 -301.97705) (xy 44.450999 -301.921288)
			(xy 44.501432 -301.870855) (xy 44.557194 -301.826386) (xy 44.617585 -301.78844) (xy 44.681844 -301.757495)
			(xy 44.749164 -301.733938) (xy 44.818699 -301.718068) (xy 44.889573 -301.710082) (xy 44.960895 -301.710082)
			(xy 45.031769 -301.718068) (xy 45.101304 -301.733938) (xy 45.168624 -301.757495) (xy 45.232883 -301.78844)
			(xy 45.293274 -301.826386) (xy 45.349036 -301.870855) (xy 45.399469 -301.921288) (xy 45.443938 -301.97705)
			(xy 45.481884 -302.037441) (xy 45.512829 -302.1017) (xy 45.536386 -302.16902) (xy 45.544281 -302.203612)
			(xy 95.969072 -302.203612) (xy 95.973143 -302.14799) (xy 95.985269 -302.093553) (xy 96.005192 -302.041462)
			(xy 96.032488 -301.992827) (xy 96.066574 -301.948684) (xy 96.106723 -301.909975) (xy 96.152081 -301.877524)
			(xy 96.201681 -301.852023) (xy 96.254465 -301.834016) (xy 96.309308 -301.823886) (xy 96.365042 -301.821849)
			(xy 96.420479 -301.827949) (xy 96.474436 -301.842055) (xy 96.525765 -301.863867) (xy 96.573371 -301.892921)
			(xy 96.616239 -301.928596) (xy 96.653456 -301.970133) (xy 96.684229 -302.016646) (xy 96.707901 -302.067143)
			(xy 96.723969 -302.12055) (xy 96.732089 -302.175726) (xy 96.732598 -302.203612) (xy 96.732089 -302.231498)
			(xy 96.723969 -302.286674) (xy 96.707901 -302.340081) (xy 96.684229 -302.390578) (xy 96.653456 -302.437091)
			(xy 96.616239 -302.478628) (xy 96.573371 -302.514303) (xy 96.525765 -302.543357) (xy 96.474436 -302.565169)
			(xy 96.420479 -302.579275) (xy 96.365042 -302.585375) (xy 96.309308 -302.583338) (xy 96.254465 -302.573208)
			(xy 96.201681 -302.555201) (xy 96.152081 -302.5297) (xy 96.106723 -302.497249) (xy 96.066574 -302.45854)
			(xy 96.032488 -302.414397) (xy 96.005192 -302.365762) (xy 95.985269 -302.313671) (xy 95.973143 -302.259234)
			(xy 95.969072 -302.203612) (xy 45.544281 -302.203612) (xy 45.552256 -302.238555) (xy 45.560242 -302.309429)
			(xy 45.560742 -302.34509) (xy 45.560242 -302.380751) (xy 45.552256 -302.451625) (xy 45.536386 -302.52116)
			(xy 45.512829 -302.58848) (xy 45.481884 -302.652739) (xy 45.443938 -302.71313) (xy 45.399469 -302.768892)
			(xy 45.349036 -302.819325) (xy 45.293274 -302.863794) (xy 45.232883 -302.90174) (xy 45.168624 -302.932685)
			(xy 45.101304 -302.956242) (xy 45.031769 -302.972112) (xy 44.960895 -302.980098) (xy 44.889573 -302.980098)
			(xy 44.818699 -302.972112) (xy 44.749164 -302.956242) (xy 44.681844 -302.932685) (xy 44.617585 -302.90174)
			(xy 44.557194 -302.863794) (xy 44.501432 -302.819325) (xy 44.450999 -302.768892) (xy 44.40653 -302.71313)
			(xy 44.368584 -302.652739) (xy 44.337639 -302.58848) (xy 44.314082 -302.52116) (xy 44.298212 -302.451625)
			(xy 44.290226 -302.380751) (xy 43.656258 -302.380751) (xy 43.648272 -302.451625) (xy 43.632402 -302.52116)
			(xy 43.608845 -302.58848) (xy 43.5779 -302.652739) (xy 43.539954 -302.71313) (xy 43.495485 -302.768892)
			(xy 43.445052 -302.819325) (xy 43.38929 -302.863794) (xy 43.328899 -302.90174) (xy 43.26464 -302.932685)
			(xy 43.19732 -302.956242) (xy 43.127785 -302.972112) (xy 43.056911 -302.980098) (xy 42.985589 -302.980098)
			(xy 42.914715 -302.972112) (xy 42.84518 -302.956242) (xy 42.77786 -302.932685) (xy 42.713601 -302.90174)
			(xy 42.65321 -302.863794) (xy 42.597448 -302.819325) (xy 42.547015 -302.768892) (xy 42.502546 -302.71313)
			(xy 42.4646 -302.652739) (xy 42.433655 -302.58848) (xy 42.410098 -302.52116) (xy 42.394228 -302.451625)
			(xy 42.386242 -302.380751) (xy 41.415216 -302.380751) (xy 41.40723 -302.451625) (xy 41.39136 -302.52116)
			(xy 41.367803 -302.58848) (xy 41.336858 -302.652739) (xy 41.298912 -302.71313) (xy 41.254443 -302.768892)
			(xy 41.20401 -302.819325) (xy 41.148248 -302.863794) (xy 41.087857 -302.90174) (xy 41.023598 -302.932685)
			(xy 40.956278 -302.956242) (xy 40.886743 -302.972112) (xy 40.815869 -302.980098) (xy 40.744547 -302.980098)
			(xy 40.673673 -302.972112) (xy 40.604138 -302.956242) (xy 40.536818 -302.932685) (xy 40.472559 -302.90174)
			(xy 40.412168 -302.863794) (xy 40.356406 -302.819325) (xy 40.305973 -302.768892) (xy 40.261504 -302.71313)
			(xy 40.223558 -302.652739) (xy 40.192613 -302.58848) (xy 40.169056 -302.52116) (xy 40.153186 -302.451625)
			(xy 40.1452 -302.380751) (xy 39.528504 -302.380751) (xy 39.520518 -302.451625) (xy 39.504648 -302.52116)
			(xy 39.481091 -302.58848) (xy 39.450146 -302.652739) (xy 39.4122 -302.71313) (xy 39.367731 -302.768892)
			(xy 39.317298 -302.819325) (xy 39.261536 -302.863794) (xy 39.201145 -302.90174) (xy 39.136886 -302.932685)
			(xy 39.069566 -302.956242) (xy 39.000031 -302.972112) (xy 38.929157 -302.980098) (xy 38.857835 -302.980098)
			(xy 38.786961 -302.972112) (xy 38.717426 -302.956242) (xy 38.650106 -302.932685) (xy 38.585847 -302.90174)
			(xy 38.525456 -302.863794) (xy 38.469694 -302.819325) (xy 38.419261 -302.768892) (xy 38.374792 -302.71313)
			(xy 38.336846 -302.652739) (xy 38.305901 -302.58848) (xy 38.282344 -302.52116) (xy 38.266474 -302.451625)
			(xy 38.258488 -302.380751) (xy 36.375855 -302.380751) (xy 36.400327 -302.429897) (xy 36.431719 -302.510929)
			(xy 36.4555 -302.594511) (xy 36.471468 -302.679931) (xy 36.479486 -302.76646) (xy 36.479988 -302.80991)
			(xy 36.479486 -302.85336) (xy 36.471468 -302.939889) (xy 36.4555 -303.025309) (xy 36.431719 -303.108891)
			(xy 36.400327 -303.189923) (xy 36.361593 -303.267712) (xy 36.315846 -303.341596) (xy 36.263477 -303.410943)
			(xy 36.204933 -303.475163) (xy 36.145058 -303.529746) (xy 95.24187 -303.529746) (xy 95.245941 -303.474124)
			(xy 95.258067 -303.419687) (xy 95.27799 -303.367596) (xy 95.305286 -303.318961) (xy 95.339372 -303.274818)
			(xy 95.379521 -303.236109) (xy 95.424879 -303.203658) (xy 95.474479 -303.178157) (xy 95.527263 -303.16015)
			(xy 95.582106 -303.15002) (xy 95.63784 -303.147983) (xy 95.693277 -303.154083) (xy 95.747234 -303.168189)
			(xy 95.798563 -303.190001) (xy 95.846169 -303.219055) (xy 95.889037 -303.25473) (xy 95.926254 -303.296267)
			(xy 95.957027 -303.34278) (xy 95.980699 -303.393277) (xy 95.996767 -303.446684) (xy 96.004887 -303.50186)
			(xy 96.005396 -303.529746) (xy 96.004887 -303.557632) (xy 95.996767 -303.612808) (xy 95.980699 -303.666215)
			(xy 95.957027 -303.716712) (xy 95.926254 -303.763225) (xy 95.889037 -303.804762) (xy 95.846169 -303.840437)
			(xy 95.798563 -303.869491) (xy 95.747234 -303.891303) (xy 95.693277 -303.905409) (xy 95.63784 -303.911509)
			(xy 95.582106 -303.909472) (xy 95.527263 -303.899342) (xy 95.474479 -303.881335) (xy 95.424879 -303.855834)
			(xy 95.379521 -303.823383) (xy 95.339372 -303.784674) (xy 95.305286 -303.740531) (xy 95.27799 -303.691896)
			(xy 95.258067 -303.639805) (xy 95.245941 -303.585368) (xy 95.24187 -303.529746) (xy 36.145058 -303.529746)
			(xy 36.140713 -303.533707) (xy 36.071366 -303.586076) (xy 35.997482 -303.631823) (xy 35.919693 -303.670557)
			(xy 35.838661 -303.701949) (xy 35.755079 -303.72573) (xy 35.669659 -303.741698) (xy 35.58313 -303.749716)
			(xy 35.49623 -303.749716) (xy 35.409701 -303.741698) (xy 35.324281 -303.72573) (xy 35.240699 -303.701949)
			(xy 35.159667 -303.670557) (xy 35.081878 -303.631823) (xy 35.007994 -303.586076) (xy 34.938647 -303.533707)
			(xy 34.874427 -303.475163) (xy 34.815883 -303.410943) (xy 34.763514 -303.341596) (xy 34.717767 -303.267712)
			(xy 34.679033 -303.189923) (xy 34.647641 -303.108891) (xy 34.62386 -303.025309) (xy 34.607892 -302.939889)
			(xy 34.599874 -302.85336) (xy 31.398525 -302.85336) (xy 31.396494 -302.8971) (xy 31.384379 -302.983555)
			(xy 31.364303 -303.068514) (xy 31.336438 -303.151247) (xy 31.301025 -303.231041) (xy 31.258368 -303.30721)
			(xy 31.208835 -303.379096) (xy 31.152853 -303.446082) (xy 31.090902 -303.50759) (xy 31.023517 -303.563092)
			(xy 30.951278 -303.612109) (xy 30.874806 -303.654219) (xy 30.79476 -303.68906) (xy 30.71183 -303.716332)
			(xy 30.626729 -303.735799) (xy 30.54019 -303.747295) (xy 30.452958 -303.75072) (xy 30.365784 -303.746045)
			(xy 30.279418 -303.73331) (xy 30.194605 -303.712625) (xy 30.112074 -303.684168) (xy 30.032536 -303.648183)
			(xy 29.994352 -303.627028) (xy 29.9749 -303.616527) (xy 29.933268 -303.601677) (xy 29.889696 -303.594253)
			(xy 29.845495 -303.59448) (xy 29.802001 -303.602352) (xy 29.760525 -303.61763) (xy 29.722318 -303.639855)
			(xy 29.688532 -303.668354) (xy 29.660187 -303.70227) (xy 29.638137 -303.740578) (xy 29.623049 -303.782124)
			(xy 29.615376 -303.825654) (xy 29.614876 -303.847754) (xy 29.614876 -304.312066) (xy 29.61535 -304.334174)
			(xy 29.623 -304.377722) (xy 29.62815 -304.391923) (xy 38.215054 -304.391923) (xy 38.215054 -304.320601)
			(xy 38.22304 -304.249727) (xy 38.23891 -304.180192) (xy 38.262467 -304.112872) (xy 38.293412 -304.048613)
			(xy 38.331358 -303.988222) (xy 38.375827 -303.93246) (xy 38.42626 -303.882027) (xy 38.482022 -303.837558)
			(xy 38.542413 -303.799612) (xy 38.606672 -303.768667) (xy 38.673992 -303.74511) (xy 38.743527 -303.72924)
			(xy 38.814401 -303.721254) (xy 38.885723 -303.721254) (xy 38.956597 -303.72924) (xy 39.026132 -303.74511)
			(xy 39.093452 -303.768667) (xy 39.157711 -303.799612) (xy 39.218102 -303.837558) (xy 39.273864 -303.882027)
			(xy 39.324297 -303.93246) (xy 39.368766 -303.988222) (xy 39.406712 -304.048613) (xy 39.437657 -304.112872)
			(xy 39.461214 -304.180192) (xy 39.477084 -304.249727) (xy 39.48507 -304.320601) (xy 39.48557 -304.356262)
			(xy 39.48507 -304.391923) (xy 40.101766 -304.391923) (xy 40.101766 -304.320601) (xy 40.109752 -304.249727)
			(xy 40.125622 -304.180192) (xy 40.149179 -304.112872) (xy 40.180124 -304.048613) (xy 40.21807 -303.988222)
			(xy 40.262539 -303.93246) (xy 40.312972 -303.882027) (xy 40.368734 -303.837558) (xy 40.429125 -303.799612)
			(xy 40.493384 -303.768667) (xy 40.560704 -303.74511) (xy 40.630239 -303.72924) (xy 40.701113 -303.721254)
			(xy 40.772435 -303.721254) (xy 40.843309 -303.72924) (xy 40.912844 -303.74511) (xy 40.980164 -303.768667)
			(xy 41.044423 -303.799612) (xy 41.104814 -303.837558) (xy 41.160576 -303.882027) (xy 41.211009 -303.93246)
			(xy 41.255478 -303.988222) (xy 41.293424 -304.048613) (xy 41.324369 -304.112872) (xy 41.347926 -304.180192)
			(xy 41.363796 -304.249727) (xy 41.371782 -304.320601) (xy 41.372282 -304.356262) (xy 41.371782 -304.391923)
			(xy 42.342808 -304.391923) (xy 42.342808 -304.320601) (xy 42.350794 -304.249727) (xy 42.366664 -304.180192)
			(xy 42.390221 -304.112872) (xy 42.421166 -304.048613) (xy 42.459112 -303.988222) (xy 42.503581 -303.93246)
			(xy 42.554014 -303.882027) (xy 42.609776 -303.837558) (xy 42.670167 -303.799612) (xy 42.734426 -303.768667)
			(xy 42.801746 -303.74511) (xy 42.871281 -303.72924) (xy 42.942155 -303.721254) (xy 43.013477 -303.721254)
			(xy 43.084351 -303.72924) (xy 43.153886 -303.74511) (xy 43.221206 -303.768667) (xy 43.285465 -303.799612)
			(xy 43.345856 -303.837558) (xy 43.401618 -303.882027) (xy 43.452051 -303.93246) (xy 43.49652 -303.988222)
			(xy 43.534466 -304.048613) (xy 43.565411 -304.112872) (xy 43.588968 -304.180192) (xy 43.604838 -304.249727)
			(xy 43.612824 -304.320601) (xy 43.613324 -304.356262) (xy 43.612824 -304.391923) (xy 44.246792 -304.391923)
			(xy 44.246792 -304.320601) (xy 44.254778 -304.249727) (xy 44.270648 -304.180192) (xy 44.294205 -304.112872)
			(xy 44.32515 -304.048613) (xy 44.363096 -303.988222) (xy 44.407565 -303.93246) (xy 44.457998 -303.882027)
			(xy 44.51376 -303.837558) (xy 44.574151 -303.799612) (xy 44.63841 -303.768667) (xy 44.70573 -303.74511)
			(xy 44.775265 -303.72924) (xy 44.846139 -303.721254) (xy 44.917461 -303.721254) (xy 44.988335 -303.72924)
			(xy 45.05787 -303.74511) (xy 45.12519 -303.768667) (xy 45.189449 -303.799612) (xy 45.24984 -303.837558)
			(xy 45.305602 -303.882027) (xy 45.356035 -303.93246) (xy 45.400504 -303.988222) (xy 45.43845 -304.048613)
			(xy 45.469395 -304.112872) (xy 45.492952 -304.180192) (xy 45.508822 -304.249727) (xy 45.516808 -304.320601)
			(xy 45.517308 -304.356262) (xy 45.516808 -304.391923) (xy 45.508822 -304.462797) (xy 45.492952 -304.532332)
			(xy 45.469395 -304.599652) (xy 45.43845 -304.663911) (xy 45.400504 -304.724302) (xy 45.364161 -304.769875)
			(xy 58.097666 -304.769875) (xy 58.097666 -304.698553) (xy 58.105652 -304.627679) (xy 58.121522 -304.558144)
			(xy 58.145079 -304.490824) (xy 58.176024 -304.426565) (xy 58.21397 -304.366174) (xy 58.258439 -304.310412)
			(xy 58.308872 -304.259979) (xy 58.364634 -304.21551) (xy 58.425025 -304.177564) (xy 58.489284 -304.146619)
			(xy 58.556604 -304.123062) (xy 58.626139 -304.107192) (xy 58.697013 -304.099206) (xy 58.768335 -304.099206)
			(xy 58.839209 -304.107192) (xy 58.908744 -304.123062) (xy 58.976064 -304.146619) (xy 59.040323 -304.177564)
			(xy 59.100714 -304.21551) (xy 59.156476 -304.259979) (xy 59.206909 -304.310412) (xy 59.251378 -304.366174)
			(xy 59.289324 -304.426565) (xy 59.320269 -304.490824) (xy 59.343826 -304.558144) (xy 59.359696 -304.627679)
			(xy 59.367682 -304.698553) (xy 59.368182 -304.734214) (xy 59.367682 -304.769875) (xy 59.984378 -304.769875)
			(xy 59.984378 -304.698553) (xy 59.992364 -304.627679) (xy 60.008234 -304.558144) (xy 60.031791 -304.490824)
			(xy 60.062736 -304.426565) (xy 60.100682 -304.366174) (xy 60.145151 -304.310412) (xy 60.195584 -304.259979)
			(xy 60.251346 -304.21551) (xy 60.311737 -304.177564) (xy 60.375996 -304.146619) (xy 60.443316 -304.123062)
			(xy 60.512851 -304.107192) (xy 60.583725 -304.099206) (xy 60.655047 -304.099206) (xy 60.725921 -304.107192)
			(xy 60.795456 -304.123062) (xy 60.862776 -304.146619) (xy 60.927035 -304.177564) (xy 60.987426 -304.21551)
			(xy 61.043188 -304.259979) (xy 61.093621 -304.310412) (xy 61.13809 -304.366174) (xy 61.176036 -304.426565)
			(xy 61.206981 -304.490824) (xy 61.230538 -304.558144) (xy 61.246408 -304.627679) (xy 61.254394 -304.698553)
			(xy 61.254894 -304.734214) (xy 61.254394 -304.769875) (xy 62.22542 -304.769875) (xy 62.22542 -304.698553)
			(xy 62.233406 -304.627679) (xy 62.249276 -304.558144) (xy 62.272833 -304.490824) (xy 62.303778 -304.426565)
			(xy 62.341724 -304.366174) (xy 62.386193 -304.310412) (xy 62.436626 -304.259979) (xy 62.492388 -304.21551)
			(xy 62.552779 -304.177564) (xy 62.617038 -304.146619) (xy 62.684358 -304.123062) (xy 62.753893 -304.107192)
			(xy 62.824767 -304.099206) (xy 62.896089 -304.099206) (xy 62.966963 -304.107192) (xy 63.036498 -304.123062)
			(xy 63.103818 -304.146619) (xy 63.168077 -304.177564) (xy 63.228468 -304.21551) (xy 63.28423 -304.259979)
			(xy 63.334663 -304.310412) (xy 63.379132 -304.366174) (xy 63.417078 -304.426565) (xy 63.448023 -304.490824)
			(xy 63.47158 -304.558144) (xy 63.48745 -304.627679) (xy 63.495436 -304.698553) (xy 63.495936 -304.734214)
			(xy 63.495436 -304.769875) (xy 64.129404 -304.769875) (xy 64.129404 -304.698553) (xy 64.13739 -304.627679)
			(xy 64.15326 -304.558144) (xy 64.176817 -304.490824) (xy 64.207762 -304.426565) (xy 64.245708 -304.366174)
			(xy 64.290177 -304.310412) (xy 64.34061 -304.259979) (xy 64.396372 -304.21551) (xy 64.456763 -304.177564)
			(xy 64.521022 -304.146619) (xy 64.588342 -304.123062) (xy 64.657877 -304.107192) (xy 64.728751 -304.099206)
			(xy 64.800073 -304.099206) (xy 64.870947 -304.107192) (xy 64.940482 -304.123062) (xy 65.007802 -304.146619)
			(xy 65.072061 -304.177564) (xy 65.132452 -304.21551) (xy 65.188214 -304.259979) (xy 65.238647 -304.310412)
			(xy 65.283116 -304.366174) (xy 65.321062 -304.426565) (xy 65.352007 -304.490824) (xy 65.375564 -304.558144)
			(xy 65.391434 -304.627679) (xy 65.39942 -304.698553) (xy 65.39992 -304.734214) (xy 65.39942 -304.769875)
			(xy 65.39697 -304.791618) (xy 94.531178 -304.791618) (xy 94.535249 -304.735996) (xy 94.547375 -304.681559)
			(xy 94.567298 -304.629468) (xy 94.594594 -304.580833) (xy 94.62868 -304.53669) (xy 94.668829 -304.497981)
			(xy 94.714187 -304.46553) (xy 94.763787 -304.440029) (xy 94.816571 -304.422022) (xy 94.871414 -304.411892)
			(xy 94.927148 -304.409855) (xy 94.982585 -304.415955) (xy 95.036542 -304.430061) (xy 95.087871 -304.451873)
			(xy 95.135477 -304.480927) (xy 95.178345 -304.516602) (xy 95.215562 -304.558139) (xy 95.246335 -304.604652)
			(xy 95.270007 -304.655149) (xy 95.286075 -304.708556) (xy 95.294195 -304.763732) (xy 95.294704 -304.791618)
			(xy 95.294195 -304.819504) (xy 95.286075 -304.87468) (xy 95.270007 -304.928087) (xy 95.246335 -304.978584)
			(xy 95.215562 -305.025097) (xy 95.178345 -305.066634) (xy 95.135477 -305.102309) (xy 95.087871 -305.131363)
			(xy 95.036542 -305.153175) (xy 94.982585 -305.167281) (xy 94.927148 -305.173381) (xy 94.871414 -305.171344)
			(xy 94.816571 -305.161214) (xy 94.763787 -305.143207) (xy 94.714187 -305.117706) (xy 94.668829 -305.085255)
			(xy 94.62868 -305.046546) (xy 94.594594 -305.002403) (xy 94.567298 -304.953768) (xy 94.547375 -304.901677)
			(xy 94.535249 -304.84724) (xy 94.531178 -304.791618) (xy 65.39697 -304.791618) (xy 65.391434 -304.840749)
			(xy 65.375564 -304.910284) (xy 65.352007 -304.977604) (xy 65.321062 -305.041863) (xy 65.283116 -305.102254)
			(xy 65.238647 -305.158016) (xy 65.188214 -305.208449) (xy 65.132452 -305.252918) (xy 65.072061 -305.290864)
			(xy 65.007802 -305.321809) (xy 64.940482 -305.345366) (xy 64.870947 -305.361236) (xy 64.800073 -305.369222)
			(xy 64.728751 -305.369222) (xy 64.657877 -305.361236) (xy 64.588342 -305.345366) (xy 64.521022 -305.321809)
			(xy 64.456763 -305.290864) (xy 64.396372 -305.252918) (xy 64.34061 -305.208449) (xy 64.290177 -305.158016)
			(xy 64.245708 -305.102254) (xy 64.207762 -305.041863) (xy 64.176817 -304.977604) (xy 64.15326 -304.910284)
			(xy 64.13739 -304.840749) (xy 64.129404 -304.769875) (xy 63.495436 -304.769875) (xy 63.48745 -304.840749)
			(xy 63.47158 -304.910284) (xy 63.448023 -304.977604) (xy 63.417078 -305.041863) (xy 63.379132 -305.102254)
			(xy 63.334663 -305.158016) (xy 63.28423 -305.208449) (xy 63.228468 -305.252918) (xy 63.168077 -305.290864)
			(xy 63.103818 -305.321809) (xy 63.036498 -305.345366) (xy 62.966963 -305.361236) (xy 62.896089 -305.369222)
			(xy 62.824767 -305.369222) (xy 62.753893 -305.361236) (xy 62.684358 -305.345366) (xy 62.617038 -305.321809)
			(xy 62.552779 -305.290864) (xy 62.492388 -305.252918) (xy 62.436626 -305.208449) (xy 62.386193 -305.158016)
			(xy 62.341724 -305.102254) (xy 62.303778 -305.041863) (xy 62.272833 -304.977604) (xy 62.249276 -304.910284)
			(xy 62.233406 -304.840749) (xy 62.22542 -304.769875) (xy 61.254394 -304.769875) (xy 61.246408 -304.840749)
			(xy 61.230538 -304.910284) (xy 61.206981 -304.977604) (xy 61.176036 -305.041863) (xy 61.13809 -305.102254)
			(xy 61.093621 -305.158016) (xy 61.043188 -305.208449) (xy 60.987426 -305.252918) (xy 60.927035 -305.290864)
			(xy 60.862776 -305.321809) (xy 60.795456 -305.345366) (xy 60.725921 -305.361236) (xy 60.655047 -305.369222)
			(xy 60.583725 -305.369222) (xy 60.512851 -305.361236) (xy 60.443316 -305.345366) (xy 60.375996 -305.321809)
			(xy 60.311737 -305.290864) (xy 60.251346 -305.252918) (xy 60.195584 -305.208449) (xy 60.145151 -305.158016)
			(xy 60.100682 -305.102254) (xy 60.062736 -305.041863) (xy 60.031791 -304.977604) (xy 60.008234 -304.910284)
			(xy 59.992364 -304.840749) (xy 59.984378 -304.769875) (xy 59.367682 -304.769875) (xy 59.359696 -304.840749)
			(xy 59.343826 -304.910284) (xy 59.320269 -304.977604) (xy 59.289324 -305.041863) (xy 59.251378 -305.102254)
			(xy 59.206909 -305.158016) (xy 59.156476 -305.208449) (xy 59.100714 -305.252918) (xy 59.040323 -305.290864)
			(xy 58.976064 -305.321809) (xy 58.908744 -305.345366) (xy 58.839209 -305.361236) (xy 58.768335 -305.369222)
			(xy 58.697013 -305.369222) (xy 58.626139 -305.361236) (xy 58.556604 -305.345366) (xy 58.489284 -305.321809)
			(xy 58.425025 -305.290864) (xy 58.364634 -305.252918) (xy 58.308872 -305.208449) (xy 58.258439 -305.158016)
			(xy 58.21397 -305.102254) (xy 58.176024 -305.041863) (xy 58.145079 -304.977604) (xy 58.121522 -304.910284)
			(xy 58.105652 -304.840749) (xy 58.097666 -304.769875) (xy 45.364161 -304.769875) (xy 45.356035 -304.780064)
			(xy 45.305602 -304.830497) (xy 45.24984 -304.874966) (xy 45.189449 -304.912912) (xy 45.12519 -304.943857)
			(xy 45.05787 -304.967414) (xy 44.988335 -304.983284) (xy 44.917461 -304.99127) (xy 44.846139 -304.99127)
			(xy 44.775265 -304.983284) (xy 44.70573 -304.967414) (xy 44.63841 -304.943857) (xy 44.574151 -304.912912)
			(xy 44.51376 -304.874966) (xy 44.457998 -304.830497) (xy 44.407565 -304.780064) (xy 44.363096 -304.724302)
			(xy 44.32515 -304.663911) (xy 44.294205 -304.599652) (xy 44.270648 -304.532332) (xy 44.254778 -304.462797)
			(xy 44.246792 -304.391923) (xy 43.612824 -304.391923) (xy 43.604838 -304.462797) (xy 43.588968 -304.532332)
			(xy 43.565411 -304.599652) (xy 43.534466 -304.663911) (xy 43.49652 -304.724302) (xy 43.452051 -304.780064)
			(xy 43.401618 -304.830497) (xy 43.345856 -304.874966) (xy 43.285465 -304.912912) (xy 43.221206 -304.943857)
			(xy 43.153886 -304.967414) (xy 43.084351 -304.983284) (xy 43.013477 -304.99127) (xy 42.942155 -304.99127)
			(xy 42.871281 -304.983284) (xy 42.801746 -304.967414) (xy 42.734426 -304.943857) (xy 42.670167 -304.912912)
			(xy 42.609776 -304.874966) (xy 42.554014 -304.830497) (xy 42.503581 -304.780064) (xy 42.459112 -304.724302)
			(xy 42.421166 -304.663911) (xy 42.390221 -304.599652) (xy 42.366664 -304.532332) (xy 42.350794 -304.462797)
			(xy 42.342808 -304.391923) (xy 41.371782 -304.391923) (xy 41.363796 -304.462797) (xy 41.347926 -304.532332)
			(xy 41.324369 -304.599652) (xy 41.293424 -304.663911) (xy 41.255478 -304.724302) (xy 41.211009 -304.780064)
			(xy 41.160576 -304.830497) (xy 41.104814 -304.874966) (xy 41.044423 -304.912912) (xy 40.980164 -304.943857)
			(xy 40.912844 -304.967414) (xy 40.843309 -304.983284) (xy 40.772435 -304.99127) (xy 40.701113 -304.99127)
			(xy 40.630239 -304.983284) (xy 40.560704 -304.967414) (xy 40.493384 -304.943857) (xy 40.429125 -304.912912)
			(xy 40.368734 -304.874966) (xy 40.312972 -304.830497) (xy 40.262539 -304.780064) (xy 40.21807 -304.724302)
			(xy 40.180124 -304.663911) (xy 40.149179 -304.599652) (xy 40.125622 -304.532332) (xy 40.109752 -304.462797)
			(xy 40.101766 -304.391923) (xy 39.48507 -304.391923) (xy 39.477084 -304.462797) (xy 39.461214 -304.532332)
			(xy 39.437657 -304.599652) (xy 39.406712 -304.663911) (xy 39.368766 -304.724302) (xy 39.324297 -304.780064)
			(xy 39.273864 -304.830497) (xy 39.218102 -304.874966) (xy 39.157711 -304.912912) (xy 39.093452 -304.943857)
			(xy 39.026132 -304.967414) (xy 38.956597 -304.983284) (xy 38.885723 -304.99127) (xy 38.814401 -304.99127)
			(xy 38.743527 -304.983284) (xy 38.673992 -304.967414) (xy 38.606672 -304.943857) (xy 38.542413 -304.912912)
			(xy 38.482022 -304.874966) (xy 38.42626 -304.830497) (xy 38.375827 -304.780064) (xy 38.331358 -304.724302)
			(xy 38.293412 -304.663911) (xy 38.262467 -304.599652) (xy 38.23891 -304.532332) (xy 38.22304 -304.462797)
			(xy 38.215054 -304.391923) (xy 29.62815 -304.391923) (xy 29.638074 -304.419288) (xy 29.660116 -304.457616)
			(xy 29.688462 -304.49155) (xy 29.722255 -304.520063) (xy 29.760474 -304.542294) (xy 29.801966 -304.557573)
			(xy 29.845475 -304.565438) (xy 29.88969 -304.56565) (xy 29.933273 -304.558204) (xy 29.974909 -304.543324)
			(xy 29.994352 -304.532792) (xy 30.032527 -304.511621) (xy 30.112065 -304.475636) (xy 30.194595 -304.447178)
			(xy 30.279409 -304.426492) (xy 30.365774 -304.413756) (xy 30.452948 -304.40908) (xy 30.54018 -304.412504)
			(xy 30.626719 -304.423999) (xy 30.711821 -304.443466) (xy 30.794751 -304.470737) (xy 30.874797 -304.505577)
			(xy 30.951269 -304.547686) (xy 31.023509 -304.596702) (xy 31.090895 -304.652203) (xy 31.152846 -304.713711)
			(xy 31.208829 -304.780696) (xy 31.258363 -304.852582) (xy 31.301021 -304.92875) (xy 31.336435 -305.008543)
			(xy 31.3643 -305.091276) (xy 31.384377 -305.176235) (xy 31.396494 -305.26269) (xy 31.400544 -305.349895)
			(xy 31.398525 -305.39336) (xy 34.599874 -305.39336) (xy 34.599874 -305.30646) (xy 34.607892 -305.219931)
			(xy 34.62386 -305.134511) (xy 34.647641 -305.050929) (xy 34.679033 -304.969897) (xy 34.717767 -304.892108)
			(xy 34.763514 -304.818224) (xy 34.815883 -304.748877) (xy 34.874427 -304.684657) (xy 34.938647 -304.626113)
			(xy 35.007994 -304.573744) (xy 35.081878 -304.527997) (xy 35.159667 -304.489263) (xy 35.240699 -304.457871)
			(xy 35.324281 -304.43409) (xy 35.409701 -304.418122) (xy 35.49623 -304.410104) (xy 35.58313 -304.410104)
			(xy 35.669659 -304.418122) (xy 35.755079 -304.43409) (xy 35.838661 -304.457871) (xy 35.919693 -304.489263)
			(xy 35.997482 -304.527997) (xy 36.071366 -304.573744) (xy 36.140713 -304.626113) (xy 36.204933 -304.684657)
			(xy 36.263477 -304.748877) (xy 36.315846 -304.818224) (xy 36.361593 -304.892108) (xy 36.400327 -304.969897)
			(xy 36.431719 -305.050929) (xy 36.4555 -305.134511) (xy 36.471468 -305.219931) (xy 36.479486 -305.30646)
			(xy 36.479988 -305.34991) (xy 36.479486 -305.39336) (xy 36.471468 -305.479889) (xy 36.4555 -305.565309)
			(xy 36.431719 -305.648891) (xy 36.400327 -305.729923) (xy 36.361593 -305.807712) (xy 36.315846 -305.881596)
			(xy 36.263477 -305.950943) (xy 36.204933 -306.015163) (xy 36.140713 -306.073707) (xy 36.071366 -306.126076)
			(xy 35.997482 -306.171823) (xy 35.919693 -306.210557) (xy 35.838661 -306.241949) (xy 35.755079 -306.26573)
			(xy 35.669659 -306.281698) (xy 35.58313 -306.289716) (xy 35.49623 -306.289716) (xy 35.409701 -306.281698)
			(xy 35.324281 -306.26573) (xy 35.240699 -306.241949) (xy 35.159667 -306.210557) (xy 35.081878 -306.171823)
			(xy 35.007994 -306.126076) (xy 34.938647 -306.073707) (xy 34.874427 -306.015163) (xy 34.815883 -305.950943)
			(xy 34.763514 -305.881596) (xy 34.717767 -305.807712) (xy 34.679033 -305.729923) (xy 34.647641 -305.648891)
			(xy 34.62386 -305.565309) (xy 34.607892 -305.479889) (xy 34.599874 -305.39336) (xy 31.398525 -305.39336)
			(xy 31.396494 -305.4371) (xy 31.384379 -305.523555) (xy 31.364303 -305.608514) (xy 31.336438 -305.691247)
			(xy 31.301025 -305.771041) (xy 31.258368 -305.84721) (xy 31.208835 -305.919096) (xy 31.152853 -305.986082)
			(xy 31.090902 -306.04759) (xy 31.023517 -306.103092) (xy 30.951278 -306.152109) (xy 30.874806 -306.194219)
			(xy 30.79476 -306.22906) (xy 30.71183 -306.256332) (xy 30.626729 -306.275799) (xy 30.54019 -306.287295)
			(xy 30.452958 -306.29072) (xy 30.365784 -306.286045) (xy 30.279418 -306.27331) (xy 30.194605 -306.252625)
			(xy 30.112074 -306.224168) (xy 30.032536 -306.188183) (xy 29.994352 -306.167028) (xy 29.9749 -306.156527)
			(xy 29.933268 -306.141677) (xy 29.889696 -306.134253) (xy 29.845495 -306.13448) (xy 29.802001 -306.142352)
			(xy 29.760525 -306.15763) (xy 29.722318 -306.179855) (xy 29.688532 -306.208354) (xy 29.660187 -306.24227)
			(xy 29.638137 -306.280578) (xy 29.623049 -306.322124) (xy 29.615376 -306.365654) (xy 29.614876 -306.387754)
			(xy 29.614876 -306.423737) (xy 47.775358 -306.423737) (xy 47.775358 -306.342627) (xy 47.783308 -306.261908)
			(xy 47.799131 -306.182357) (xy 47.822676 -306.104741) (xy 47.853715 -306.029805) (xy 47.89195 -305.958273)
			(xy 47.937012 -305.890833) (xy 47.988467 -305.828134) (xy 48.04582 -305.770781) (xy 48.108519 -305.719326)
			(xy 48.175959 -305.674264) (xy 48.247491 -305.636029) (xy 48.322427 -305.60499) (xy 48.400043 -305.581445)
			(xy 48.479594 -305.565622) (xy 48.560313 -305.557672) (xy 48.641423 -305.557672) (xy 48.722142 -305.565622)
			(xy 48.801693 -305.581445) (xy 48.879309 -305.60499) (xy 48.954245 -305.636029) (xy 49.025777 -305.674264)
			(xy 49.093217 -305.719326) (xy 49.155916 -305.770781) (xy 49.213269 -305.828134) (xy 49.264724 -305.890833)
			(xy 49.309786 -305.958273) (xy 49.33217 -306.00015) (xy 93.984824 -306.00015) (xy 93.988895 -305.944528)
			(xy 94.001021 -305.890091) (xy 94.020944 -305.838) (xy 94.04824 -305.789365) (xy 94.082326 -305.745222)
			(xy 94.122475 -305.706513) (xy 94.167833 -305.674062) (xy 94.217433 -305.648561) (xy 94.270217 -305.630554)
			(xy 94.32506 -305.620424) (xy 94.380794 -305.618387) (xy 94.436231 -305.624487) (xy 94.490188 -305.638593)
			(xy 94.541517 -305.660405) (xy 94.589123 -305.689459) (xy 94.631991 -305.725134) (xy 94.669208 -305.766671)
			(xy 94.699981 -305.813184) (xy 94.723653 -305.863681) (xy 94.739721 -305.917088) (xy 94.747841 -305.972264)
			(xy 94.74835 -306.00015) (xy 94.747841 -306.028036) (xy 94.739721 -306.083212) (xy 94.723653 -306.136619)
			(xy 94.699981 -306.187116) (xy 94.669208 -306.233629) (xy 94.631991 -306.275166) (xy 94.589123 -306.310841)
			(xy 94.541517 -306.339895) (xy 94.490188 -306.361707) (xy 94.436231 -306.375813) (xy 94.380794 -306.381913)
			(xy 94.32506 -306.379876) (xy 94.270217 -306.369746) (xy 94.217433 -306.351739) (xy 94.167833 -306.326238)
			(xy 94.122475 -306.293787) (xy 94.082326 -306.255078) (xy 94.04824 -306.210935) (xy 94.020944 -306.1623)
			(xy 94.001021 -306.110209) (xy 93.988895 -306.055772) (xy 93.984824 -306.00015) (xy 49.33217 -306.00015)
			(xy 49.348021 -306.029805) (xy 49.37906 -306.104741) (xy 49.402605 -306.182357) (xy 49.418428 -306.261908)
			(xy 49.426378 -306.342627) (xy 49.426876 -306.383182) (xy 49.426378 -306.423737) (xy 49.418428 -306.504456)
			(xy 49.402605 -306.584007) (xy 49.37906 -306.661623) (xy 49.348021 -306.736559) (xy 49.309786 -306.808091)
			(xy 49.30783 -306.811019) (xy 58.097666 -306.811019) (xy 58.097666 -306.739697) (xy 58.105652 -306.668823)
			(xy 58.121522 -306.599288) (xy 58.145079 -306.531968) (xy 58.176024 -306.467709) (xy 58.21397 -306.407318)
			(xy 58.258439 -306.351556) (xy 58.308872 -306.301123) (xy 58.364634 -306.256654) (xy 58.425025 -306.218708)
			(xy 58.489284 -306.187763) (xy 58.556604 -306.164206) (xy 58.626139 -306.148336) (xy 58.697013 -306.14035)
			(xy 58.768335 -306.14035) (xy 58.839209 -306.148336) (xy 58.908744 -306.164206) (xy 58.976064 -306.187763)
			(xy 59.040323 -306.218708) (xy 59.100714 -306.256654) (xy 59.156476 -306.301123) (xy 59.206909 -306.351556)
			(xy 59.251378 -306.407318) (xy 59.289324 -306.467709) (xy 59.320269 -306.531968) (xy 59.343826 -306.599288)
			(xy 59.359696 -306.668823) (xy 59.367682 -306.739697) (xy 59.368182 -306.775358) (xy 59.367682 -306.811019)
			(xy 59.984378 -306.811019) (xy 59.984378 -306.739697) (xy 59.992364 -306.668823) (xy 60.008234 -306.599288)
			(xy 60.031791 -306.531968) (xy 60.062736 -306.467709) (xy 60.100682 -306.407318) (xy 60.145151 -306.351556)
			(xy 60.195584 -306.301123) (xy 60.251346 -306.256654) (xy 60.311737 -306.218708) (xy 60.375996 -306.187763)
			(xy 60.443316 -306.164206) (xy 60.512851 -306.148336) (xy 60.583725 -306.14035) (xy 60.655047 -306.14035)
			(xy 60.725921 -306.148336) (xy 60.795456 -306.164206) (xy 60.862776 -306.187763) (xy 60.927035 -306.218708)
			(xy 60.987426 -306.256654) (xy 61.043188 -306.301123) (xy 61.093621 -306.351556) (xy 61.13809 -306.407318)
			(xy 61.176036 -306.467709) (xy 61.206981 -306.531968) (xy 61.230538 -306.599288) (xy 61.246408 -306.668823)
			(xy 61.254394 -306.739697) (xy 61.254894 -306.775358) (xy 61.254394 -306.811019) (xy 62.22542 -306.811019)
			(xy 62.22542 -306.739697) (xy 62.233406 -306.668823) (xy 62.249276 -306.599288) (xy 62.272833 -306.531968)
			(xy 62.303778 -306.467709) (xy 62.341724 -306.407318) (xy 62.386193 -306.351556) (xy 62.436626 -306.301123)
			(xy 62.492388 -306.256654) (xy 62.552779 -306.218708) (xy 62.617038 -306.187763) (xy 62.684358 -306.164206)
			(xy 62.753893 -306.148336) (xy 62.824767 -306.14035) (xy 62.896089 -306.14035) (xy 62.966963 -306.148336)
			(xy 63.036498 -306.164206) (xy 63.103818 -306.187763) (xy 63.168077 -306.218708) (xy 63.228468 -306.256654)
			(xy 63.28423 -306.301123) (xy 63.334663 -306.351556) (xy 63.379132 -306.407318) (xy 63.417078 -306.467709)
			(xy 63.448023 -306.531968) (xy 63.47158 -306.599288) (xy 63.48745 -306.668823) (xy 63.495436 -306.739697)
			(xy 63.495936 -306.775358) (xy 63.495436 -306.811019) (xy 64.129404 -306.811019) (xy 64.129404 -306.739697)
			(xy 64.13739 -306.668823) (xy 64.15326 -306.599288) (xy 64.176817 -306.531968) (xy 64.207762 -306.467709)
			(xy 64.245708 -306.407318) (xy 64.290177 -306.351556) (xy 64.34061 -306.301123) (xy 64.396372 -306.256654)
			(xy 64.456763 -306.218708) (xy 64.521022 -306.187763) (xy 64.588342 -306.164206) (xy 64.657877 -306.148336)
			(xy 64.728751 -306.14035) (xy 64.800073 -306.14035) (xy 64.870947 -306.148336) (xy 64.940482 -306.164206)
			(xy 65.007802 -306.187763) (xy 65.072061 -306.218708) (xy 65.132452 -306.256654) (xy 65.188214 -306.301123)
			(xy 65.238647 -306.351556) (xy 65.283116 -306.407318) (xy 65.321062 -306.467709) (xy 65.352007 -306.531968)
			(xy 65.375564 -306.599288) (xy 65.391434 -306.668823) (xy 65.39942 -306.739697) (xy 65.39992 -306.775358)
			(xy 65.39942 -306.811019) (xy 65.391434 -306.881893) (xy 65.375564 -306.951428) (xy 65.352007 -307.018748)
			(xy 65.321062 -307.083007) (xy 65.283116 -307.143398) (xy 65.238647 -307.19916) (xy 65.188214 -307.249593)
			(xy 65.132452 -307.294062) (xy 65.072061 -307.332008) (xy 65.007802 -307.362953) (xy 64.940482 -307.38651)
			(xy 64.870947 -307.40238) (xy 64.800073 -307.410366) (xy 64.728751 -307.410366) (xy 64.657877 -307.40238)
			(xy 64.588342 -307.38651) (xy 64.521022 -307.362953) (xy 64.456763 -307.332008) (xy 64.396372 -307.294062)
			(xy 64.34061 -307.249593) (xy 64.290177 -307.19916) (xy 64.245708 -307.143398) (xy 64.207762 -307.083007)
			(xy 64.176817 -307.018748) (xy 64.15326 -306.951428) (xy 64.13739 -306.881893) (xy 64.129404 -306.811019)
			(xy 63.495436 -306.811019) (xy 63.48745 -306.881893) (xy 63.47158 -306.951428) (xy 63.448023 -307.018748)
			(xy 63.417078 -307.083007) (xy 63.379132 -307.143398) (xy 63.334663 -307.19916) (xy 63.28423 -307.249593)
			(xy 63.228468 -307.294062) (xy 63.168077 -307.332008) (xy 63.103818 -307.362953) (xy 63.036498 -307.38651)
			(xy 62.966963 -307.40238) (xy 62.896089 -307.410366) (xy 62.824767 -307.410366) (xy 62.753893 -307.40238)
			(xy 62.684358 -307.38651) (xy 62.617038 -307.362953) (xy 62.552779 -307.332008) (xy 62.492388 -307.294062)
			(xy 62.436626 -307.249593) (xy 62.386193 -307.19916) (xy 62.341724 -307.143398) (xy 62.303778 -307.083007)
			(xy 62.272833 -307.018748) (xy 62.249276 -306.951428) (xy 62.233406 -306.881893) (xy 62.22542 -306.811019)
			(xy 61.254394 -306.811019) (xy 61.246408 -306.881893) (xy 61.230538 -306.951428) (xy 61.206981 -307.018748)
			(xy 61.176036 -307.083007) (xy 61.13809 -307.143398) (xy 61.093621 -307.19916) (xy 61.043188 -307.249593)
			(xy 60.987426 -307.294062) (xy 60.927035 -307.332008) (xy 60.862776 -307.362953) (xy 60.795456 -307.38651)
			(xy 60.725921 -307.40238) (xy 60.655047 -307.410366) (xy 60.583725 -307.410366) (xy 60.512851 -307.40238)
			(xy 60.443316 -307.38651) (xy 60.375996 -307.362953) (xy 60.311737 -307.332008) (xy 60.251346 -307.294062)
			(xy 60.195584 -307.249593) (xy 60.145151 -307.19916) (xy 60.100682 -307.143398) (xy 60.062736 -307.083007)
			(xy 60.031791 -307.018748) (xy 60.008234 -306.951428) (xy 59.992364 -306.881893) (xy 59.984378 -306.811019)
			(xy 59.367682 -306.811019) (xy 59.359696 -306.881893) (xy 59.343826 -306.951428) (xy 59.320269 -307.018748)
			(xy 59.289324 -307.083007) (xy 59.251378 -307.143398) (xy 59.206909 -307.19916) (xy 59.156476 -307.249593)
			(xy 59.100714 -307.294062) (xy 59.040323 -307.332008) (xy 58.976064 -307.362953) (xy 58.908744 -307.38651)
			(xy 58.839209 -307.40238) (xy 58.768335 -307.410366) (xy 58.697013 -307.410366) (xy 58.626139 -307.40238)
			(xy 58.556604 -307.38651) (xy 58.489284 -307.362953) (xy 58.425025 -307.332008) (xy 58.364634 -307.294062)
			(xy 58.308872 -307.249593) (xy 58.258439 -307.19916) (xy 58.21397 -307.143398) (xy 58.176024 -307.083007)
			(xy 58.145079 -307.018748) (xy 58.121522 -306.951428) (xy 58.105652 -306.881893) (xy 58.097666 -306.811019)
			(xy 49.30783 -306.811019) (xy 49.264724 -306.875531) (xy 49.213269 -306.93823) (xy 49.155916 -306.995583)
			(xy 49.093217 -307.047038) (xy 49.025777 -307.0921) (xy 48.954245 -307.130335) (xy 48.879309 -307.161374)
			(xy 48.801693 -307.184919) (xy 48.722142 -307.200742) (xy 48.641423 -307.208692) (xy 48.560313 -307.208692)
			(xy 48.479594 -307.200742) (xy 48.400043 -307.184919) (xy 48.322427 -307.161374) (xy 48.247491 -307.130335)
			(xy 48.175959 -307.0921) (xy 48.108519 -307.047038) (xy 48.04582 -306.995583) (xy 47.988467 -306.93823)
			(xy 47.937012 -306.875531) (xy 47.89195 -306.808091) (xy 47.853715 -306.736559) (xy 47.822676 -306.661623)
			(xy 47.799131 -306.584007) (xy 47.783308 -306.504456) (xy 47.775358 -306.423737) (xy 29.614876 -306.423737)
			(xy 29.614876 -306.852066) (xy 29.61535 -306.874174) (xy 29.623 -306.917722) (xy 29.638074 -306.959288)
			(xy 29.660116 -306.997616) (xy 29.688462 -307.03155) (xy 29.722255 -307.060063) (xy 29.760474 -307.082294)
			(xy 29.801966 -307.097573) (xy 29.845475 -307.105438) (xy 29.88969 -307.10565) (xy 29.933273 -307.098204)
			(xy 29.974909 -307.083324) (xy 29.994352 -307.072792) (xy 30.032527 -307.051621) (xy 30.112065 -307.015636)
			(xy 30.194595 -306.987178) (xy 30.279409 -306.966492) (xy 30.365774 -306.953756) (xy 30.452948 -306.94908)
			(xy 30.54018 -306.952504) (xy 30.626719 -306.963999) (xy 30.711821 -306.983466) (xy 30.794751 -307.010737)
			(xy 30.874797 -307.045577) (xy 30.951269 -307.087686) (xy 31.023509 -307.136702) (xy 31.090895 -307.192203)
			(xy 31.152846 -307.253711) (xy 31.208829 -307.320696) (xy 31.258363 -307.392582) (xy 31.301021 -307.46875)
			(xy 31.336435 -307.548543) (xy 31.3643 -307.631276) (xy 31.384377 -307.716235) (xy 31.396494 -307.80269)
			(xy 31.400544 -307.889895) (xy 31.398525 -307.93336) (xy 34.599874 -307.93336) (xy 34.599874 -307.84646)
			(xy 34.607892 -307.759931) (xy 34.62386 -307.674511) (xy 34.647641 -307.590929) (xy 34.679033 -307.509897)
			(xy 34.717767 -307.432108) (xy 34.763514 -307.358224) (xy 34.815883 -307.288877) (xy 34.874427 -307.224657)
			(xy 34.938647 -307.166113) (xy 35.007994 -307.113744) (xy 35.081878 -307.067997) (xy 35.159667 -307.029263)
			(xy 35.240699 -306.997871) (xy 35.324281 -306.97409) (xy 35.409701 -306.958122) (xy 35.49623 -306.950104)
			(xy 35.58313 -306.950104) (xy 35.669659 -306.958122) (xy 35.755079 -306.97409) (xy 35.838661 -306.997871)
			(xy 35.919693 -307.029263) (xy 35.997482 -307.067997) (xy 36.071366 -307.113744) (xy 36.140713 -307.166113)
			(xy 36.204933 -307.224657) (xy 36.263477 -307.288877) (xy 36.315846 -307.358224) (xy 36.353945 -307.419756)
			(xy 70.499732 -307.419756) (xy 70.499732 -306.521358) (xy 70.500199 -306.490178) (xy 70.507822 -306.428287)
			(xy 70.522958 -306.367792) (xy 70.545382 -306.309605) (xy 70.574757 -306.254597) (xy 70.61064 -306.203597)
			(xy 70.652494 -306.15737) (xy 70.699689 -306.11661) (xy 70.751515 -306.081931) (xy 70.807195 -306.053852)
			(xy 70.865892 -306.032797) (xy 70.926724 -306.019081) (xy 70.988778 -306.01291) (xy 71.05112 -306.014377)
			(xy 71.112814 -306.023461) (xy 71.172933 -306.040024) (xy 71.230575 -306.063817) (xy 71.284872 -306.094484)
			(xy 71.33501 -306.131563) (xy 71.380234 -306.174498) (xy 71.400416 -306.19827) (xy 71.415043 -306.215285)
			(xy 71.449197 -306.244379) (xy 71.487926 -306.267029) (xy 71.530028 -306.28253) (xy 71.574198 -306.290403)
			(xy 71.619064 -306.290403) (xy 71.663234 -306.28253) (xy 71.705336 -306.267029) (xy 71.744065 -306.244379)
			(xy 71.778219 -306.215285) (xy 71.792846 -306.19827) (xy 71.812994 -306.174597) (xy 71.858046 -306.131765)
			(xy 71.907986 -306.094748) (xy 71.962068 -306.064097) (xy 72.019484 -306.040272) (xy 72.079377 -306.023627)
			(xy 72.140854 -306.01441) (xy 72.202995 -306.012761) (xy 72.264874 -306.018702) (xy 72.325566 -306.032146)
			(xy 72.384165 -306.052892) (xy 72.439797 -306.08063) (xy 72.491631 -306.114945) (xy 72.538892 -306.155326)
			(xy 72.580876 -306.20117) (xy 72.599296 -306.22621) (xy 72.61243 -306.243839) (xy 72.643722 -306.274713)
			(xy 72.679862 -306.299738) (xy 72.719772 -306.318166) (xy 72.762258 -306.329449) (xy 72.806052 -306.333247)
			(xy 72.849846 -306.329449) (xy 72.892332 -306.318166) (xy 72.932242 -306.299738) (xy 72.968382 -306.274713)
			(xy 72.999674 -306.243839) (xy 73.012808 -306.22621) (xy 73.031501 -306.200872) (xy 73.074115 -306.154516)
			(xy 73.122126 -306.113777) (xy 73.1748 -306.079278) (xy 73.231332 -306.051547) (xy 73.290854 -306.031007)
			(xy 73.352457 -306.017975) (xy 73.415198 -306.012649) (xy 73.478116 -306.01511) (xy 73.540249 -306.025321)
			(xy 73.600646 -306.043126) (xy 73.658382 -306.068252) (xy 73.712574 -306.100314) (xy 73.762393 -306.138823)
			(xy 73.807075 -306.183188) (xy 73.826878 -306.207668) (xy 73.841485 -306.225499) (xy 73.875985 -306.256061)
			(xy 73.915428 -306.279904) (xy 73.958523 -306.296247) (xy 74.003858 -306.304555) (xy 74.049948 -306.304555)
			(xy 74.095283 -306.296247) (xy 74.138378 -306.279904) (xy 74.177821 -306.256061) (xy 74.212321 -306.225499)
			(xy 74.226928 -306.207668) (xy 74.246732 -306.183192) (xy 74.291412 -306.138829) (xy 74.341229 -306.100325)
			(xy 74.395419 -306.068267) (xy 74.453154 -306.043148) (xy 74.51355 -306.025351) (xy 74.57568 -306.01515)
			(xy 74.638595 -306.0127) (xy 74.701331 -306.018039) (xy 74.762928 -306.031085) (xy 74.822441 -306.051638)
			(xy 74.878961 -306.079384) (xy 74.931621 -306.113898) (xy 74.979615 -306.154652) (xy 75.022209 -306.20102)
			(xy 75.05875 -306.252295) (xy 75.088679 -306.307689) (xy 75.111538 -306.366356) (xy 75.126976 -306.427397)
			(xy 75.134757 -306.489877) (xy 75.135232 -306.521358) (xy 75.135232 -307.419756) (xy 75.134708 -307.452482)
			(xy 75.126319 -307.517393) (xy 75.109674 -307.580692) (xy 75.085048 -307.641333) (xy 75.052848 -307.698315)
			(xy 75.033632 -307.72481) (xy 75.008232 -307.758592) (xy 75.008232 -307.775864) (xy 74.992992 -307.775864)
			(xy 74.957178 -307.80609) (xy 74.932001 -307.826943) (xy 74.877269 -307.862694) (xy 74.818404 -307.891133)
			(xy 74.756379 -307.911788) (xy 74.692217 -307.924319) (xy 74.626978 -307.928519) (xy 74.561739 -307.924319)
			(xy 74.497577 -307.911788) (xy 74.435552 -307.891133) (xy 74.376687 -307.862694) (xy 74.321955 -307.826943)
			(xy 74.296778 -307.80609) (xy 74.260964 -307.775864) (xy 74.245724 -307.775864) (xy 74.245724 -307.758592)
			(xy 74.220324 -307.72481) (xy 74.197373 -307.692978) (xy 74.160507 -307.623703) (xy 74.146918 -307.586888)
			(xy 74.14133 -307.572163) (xy 74.124066 -307.545832) (xy 74.100875 -307.524536) (xy 74.073171 -307.509573)
			(xy 74.042646 -307.501856) (xy 74.01116 -307.501856) (xy 73.980635 -307.509573) (xy 73.952931 -307.524536)
			(xy 73.92974 -307.545832) (xy 73.912476 -307.572163) (xy 73.906888 -307.586888) (xy 73.893318 -307.623712)
			(xy 73.856447 -307.692986) (xy 73.833482 -307.72481) (xy 73.808336 -307.758592) (xy 73.808336 -307.775864)
			(xy 73.792842 -307.775864) (xy 73.757028 -307.80609) (xy 73.731851 -307.826943) (xy 73.677119 -307.862694)
			(xy 73.618254 -307.891133) (xy 73.556229 -307.911788) (xy 73.492067 -307.924319) (xy 73.426828 -307.928519)
			(xy 73.361589 -307.924319) (xy 73.297427 -307.911788) (xy 73.235402 -307.891133) (xy 73.176537 -307.862694)
			(xy 73.121805 -307.826943) (xy 73.096628 -307.80609) (xy 73.060814 -307.775864) (xy 73.04532 -307.775864)
			(xy 73.04532 -307.758592) (xy 73.020174 -307.72481) (xy 73.012808 -307.714904) (xy 72.999674 -307.697275)
			(xy 72.968382 -307.666401) (xy 72.932242 -307.641376) (xy 72.892332 -307.622948) (xy 72.849846 -307.611665)
			(xy 72.806052 -307.607867) (xy 72.762258 -307.611665) (xy 72.719772 -307.622948) (xy 72.679862 -307.641376)
			(xy 72.643722 -307.666401) (xy 72.61243 -307.697275) (xy 72.599296 -307.714904) (xy 72.59193 -307.72481)
			(xy 72.566784 -307.758592) (xy 72.566784 -307.775864) (xy 72.55129 -307.775864) (xy 72.515476 -307.80609)
			(xy 72.490299 -307.826943) (xy 72.435567 -307.862694) (xy 72.376702 -307.891133) (xy 72.314677 -307.911788)
			(xy 72.250515 -307.924319) (xy 72.185276 -307.928519) (xy 72.120037 -307.924319) (xy 72.055875 -307.911788)
			(xy 71.99385 -307.891133) (xy 71.934985 -307.862694) (xy 71.880253 -307.826943) (xy 71.855076 -307.80609)
			(xy 71.819262 -307.775864) (xy 71.803768 -307.775864) (xy 71.803768 -307.758592) (xy 71.778622 -307.72481)
			(xy 71.759381 -307.698274) (xy 71.727147 -307.641199) (xy 71.71436 -307.611018) (xy 71.707583 -307.59568)
			(xy 71.687319 -307.568977) (xy 71.660803 -307.548468) (xy 71.629862 -307.535569) (xy 71.596631 -307.531168)
			(xy 71.5634 -307.535569) (xy 71.532459 -307.548468) (xy 71.505943 -307.568977) (xy 71.485679 -307.59568)
			(xy 71.478902 -307.611018) (xy 71.46611 -307.641197) (xy 71.433879 -307.698273) (xy 71.41464 -307.72481)
			(xy 71.38924 -307.758592) (xy 71.38924 -307.775864) (xy 71.374 -307.775864) (xy 71.338186 -307.80609)
			(xy 71.313009 -307.826943) (xy 71.258277 -307.862694) (xy 71.199412 -307.891133) (xy 71.137387 -307.911788)
			(xy 71.073225 -307.924319) (xy 71.007986 -307.928519) (xy 70.942747 -307.924319) (xy 70.878585 -307.911788)
			(xy 70.81656 -307.891133) (xy 70.757695 -307.862694) (xy 70.702963 -307.826943) (xy 70.677786 -307.80609)
			(xy 70.641972 -307.775864) (xy 70.626732 -307.775864) (xy 70.626732 -307.758592) (xy 70.601332 -307.72481)
			(xy 70.582093 -307.698329) (xy 70.549866 -307.641354) (xy 70.525228 -307.580711) (xy 70.508587 -307.517405)
			(xy 70.50022 -307.452485) (xy 70.499732 -307.419756) (xy 36.353945 -307.419756) (xy 36.361593 -307.432108)
			(xy 36.400327 -307.509897) (xy 36.431719 -307.590929) (xy 36.4555 -307.674511) (xy 36.471468 -307.759931)
			(xy 36.479486 -307.84646) (xy 36.479988 -307.88991) (xy 36.479486 -307.93336) (xy 36.471468 -308.019889)
			(xy 36.4555 -308.105309) (xy 36.431719 -308.188891) (xy 36.400327 -308.269923) (xy 36.361593 -308.347712)
			(xy 36.315846 -308.421596) (xy 36.263477 -308.490943) (xy 36.204933 -308.555163) (xy 36.140713 -308.613707)
			(xy 36.071366 -308.666076) (xy 35.997482 -308.711823) (xy 35.979363 -308.720845) (xy 58.097666 -308.720845)
			(xy 58.097666 -308.649523) (xy 58.105652 -308.578649) (xy 58.121522 -308.509114) (xy 58.145079 -308.441794)
			(xy 58.176024 -308.377535) (xy 58.21397 -308.317144) (xy 58.258439 -308.261382) (xy 58.308872 -308.210949)
			(xy 58.364634 -308.16648) (xy 58.425025 -308.128534) (xy 58.489284 -308.097589) (xy 58.556604 -308.074032)
			(xy 58.626139 -308.058162) (xy 58.697013 -308.050176) (xy 58.768335 -308.050176) (xy 58.839209 -308.058162)
			(xy 58.908744 -308.074032) (xy 58.976064 -308.097589) (xy 59.040323 -308.128534) (xy 59.100714 -308.16648)
			(xy 59.156476 -308.210949) (xy 59.206909 -308.261382) (xy 59.251378 -308.317144) (xy 59.289324 -308.377535)
			(xy 59.320269 -308.441794) (xy 59.343826 -308.509114) (xy 59.359696 -308.578649) (xy 59.367682 -308.649523)
			(xy 59.368182 -308.685184) (xy 59.367682 -308.720845) (xy 59.984378 -308.720845) (xy 59.984378 -308.649523)
			(xy 59.992364 -308.578649) (xy 60.008234 -308.509114) (xy 60.031791 -308.441794) (xy 60.062736 -308.377535)
			(xy 60.100682 -308.317144) (xy 60.145151 -308.261382) (xy 60.195584 -308.210949) (xy 60.251346 -308.16648)
			(xy 60.311737 -308.128534) (xy 60.375996 -308.097589) (xy 60.443316 -308.074032) (xy 60.512851 -308.058162)
			(xy 60.583725 -308.050176) (xy 60.655047 -308.050176) (xy 60.725921 -308.058162) (xy 60.795456 -308.074032)
			(xy 60.862776 -308.097589) (xy 60.927035 -308.128534) (xy 60.987426 -308.16648) (xy 61.043188 -308.210949)
			(xy 61.093621 -308.261382) (xy 61.13809 -308.317144) (xy 61.176036 -308.377535) (xy 61.206981 -308.441794)
			(xy 61.230538 -308.509114) (xy 61.246408 -308.578649) (xy 61.254394 -308.649523) (xy 61.254894 -308.685184)
			(xy 61.254394 -308.720845) (xy 62.22542 -308.720845) (xy 62.22542 -308.649523) (xy 62.233406 -308.578649)
			(xy 62.249276 -308.509114) (xy 62.272833 -308.441794) (xy 62.303778 -308.377535) (xy 62.341724 -308.317144)
			(xy 62.386193 -308.261382) (xy 62.436626 -308.210949) (xy 62.492388 -308.16648) (xy 62.552779 -308.128534)
			(xy 62.617038 -308.097589) (xy 62.684358 -308.074032) (xy 62.753893 -308.058162) (xy 62.824767 -308.050176)
			(xy 62.896089 -308.050176) (xy 62.966963 -308.058162) (xy 63.036498 -308.074032) (xy 63.103818 -308.097589)
			(xy 63.168077 -308.128534) (xy 63.228468 -308.16648) (xy 63.28423 -308.210949) (xy 63.334663 -308.261382)
			(xy 63.379132 -308.317144) (xy 63.417078 -308.377535) (xy 63.448023 -308.441794) (xy 63.47158 -308.509114)
			(xy 63.48745 -308.578649) (xy 63.495436 -308.649523) (xy 63.495936 -308.685184) (xy 63.495436 -308.720845)
			(xy 64.129404 -308.720845) (xy 64.129404 -308.649523) (xy 64.13739 -308.578649) (xy 64.15326 -308.509114)
			(xy 64.176817 -308.441794) (xy 64.207762 -308.377535) (xy 64.245708 -308.317144) (xy 64.290177 -308.261382)
			(xy 64.34061 -308.210949) (xy 64.396372 -308.16648) (xy 64.456763 -308.128534) (xy 64.521022 -308.097589)
			(xy 64.588342 -308.074032) (xy 64.657877 -308.058162) (xy 64.728751 -308.050176) (xy 64.800073 -308.050176)
			(xy 64.870947 -308.058162) (xy 64.940482 -308.074032) (xy 65.007802 -308.097589) (xy 65.072061 -308.128534)
			(xy 65.132452 -308.16648) (xy 65.188214 -308.210949) (xy 65.238647 -308.261382) (xy 65.283116 -308.317144)
			(xy 65.321062 -308.377535) (xy 65.352007 -308.441794) (xy 65.375564 -308.509114) (xy 65.391434 -308.578649)
			(xy 65.39942 -308.649523) (xy 65.39992 -308.685184) (xy 65.39942 -308.720845) (xy 65.391434 -308.791719)
			(xy 65.375564 -308.861254) (xy 65.352007 -308.928574) (xy 65.321062 -308.992833) (xy 65.283116 -309.053224)
			(xy 65.238647 -309.108986) (xy 65.188214 -309.159419) (xy 65.132452 -309.203888) (xy 65.072061 -309.241834)
			(xy 65.007802 -309.272779) (xy 64.940482 -309.296336) (xy 64.870947 -309.312206) (xy 64.800073 -309.320192)
			(xy 64.728751 -309.320192) (xy 64.657877 -309.312206) (xy 64.588342 -309.296336) (xy 64.521022 -309.272779)
			(xy 64.456763 -309.241834) (xy 64.396372 -309.203888) (xy 64.34061 -309.159419) (xy 64.290177 -309.108986)
			(xy 64.245708 -309.053224) (xy 64.207762 -308.992833) (xy 64.176817 -308.928574) (xy 64.15326 -308.861254)
			(xy 64.13739 -308.791719) (xy 64.129404 -308.720845) (xy 63.495436 -308.720845) (xy 63.48745 -308.791719)
			(xy 63.47158 -308.861254) (xy 63.448023 -308.928574) (xy 63.417078 -308.992833) (xy 63.379132 -309.053224)
			(xy 63.334663 -309.108986) (xy 63.28423 -309.159419) (xy 63.228468 -309.203888) (xy 63.168077 -309.241834)
			(xy 63.103818 -309.272779) (xy 63.036498 -309.296336) (xy 62.966963 -309.312206) (xy 62.896089 -309.320192)
			(xy 62.824767 -309.320192) (xy 62.753893 -309.312206) (xy 62.684358 -309.296336) (xy 62.617038 -309.272779)
			(xy 62.552779 -309.241834) (xy 62.492388 -309.203888) (xy 62.436626 -309.159419) (xy 62.386193 -309.108986)
			(xy 62.341724 -309.053224) (xy 62.303778 -308.992833) (xy 62.272833 -308.928574) (xy 62.249276 -308.861254)
			(xy 62.233406 -308.791719) (xy 62.22542 -308.720845) (xy 61.254394 -308.720845) (xy 61.246408 -308.791719)
			(xy 61.230538 -308.861254) (xy 61.206981 -308.928574) (xy 61.176036 -308.992833) (xy 61.13809 -309.053224)
			(xy 61.093621 -309.108986) (xy 61.043188 -309.159419) (xy 60.987426 -309.203888) (xy 60.927035 -309.241834)
			(xy 60.862776 -309.272779) (xy 60.795456 -309.296336) (xy 60.725921 -309.312206) (xy 60.655047 -309.320192)
			(xy 60.583725 -309.320192) (xy 60.512851 -309.312206) (xy 60.443316 -309.296336) (xy 60.375996 -309.272779)
			(xy 60.311737 -309.241834) (xy 60.251346 -309.203888) (xy 60.195584 -309.159419) (xy 60.145151 -309.108986)
			(xy 60.100682 -309.053224) (xy 60.062736 -308.992833) (xy 60.031791 -308.928574) (xy 60.008234 -308.861254)
			(xy 59.992364 -308.791719) (xy 59.984378 -308.720845) (xy 59.367682 -308.720845) (xy 59.359696 -308.791719)
			(xy 59.343826 -308.861254) (xy 59.320269 -308.928574) (xy 59.289324 -308.992833) (xy 59.251378 -309.053224)
			(xy 59.206909 -309.108986) (xy 59.156476 -309.159419) (xy 59.100714 -309.203888) (xy 59.040323 -309.241834)
			(xy 58.976064 -309.272779) (xy 58.908744 -309.296336) (xy 58.839209 -309.312206) (xy 58.768335 -309.320192)
			(xy 58.697013 -309.320192) (xy 58.626139 -309.312206) (xy 58.556604 -309.296336) (xy 58.489284 -309.272779)
			(xy 58.425025 -309.241834) (xy 58.364634 -309.203888) (xy 58.308872 -309.159419) (xy 58.258439 -309.108986)
			(xy 58.21397 -309.053224) (xy 58.176024 -308.992833) (xy 58.145079 -308.928574) (xy 58.121522 -308.861254)
			(xy 58.105652 -308.791719) (xy 58.097666 -308.720845) (xy 35.979363 -308.720845) (xy 35.919693 -308.750557)
			(xy 35.838661 -308.781949) (xy 35.755079 -308.80573) (xy 35.669659 -308.821698) (xy 35.58313 -308.829716)
			(xy 35.49623 -308.829716) (xy 35.409701 -308.821698) (xy 35.324281 -308.80573) (xy 35.240699 -308.781949)
			(xy 35.159667 -308.750557) (xy 35.081878 -308.711823) (xy 35.007994 -308.666076) (xy 34.938647 -308.613707)
			(xy 34.874427 -308.555163) (xy 34.815883 -308.490943) (xy 34.763514 -308.421596) (xy 34.717767 -308.347712)
			(xy 34.679033 -308.269923) (xy 34.647641 -308.188891) (xy 34.62386 -308.105309) (xy 34.607892 -308.019889)
			(xy 34.599874 -307.93336) (xy 31.398525 -307.93336) (xy 31.396494 -307.9771) (xy 31.384379 -308.063555)
			(xy 31.364303 -308.148514) (xy 31.336438 -308.231247) (xy 31.301025 -308.311041) (xy 31.258368 -308.38721)
			(xy 31.208835 -308.459096) (xy 31.152853 -308.526082) (xy 31.090902 -308.58759) (xy 31.023517 -308.643092)
			(xy 30.951278 -308.692109) (xy 30.874806 -308.734219) (xy 30.79476 -308.76906) (xy 30.71183 -308.796332)
			(xy 30.626729 -308.815799) (xy 30.54019 -308.827295) (xy 30.452958 -308.83072) (xy 30.365784 -308.826045)
			(xy 30.279418 -308.81331) (xy 30.194605 -308.792625) (xy 30.112074 -308.764168) (xy 30.032536 -308.728183)
			(xy 29.994352 -308.707028) (xy 29.9749 -308.696527) (xy 29.933268 -308.681677) (xy 29.889696 -308.674253)
			(xy 29.845495 -308.67448) (xy 29.802001 -308.682352) (xy 29.760525 -308.69763) (xy 29.722318 -308.719855)
			(xy 29.688532 -308.748354) (xy 29.660187 -308.78227) (xy 29.638137 -308.820578) (xy 29.623049 -308.862124)
			(xy 29.615376 -308.905654) (xy 29.614876 -308.927754) (xy 29.614876 -309.392066) (xy 29.61535 -309.414174)
			(xy 29.623 -309.457722) (xy 29.638074 -309.499288) (xy 29.660116 -309.537616) (xy 29.688462 -309.57155)
			(xy 29.722255 -309.600063) (xy 29.760474 -309.622294) (xy 29.801966 -309.637573) (xy 29.845475 -309.645438)
			(xy 29.88969 -309.64565) (xy 29.933273 -309.638204) (xy 29.974909 -309.623324) (xy 29.994352 -309.612792)
			(xy 30.032129 -309.591839) (xy 30.110804 -309.556148) (xy 30.192421 -309.527824) (xy 30.276292 -309.507107)
			(xy 30.36171 -309.49417) (xy 30.447955 -309.489124) (xy 30.534299 -309.49201) (xy 30.620014 -309.502804)
			(xy 30.704378 -309.521416) (xy 30.786678 -309.547688) (xy 30.866222 -309.581399) (xy 30.942338 -309.622264)
			(xy 31.014384 -309.66994) (xy 31.081753 -309.724023) (xy 31.143877 -309.784058) (xy 31.200232 -309.849538)
			(xy 31.250343 -309.919912) (xy 31.293787 -309.994587) (xy 31.330197 -310.072931) (xy 31.359268 -310.154285)
			(xy 31.380753 -310.237963) (xy 31.394472 -310.323259) (xy 31.400309 -310.409454) (xy 31.398759 -310.47336)
			(xy 34.599874 -310.47336) (xy 34.599874 -310.38646) (xy 34.607892 -310.299931) (xy 34.62386 -310.214511)
			(xy 34.647641 -310.130929) (xy 34.679033 -310.049897) (xy 34.717767 -309.972108) (xy 34.763514 -309.898224)
			(xy 34.815883 -309.828877) (xy 34.874427 -309.764657) (xy 34.938647 -309.706113) (xy 35.007994 -309.653744)
			(xy 35.081878 -309.607997) (xy 35.159667 -309.569263) (xy 35.240699 -309.537871) (xy 35.324281 -309.51409)
			(xy 35.409701 -309.498122) (xy 35.49623 -309.490104) (xy 35.58313 -309.490104) (xy 35.669659 -309.498122)
			(xy 35.755079 -309.51409) (xy 35.838661 -309.537871) (xy 35.919693 -309.569263) (xy 35.997482 -309.607997)
			(xy 36.071366 -309.653744) (xy 36.140713 -309.706113) (xy 36.204933 -309.764657) (xy 36.263477 -309.828877)
			(xy 36.315846 -309.898224) (xy 36.361593 -309.972108) (xy 36.400327 -310.049897) (xy 36.431719 -310.130929)
			(xy 36.4555 -310.214511) (xy 36.471468 -310.299931) (xy 36.479486 -310.38646) (xy 36.479988 -310.42991)
			(xy 36.479486 -310.47336) (xy 36.471468 -310.559889) (xy 36.4555 -310.645309) (xy 36.431719 -310.728891)
			(xy 36.400327 -310.809923) (xy 36.361593 -310.887712) (xy 36.315846 -310.961596) (xy 36.263477 -311.030943)
			(xy 36.204933 -311.095163) (xy 36.140713 -311.153707) (xy 36.071366 -311.206076) (xy 35.997482 -311.251823)
			(xy 35.919693 -311.290557) (xy 35.838661 -311.321949) (xy 35.755079 -311.34573) (xy 35.669659 -311.361698)
			(xy 35.58313 -311.369716) (xy 35.49623 -311.369716) (xy 35.409701 -311.361698) (xy 35.324281 -311.34573)
			(xy 35.240699 -311.321949) (xy 35.159667 -311.290557) (xy 35.081878 -311.251823) (xy 35.007994 -311.206076)
			(xy 34.938647 -311.153707) (xy 34.874427 -311.095163) (xy 34.815883 -311.030943) (xy 34.763514 -310.961596)
			(xy 34.717767 -310.887712) (xy 34.679033 -310.809923) (xy 34.647641 -310.728891) (xy 34.62386 -310.645309)
			(xy 34.607892 -310.559889) (xy 34.599874 -310.47336) (xy 31.398759 -310.47336) (xy 31.398214 -310.49582)
			(xy 31.388206 -310.581631) (xy 31.370368 -310.666161) (xy 31.344851 -310.748699) (xy 31.311871 -310.828548)
			(xy 31.271705 -310.905036) (xy 31.224692 -310.977516) (xy 31.171229 -311.045378) (xy 31.111765 -311.108049)
			(xy 31.046804 -311.165002) (xy 30.976892 -311.215756) (xy 30.902619 -311.259882) (xy 30.824612 -311.29701)
			(xy 30.743528 -311.326825) (xy 30.66005 -311.349076) (xy 30.574884 -311.363576) (xy 30.488746 -311.370203)
			(xy 30.402364 -311.368899) (xy 30.316465 -311.359678) (xy 30.231775 -311.342616) (xy 30.149007 -311.317857)
			(xy 30.068858 -311.285609) (xy 29.992006 -311.246146) (xy 29.919098 -311.199799) (xy 29.850749 -311.14696)
			(xy 29.787535 -311.088074) (xy 29.729989 -311.023637) (xy 29.678597 -310.954194) (xy 29.633792 -310.880328)
			(xy 29.595951 -310.802664) (xy 29.565394 -310.721857) (xy 29.553408 -310.680354) (xy 29.547071 -310.659177)
			(xy 29.528119 -310.619247) (xy 29.502543 -310.5832) (xy 29.471115 -310.552122) (xy 29.434782 -310.526952)
			(xy 29.394642 -310.508449) (xy 29.351906 -310.497172) (xy 29.307863 -310.493461) (xy 29.263842 -310.497427)
			(xy 29.221172 -310.508952) (xy 29.18114 -310.527687) (xy 29.144954 -310.553067) (xy 29.128974 -310.56834)
			(xy 28.067 -311.630314) (xy 28.067 -313.01336) (xy 29.519874 -313.01336) (xy 29.519874 -312.92646)
			(xy 29.527892 -312.839931) (xy 29.54386 -312.754511) (xy 29.567641 -312.670929) (xy 29.599033 -312.589897)
			(xy 29.637767 -312.512108) (xy 29.683514 -312.438224) (xy 29.735883 -312.368877) (xy 29.794427 -312.304657)
			(xy 29.858647 -312.246113) (xy 29.927994 -312.193744) (xy 30.001878 -312.147997) (xy 30.079667 -312.109263)
			(xy 30.160699 -312.077871) (xy 30.244281 -312.05409) (xy 30.329701 -312.038122) (xy 30.41623 -312.030104)
			(xy 30.50313 -312.030104) (xy 30.589659 -312.038122) (xy 30.675079 -312.05409) (xy 30.758661 -312.077871)
			(xy 30.839693 -312.109263) (xy 30.917482 -312.147997) (xy 30.991366 -312.193744) (xy 31.060713 -312.246113)
			(xy 31.124933 -312.304657) (xy 31.183477 -312.368877) (xy 31.235846 -312.438224) (xy 31.281593 -312.512108)
			(xy 31.320327 -312.589897) (xy 31.351719 -312.670929) (xy 31.3755 -312.754511) (xy 31.391468 -312.839931)
			(xy 31.399486 -312.92646) (xy 31.399988 -312.96991) (xy 31.399486 -313.01336) (xy 34.599874 -313.01336)
			(xy 34.599874 -312.92646) (xy 34.607892 -312.839931) (xy 34.62386 -312.754511) (xy 34.647641 -312.670929)
			(xy 34.679033 -312.589897) (xy 34.717767 -312.512108) (xy 34.763514 -312.438224) (xy 34.815883 -312.368877)
			(xy 34.874427 -312.304657) (xy 34.938647 -312.246113) (xy 35.007994 -312.193744) (xy 35.081878 -312.147997)
			(xy 35.159667 -312.109263) (xy 35.240699 -312.077871) (xy 35.324281 -312.05409) (xy 35.409701 -312.038122)
			(xy 35.49623 -312.030104) (xy 35.58313 -312.030104) (xy 35.669659 -312.038122) (xy 35.755079 -312.05409)
			(xy 35.838661 -312.077871) (xy 35.919693 -312.109263) (xy 35.997482 -312.147997) (xy 36.071366 -312.193744)
			(xy 36.140713 -312.246113) (xy 36.204933 -312.304657) (xy 36.263477 -312.368877) (xy 36.315846 -312.438224)
			(xy 36.361593 -312.512108) (xy 36.400327 -312.589897) (xy 36.431719 -312.670929) (xy 36.4555 -312.754511)
			(xy 36.471468 -312.839931) (xy 36.479486 -312.92646) (xy 36.479988 -312.96991) (xy 36.479486 -313.01336)
			(xy 36.471468 -313.099889) (xy 36.4555 -313.185309) (xy 36.431719 -313.268891) (xy 36.400327 -313.349923)
			(xy 36.361593 -313.427712) (xy 36.315846 -313.501596) (xy 36.263477 -313.570943) (xy 36.204933 -313.635163)
			(xy 36.140713 -313.693707) (xy 36.071366 -313.746076) (xy 35.997482 -313.791823) (xy 35.919693 -313.830557)
			(xy 35.838661 -313.861949) (xy 35.755079 -313.88573) (xy 35.669659 -313.901698) (xy 35.58313 -313.909716)
			(xy 35.49623 -313.909716) (xy 35.409701 -313.901698) (xy 35.324281 -313.88573) (xy 35.240699 -313.861949)
			(xy 35.159667 -313.830557) (xy 35.081878 -313.791823) (xy 35.007994 -313.746076) (xy 34.938647 -313.693707)
			(xy 34.874427 -313.635163) (xy 34.815883 -313.570943) (xy 34.763514 -313.501596) (xy 34.717767 -313.427712)
			(xy 34.679033 -313.349923) (xy 34.647641 -313.268891) (xy 34.62386 -313.185309) (xy 34.607892 -313.099889)
			(xy 34.599874 -313.01336) (xy 31.399486 -313.01336) (xy 31.391468 -313.099889) (xy 31.3755 -313.185309)
			(xy 31.351719 -313.268891) (xy 31.320327 -313.349923) (xy 31.281593 -313.427712) (xy 31.235846 -313.501596)
			(xy 31.183477 -313.570943) (xy 31.124933 -313.635163) (xy 31.060713 -313.693707) (xy 30.991366 -313.746076)
			(xy 30.917482 -313.791823) (xy 30.839693 -313.830557) (xy 30.758661 -313.861949) (xy 30.675079 -313.88573)
			(xy 30.589659 -313.901698) (xy 30.50313 -313.909716) (xy 30.41623 -313.909716) (xy 30.329701 -313.901698)
			(xy 30.244281 -313.88573) (xy 30.160699 -313.861949) (xy 30.079667 -313.830557) (xy 30.001878 -313.791823)
			(xy 29.927994 -313.746076) (xy 29.858647 -313.693707) (xy 29.794427 -313.635163) (xy 29.735883 -313.570943)
			(xy 29.683514 -313.501596) (xy 29.637767 -313.427712) (xy 29.599033 -313.349923) (xy 29.567641 -313.268891)
			(xy 29.54386 -313.185309) (xy 29.527892 -313.099889) (xy 29.519874 -313.01336) (xy 28.067 -313.01336)
			(xy 28.067 -315.55336) (xy 29.519874 -315.55336) (xy 29.519874 -315.46646) (xy 29.527892 -315.379931)
			(xy 29.54386 -315.294511) (xy 29.567641 -315.210929) (xy 29.599033 -315.129897) (xy 29.637767 -315.052108)
			(xy 29.683514 -314.978224) (xy 29.735883 -314.908877) (xy 29.794427 -314.844657) (xy 29.858647 -314.786113)
			(xy 29.927994 -314.733744) (xy 30.001878 -314.687997) (xy 30.079667 -314.649263) (xy 30.160699 -314.617871)
			(xy 30.244281 -314.59409) (xy 30.329701 -314.578122) (xy 30.41623 -314.570104) (xy 30.50313 -314.570104)
			(xy 30.589659 -314.578122) (xy 30.675079 -314.59409) (xy 30.758661 -314.617871) (xy 30.839693 -314.649263)
			(xy 30.917482 -314.687997) (xy 30.991366 -314.733744) (xy 31.060713 -314.786113) (xy 31.124933 -314.844657)
			(xy 31.183477 -314.908877) (xy 31.235846 -314.978224) (xy 31.281593 -315.052108) (xy 31.320327 -315.129897)
			(xy 31.351719 -315.210929) (xy 31.3755 -315.294511) (xy 31.391468 -315.379931) (xy 31.399486 -315.46646)
			(xy 31.399988 -315.50991) (xy 31.399486 -315.55336) (xy 34.599874 -315.55336) (xy 34.599874 -315.46646)
			(xy 34.607892 -315.379931) (xy 34.62386 -315.294511) (xy 34.647641 -315.210929) (xy 34.679033 -315.129897)
			(xy 34.717767 -315.052108) (xy 34.763514 -314.978224) (xy 34.815883 -314.908877) (xy 34.874427 -314.844657)
			(xy 34.938647 -314.786113) (xy 35.007994 -314.733744) (xy 35.081878 -314.687997) (xy 35.159667 -314.649263)
			(xy 35.240699 -314.617871) (xy 35.324281 -314.59409) (xy 35.409701 -314.578122) (xy 35.49623 -314.570104)
			(xy 35.58313 -314.570104) (xy 35.669659 -314.578122) (xy 35.755079 -314.59409) (xy 35.838661 -314.617871)
			(xy 35.919693 -314.649263) (xy 35.997482 -314.687997) (xy 36.071366 -314.733744) (xy 36.140713 -314.786113)
			(xy 36.204933 -314.844657) (xy 36.263477 -314.908877) (xy 36.315846 -314.978224) (xy 36.361593 -315.052108)
			(xy 36.400327 -315.129897) (xy 36.431719 -315.210929) (xy 36.4555 -315.294511) (xy 36.471468 -315.379931)
			(xy 36.479486 -315.46646) (xy 36.479988 -315.50991) (xy 36.479486 -315.55336) (xy 36.471468 -315.639889)
			(xy 36.4555 -315.725309) (xy 36.431719 -315.808891) (xy 36.400327 -315.889923) (xy 36.361593 -315.967712)
			(xy 36.315846 -316.041596) (xy 36.263477 -316.110943) (xy 36.204933 -316.175163) (xy 36.140713 -316.233707)
			(xy 36.071366 -316.286076) (xy 35.997482 -316.331823) (xy 35.919693 -316.370557) (xy 35.838661 -316.401949)
			(xy 35.755079 -316.42573) (xy 35.669659 -316.441698) (xy 35.58313 -316.449716) (xy 35.49623 -316.449716)
			(xy 35.409701 -316.441698) (xy 35.324281 -316.42573) (xy 35.240699 -316.401949) (xy 35.159667 -316.370557)
			(xy 35.081878 -316.331823) (xy 35.007994 -316.286076) (xy 34.938647 -316.233707) (xy 34.874427 -316.175163)
			(xy 34.815883 -316.110943) (xy 34.763514 -316.041596) (xy 34.717767 -315.967712) (xy 34.679033 -315.889923)
			(xy 34.647641 -315.808891) (xy 34.62386 -315.725309) (xy 34.607892 -315.639889) (xy 34.599874 -315.55336)
			(xy 31.399486 -315.55336) (xy 31.391468 -315.639889) (xy 31.3755 -315.725309) (xy 31.351719 -315.808891)
			(xy 31.320327 -315.889923) (xy 31.281593 -315.967712) (xy 31.235846 -316.041596) (xy 31.183477 -316.110943)
			(xy 31.124933 -316.175163) (xy 31.060713 -316.233707) (xy 30.991366 -316.286076) (xy 30.917482 -316.331823)
			(xy 30.839693 -316.370557) (xy 30.758661 -316.401949) (xy 30.675079 -316.42573) (xy 30.589659 -316.441698)
			(xy 30.50313 -316.449716) (xy 30.41623 -316.449716) (xy 30.329701 -316.441698) (xy 30.244281 -316.42573)
			(xy 30.160699 -316.401949) (xy 30.079667 -316.370557) (xy 30.001878 -316.331823) (xy 29.927994 -316.286076)
			(xy 29.858647 -316.233707) (xy 29.794427 -316.175163) (xy 29.735883 -316.110943) (xy 29.683514 -316.041596)
			(xy 29.637767 -315.967712) (xy 29.599033 -315.889923) (xy 29.567641 -315.808891) (xy 29.54386 -315.725309)
			(xy 29.527892 -315.639889) (xy 29.519874 -315.55336) (xy 28.067 -315.55336) (xy 28.067 -318.09336)
			(xy 29.519874 -318.09336) (xy 29.519874 -318.00646) (xy 29.527892 -317.919931) (xy 29.54386 -317.834511)
			(xy 29.567641 -317.750929) (xy 29.599033 -317.669897) (xy 29.637767 -317.592108) (xy 29.683514 -317.518224)
			(xy 29.735883 -317.448877) (xy 29.794427 -317.384657) (xy 29.858647 -317.326113) (xy 29.927994 -317.273744)
			(xy 30.001878 -317.227997) (xy 30.079667 -317.189263) (xy 30.160699 -317.157871) (xy 30.244281 -317.13409)
			(xy 30.329701 -317.118122) (xy 30.41623 -317.110104) (xy 30.50313 -317.110104) (xy 30.589659 -317.118122)
			(xy 30.675079 -317.13409) (xy 30.758661 -317.157871) (xy 30.839693 -317.189263) (xy 30.917482 -317.227997)
			(xy 30.991366 -317.273744) (xy 31.060713 -317.326113) (xy 31.124933 -317.384657) (xy 31.183477 -317.448877)
			(xy 31.235846 -317.518224) (xy 31.281593 -317.592108) (xy 31.320327 -317.669897) (xy 31.351719 -317.750929)
			(xy 31.3755 -317.834511) (xy 31.391468 -317.919931) (xy 31.399486 -318.00646) (xy 31.399988 -318.04991)
			(xy 31.399486 -318.09336) (xy 34.599874 -318.09336) (xy 34.599874 -318.00646) (xy 34.607892 -317.919931)
			(xy 34.62386 -317.834511) (xy 34.647641 -317.750929) (xy 34.679033 -317.669897) (xy 34.717767 -317.592108)
			(xy 34.763514 -317.518224) (xy 34.815883 -317.448877) (xy 34.874427 -317.384657) (xy 34.938647 -317.326113)
			(xy 35.007994 -317.273744) (xy 35.081878 -317.227997) (xy 35.159667 -317.189263) (xy 35.240699 -317.157871)
			(xy 35.324281 -317.13409) (xy 35.409701 -317.118122) (xy 35.49623 -317.110104) (xy 35.58313 -317.110104)
			(xy 35.669659 -317.118122) (xy 35.755079 -317.13409) (xy 35.838661 -317.157871) (xy 35.919693 -317.189263)
			(xy 35.997482 -317.227997) (xy 36.071366 -317.273744) (xy 36.140713 -317.326113) (xy 36.204933 -317.384657)
			(xy 36.263477 -317.448877) (xy 36.315846 -317.518224) (xy 36.361593 -317.592108) (xy 36.400327 -317.669897)
			(xy 36.431719 -317.750929) (xy 36.4555 -317.834511) (xy 36.471468 -317.919931) (xy 36.479486 -318.00646)
			(xy 36.479988 -318.04991) (xy 36.479871 -318.06007) (xy 39.818063 -318.06007) (xy 39.82207 -317.944046)
			(xy 39.834072 -317.828574) (xy 39.854012 -317.714206) (xy 39.881795 -317.601486) (xy 39.917289 -317.490952)
			(xy 39.960324 -317.383129) (xy 40.010695 -317.278532) (xy 40.068162 -317.17766) (xy 40.132452 -317.080993)
			(xy 40.203257 -316.988992) (xy 40.280241 -316.902095) (xy 40.363037 -316.820716) (xy 40.45125 -316.745243)
			(xy 40.54446 -316.676036) (xy 40.642223 -316.613424) (xy 40.744072 -316.557707) (xy 40.849522 -316.509149)
			(xy 40.958071 -316.467981) (xy 41.069202 -316.434401) (xy 41.182385 -316.408568) (xy 41.29708 -316.390605)
			(xy 41.412742 -316.380597) (xy 41.528818 -316.378594) (xy 41.644756 -316.384603) (xy 41.760003 -316.398596)
			(xy 41.874009 -316.420507) (xy 41.986233 -316.450232) (xy 42.096139 -316.487628) (xy 42.203202 -316.532517)
			(xy 42.306914 -316.584686) (xy 42.406779 -316.643886) (xy 42.502322 -316.709835) (xy 42.502604 -316.71006)
			(xy 43.327577 -316.71006) (xy 43.331612 -316.634356) (xy 43.343671 -316.559511) (xy 43.363617 -316.48637)
			(xy 43.391224 -316.415765) (xy 43.42618 -316.348494) (xy 43.468088 -316.285319) (xy 43.516474 -316.226957)
			(xy 43.57079 -316.174069) (xy 43.630419 -316.127254) (xy 43.694687 -316.087042) (xy 43.762864 -316.05389)
			(xy 43.83418 -316.028172) (xy 43.907825 -316.01018) (xy 43.982965 -316.000118) (xy 44.058749 -315.998099)
			(xy 44.134319 -316.004148) (xy 44.208817 -316.018195) (xy 44.2814 -316.040081) (xy 44.351246 -316.069558)
			(xy 44.417563 -316.106293) (xy 44.479599 -316.149868) (xy 44.536652 -316.19979) (xy 44.588076 -316.255494)
			(xy 44.633287 -316.316349) (xy 44.671774 -316.381664) (xy 44.7031 -316.4507) (xy 44.72691 -316.522675)
			(xy 44.742935 -316.596773) (xy 44.750994 -316.672154) (xy 44.751498 -316.71006) (xy 45.867577 -316.71006)
			(xy 45.871612 -316.634356) (xy 45.883671 -316.559511) (xy 45.903617 -316.48637) (xy 45.931224 -316.415765)
			(xy 45.96618 -316.348494) (xy 46.008088 -316.285319) (xy 46.056474 -316.226957) (xy 46.11079 -316.174069)
			(xy 46.170419 -316.127254) (xy 46.234687 -316.087042) (xy 46.302864 -316.05389) (xy 46.37418 -316.028172)
			(xy 46.447825 -316.01018) (xy 46.522965 -316.000118) (xy 46.598749 -315.998099) (xy 46.674319 -316.004148)
			(xy 46.748817 -316.018195) (xy 46.8214 -316.040081) (xy 46.891246 -316.069558) (xy 46.957563 -316.106293)
			(xy 47.019599 -316.149868) (xy 47.076652 -316.19979) (xy 47.128076 -316.255494) (xy 47.173287 -316.316349)
			(xy 47.211774 -316.381664) (xy 47.2431 -316.4507) (xy 47.26691 -316.522675) (xy 47.282935 -316.596773)
			(xy 47.290994 -316.672154) (xy 47.291498 -316.71006) (xy 48.407577 -316.71006) (xy 48.411612 -316.634356)
			(xy 48.423671 -316.559511) (xy 48.443617 -316.48637) (xy 48.471224 -316.415765) (xy 48.50618 -316.348494)
			(xy 48.548088 -316.285319) (xy 48.596474 -316.226957) (xy 48.65079 -316.174069) (xy 48.710419 -316.127254)
			(xy 48.774687 -316.087042) (xy 48.842864 -316.05389) (xy 48.91418 -316.028172) (xy 48.987825 -316.01018)
			(xy 49.062965 -316.000118) (xy 49.138749 -315.998099) (xy 49.214319 -316.004148) (xy 49.288817 -316.018195)
			(xy 49.3614 -316.040081) (xy 49.431246 -316.069558) (xy 49.497563 -316.106293) (xy 49.559599 -316.149868)
			(xy 49.616652 -316.19979) (xy 49.668076 -316.255494) (xy 49.713287 -316.316349) (xy 49.751774 -316.381664)
			(xy 49.7831 -316.4507) (xy 49.80691 -316.522675) (xy 49.822935 -316.596773) (xy 49.830994 -316.672154)
			(xy 49.831498 -316.71006) (xy 50.947577 -316.71006) (xy 50.951612 -316.634356) (xy 50.963671 -316.559511)
			(xy 50.983617 -316.48637) (xy 51.011224 -316.415765) (xy 51.04618 -316.348494) (xy 51.088088 -316.285319)
			(xy 51.136474 -316.226957) (xy 51.19079 -316.174069) (xy 51.250419 -316.127254) (xy 51.314687 -316.087042)
			(xy 51.382864 -316.05389) (xy 51.45418 -316.028172) (xy 51.527825 -316.01018) (xy 51.602965 -316.000118)
			(xy 51.678749 -315.998099) (xy 51.754319 -316.004148) (xy 51.828817 -316.018195) (xy 51.9014 -316.040081)
			(xy 51.971246 -316.069558) (xy 52.037563 -316.106293) (xy 52.099599 -316.149868) (xy 52.156652 -316.19979)
			(xy 52.208076 -316.255494) (xy 52.253287 -316.316349) (xy 52.291774 -316.381664) (xy 52.3231 -316.4507)
			(xy 52.34691 -316.522675) (xy 52.362935 -316.596773) (xy 52.370994 -316.672154) (xy 52.371498 -316.71006)
			(xy 53.487577 -316.71006) (xy 53.491612 -316.634356) (xy 53.503671 -316.559511) (xy 53.523617 -316.48637)
			(xy 53.551224 -316.415765) (xy 53.58618 -316.348494) (xy 53.628088 -316.285319) (xy 53.676474 -316.226957)
			(xy 53.73079 -316.174069) (xy 53.790419 -316.127254) (xy 53.854687 -316.087042) (xy 53.922864 -316.05389)
			(xy 53.99418 -316.028172) (xy 54.067825 -316.01018) (xy 54.142965 -316.000118) (xy 54.218749 -315.998099)
			(xy 54.294319 -316.004148) (xy 54.368817 -316.018195) (xy 54.4414 -316.040081) (xy 54.511246 -316.069558)
			(xy 54.577563 -316.106293) (xy 54.639599 -316.149868) (xy 54.696652 -316.19979) (xy 54.748076 -316.255494)
			(xy 54.793287 -316.316349) (xy 54.831774 -316.381664) (xy 54.8631 -316.4507) (xy 54.88691 -316.522675)
			(xy 54.902935 -316.596773) (xy 54.910994 -316.672154) (xy 54.911498 -316.71006) (xy 56.027577 -316.71006)
			(xy 56.031612 -316.634356) (xy 56.043671 -316.559511) (xy 56.063617 -316.48637) (xy 56.091224 -316.415765)
			(xy 56.12618 -316.348494) (xy 56.168088 -316.285319) (xy 56.216474 -316.226957) (xy 56.27079 -316.174069)
			(xy 56.330419 -316.127254) (xy 56.394687 -316.087042) (xy 56.462864 -316.05389) (xy 56.53418 -316.028172)
			(xy 56.607825 -316.01018) (xy 56.682965 -316.000118) (xy 56.758749 -315.998099) (xy 56.834319 -316.004148)
			(xy 56.908817 -316.018195) (xy 56.9814 -316.040081) (xy 57.051246 -316.069558) (xy 57.117563 -316.106293)
			(xy 57.179599 -316.149868) (xy 57.236652 -316.19979) (xy 57.288076 -316.255494) (xy 57.333287 -316.316349)
			(xy 57.371774 -316.381664) (xy 57.4031 -316.4507) (xy 57.42691 -316.522675) (xy 57.442935 -316.596773)
			(xy 57.450994 -316.672154) (xy 57.451498 -316.71006) (xy 58.567577 -316.71006) (xy 58.571612 -316.634356)
			(xy 58.583671 -316.559511) (xy 58.603617 -316.48637) (xy 58.631224 -316.415765) (xy 58.66618 -316.348494)
			(xy 58.708088 -316.285319) (xy 58.756474 -316.226957) (xy 58.81079 -316.174069) (xy 58.870419 -316.127254)
			(xy 58.934687 -316.087042) (xy 59.002864 -316.05389) (xy 59.07418 -316.028172) (xy 59.147825 -316.01018)
			(xy 59.222965 -316.000118) (xy 59.298749 -315.998099) (xy 59.374319 -316.004148) (xy 59.448817 -316.018195)
			(xy 59.5214 -316.040081) (xy 59.591246 -316.069558) (xy 59.657563 -316.106293) (xy 59.719599 -316.149868)
			(xy 59.776652 -316.19979) (xy 59.828076 -316.255494) (xy 59.873287 -316.316349) (xy 59.911774 -316.381664)
			(xy 59.9431 -316.4507) (xy 59.96691 -316.522675) (xy 59.982935 -316.596773) (xy 59.990994 -316.672154)
			(xy 59.991498 -316.71006) (xy 61.107577 -316.71006) (xy 61.111612 -316.634356) (xy 61.123671 -316.559511)
			(xy 61.143617 -316.48637) (xy 61.171224 -316.415765) (xy 61.20618 -316.348494) (xy 61.248088 -316.285319)
			(xy 61.296474 -316.226957) (xy 61.35079 -316.174069) (xy 61.410419 -316.127254) (xy 61.474687 -316.087042)
			(xy 61.542864 -316.05389) (xy 61.61418 -316.028172) (xy 61.687825 -316.01018) (xy 61.762965 -316.000118)
			(xy 61.838749 -315.998099) (xy 61.914319 -316.004148) (xy 61.988817 -316.018195) (xy 62.0614 -316.040081)
			(xy 62.131246 -316.069558) (xy 62.197563 -316.106293) (xy 62.259599 -316.149868) (xy 62.265544 -316.15507)
			(xy 86.197697 -316.15507) (xy 86.201732 -316.079366) (xy 86.213791 -316.004521) (xy 86.233737 -315.93138)
			(xy 86.261344 -315.860775) (xy 86.2963 -315.793504) (xy 86.338208 -315.730329) (xy 86.386594 -315.671967)
			(xy 86.44091 -315.619079) (xy 86.500539 -315.572264) (xy 86.564807 -315.532052) (xy 86.632984 -315.4989)
			(xy 86.7043 -315.473182) (xy 86.777945 -315.45519) (xy 86.853085 -315.445128) (xy 86.928869 -315.443109)
			(xy 87.004439 -315.449158) (xy 87.078937 -315.463205) (xy 87.15152 -315.485091) (xy 87.221366 -315.514568)
			(xy 87.287683 -315.551303) (xy 87.349719 -315.594878) (xy 87.406772 -315.6448) (xy 87.458196 -315.700504)
			(xy 87.503407 -315.761359) (xy 87.541894 -315.826674) (xy 87.57322 -315.89571) (xy 87.59703 -315.967685)
			(xy 87.613055 -316.041783) (xy 87.621114 -316.117164) (xy 87.621618 -316.15507) (xy 88.737697 -316.15507)
			(xy 88.741732 -316.079366) (xy 88.753791 -316.004521) (xy 88.773737 -315.93138) (xy 88.801344 -315.860775)
			(xy 88.8363 -315.793504) (xy 88.878208 -315.730329) (xy 88.926594 -315.671967) (xy 88.98091 -315.619079)
			(xy 89.040539 -315.572264) (xy 89.104807 -315.532052) (xy 89.172984 -315.4989) (xy 89.2443 -315.473182)
			(xy 89.317945 -315.45519) (xy 89.393085 -315.445128) (xy 89.468869 -315.443109) (xy 89.544439 -315.449158)
			(xy 89.618937 -315.463205) (xy 89.69152 -315.485091) (xy 89.761366 -315.514568) (xy 89.827683 -315.551303)
			(xy 89.889719 -315.594878) (xy 89.946772 -315.6448) (xy 89.998196 -315.700504) (xy 90.043407 -315.761359)
			(xy 90.081894 -315.826674) (xy 90.11322 -315.89571) (xy 90.13703 -315.967685) (xy 90.153055 -316.041783)
			(xy 90.161114 -316.117164) (xy 90.161618 -316.15507) (xy 91.277697 -316.15507) (xy 91.281732 -316.079366)
			(xy 91.293791 -316.004521) (xy 91.313737 -315.93138) (xy 91.341344 -315.860775) (xy 91.3763 -315.793504)
			(xy 91.418208 -315.730329) (xy 91.466594 -315.671967) (xy 91.52091 -315.619079) (xy 91.580539 -315.572264)
			(xy 91.644807 -315.532052) (xy 91.712984 -315.4989) (xy 91.7843 -315.473182) (xy 91.857945 -315.45519)
			(xy 91.933085 -315.445128) (xy 92.008869 -315.443109) (xy 92.084439 -315.449158) (xy 92.158937 -315.463205)
			(xy 92.23152 -315.485091) (xy 92.301366 -315.514568) (xy 92.367683 -315.551303) (xy 92.429719 -315.594878)
			(xy 92.486772 -315.6448) (xy 92.538196 -315.700504) (xy 92.583407 -315.761359) (xy 92.621894 -315.826674)
			(xy 92.65322 -315.89571) (xy 92.67703 -315.967685) (xy 92.693055 -316.041783) (xy 92.701114 -316.117164)
			(xy 92.701618 -316.15507) (xy 92.701114 -316.192976) (xy 92.693055 -316.268357) (xy 92.67703 -316.342455)
			(xy 92.65322 -316.41443) (xy 92.621894 -316.483466) (xy 92.583407 -316.548781) (xy 92.538196 -316.609636)
			(xy 92.486772 -316.66534) (xy 92.429719 -316.715262) (xy 92.367683 -316.758837) (xy 92.301366 -316.795572)
			(xy 92.23152 -316.825049) (xy 92.158937 -316.846935) (xy 92.084439 -316.860982) (xy 92.008869 -316.867031)
			(xy 91.933085 -316.865012) (xy 91.857945 -316.85495) (xy 91.7843 -316.836958) (xy 91.712984 -316.81124)
			(xy 91.644807 -316.778088) (xy 91.580539 -316.737876) (xy 91.52091 -316.691061) (xy 91.466594 -316.638173)
			(xy 91.418208 -316.579811) (xy 91.3763 -316.516636) (xy 91.341344 -316.449365) (xy 91.313737 -316.37876)
			(xy 91.293791 -316.305619) (xy 91.281732 -316.230774) (xy 91.277697 -316.15507) (xy 90.161618 -316.15507)
			(xy 90.161114 -316.192976) (xy 90.153055 -316.268357) (xy 90.13703 -316.342455) (xy 90.11322 -316.41443)
			(xy 90.081894 -316.483466) (xy 90.043407 -316.548781) (xy 89.998196 -316.609636) (xy 89.946772 -316.66534)
			(xy 89.889719 -316.715262) (xy 89.827683 -316.758837) (xy 89.761366 -316.795572) (xy 89.69152 -316.825049)
			(xy 89.618937 -316.846935) (xy 89.544439 -316.860982) (xy 89.468869 -316.867031) (xy 89.393085 -316.865012)
			(xy 89.317945 -316.85495) (xy 89.2443 -316.836958) (xy 89.172984 -316.81124) (xy 89.104807 -316.778088)
			(xy 89.040539 -316.737876) (xy 88.98091 -316.691061) (xy 88.926594 -316.638173) (xy 88.878208 -316.579811)
			(xy 88.8363 -316.516636) (xy 88.801344 -316.449365) (xy 88.773737 -316.37876) (xy 88.753791 -316.305619)
			(xy 88.741732 -316.230774) (xy 88.737697 -316.15507) (xy 87.621618 -316.15507) (xy 87.621114 -316.192976)
			(xy 87.613055 -316.268357) (xy 87.59703 -316.342455) (xy 87.57322 -316.41443) (xy 87.541894 -316.483466)
			(xy 87.503407 -316.548781) (xy 87.458196 -316.609636) (xy 87.406772 -316.66534) (xy 87.349719 -316.715262)
			(xy 87.287683 -316.758837) (xy 87.221366 -316.795572) (xy 87.15152 -316.825049) (xy 87.078937 -316.846935)
			(xy 87.004439 -316.860982) (xy 86.928869 -316.867031) (xy 86.853085 -316.865012) (xy 86.777945 -316.85495)
			(xy 86.7043 -316.836958) (xy 86.632984 -316.81124) (xy 86.564807 -316.778088) (xy 86.500539 -316.737876)
			(xy 86.44091 -316.691061) (xy 86.386594 -316.638173) (xy 86.338208 -316.579811) (xy 86.2963 -316.516636)
			(xy 86.261344 -316.449365) (xy 86.233737 -316.37876) (xy 86.213791 -316.305619) (xy 86.201732 -316.230774)
			(xy 86.197697 -316.15507) (xy 62.265544 -316.15507) (xy 62.316652 -316.19979) (xy 62.368076 -316.255494)
			(xy 62.413287 -316.316349) (xy 62.451774 -316.381664) (xy 62.4831 -316.4507) (xy 62.50691 -316.522675)
			(xy 62.522935 -316.596773) (xy 62.530994 -316.672154) (xy 62.531498 -316.71006) (xy 62.530994 -316.747966)
			(xy 62.522935 -316.823347) (xy 62.50691 -316.897445) (xy 62.4831 -316.96942) (xy 62.451774 -317.038456)
			(xy 62.413287 -317.103771) (xy 62.368076 -317.164626) (xy 62.316652 -317.22033) (xy 62.259599 -317.270252)
			(xy 62.197563 -317.313827) (xy 62.131246 -317.350562) (xy 62.0614 -317.380039) (xy 61.988817 -317.401925)
			(xy 61.914319 -317.415972) (xy 61.838749 -317.422021) (xy 61.762965 -317.420002) (xy 61.687825 -317.40994)
			(xy 61.61418 -317.391948) (xy 61.542864 -317.36623) (xy 61.474687 -317.333078) (xy 61.410419 -317.292866)
			(xy 61.35079 -317.246051) (xy 61.296474 -317.193163) (xy 61.248088 -317.134801) (xy 61.20618 -317.071626)
			(xy 61.171224 -317.004355) (xy 61.143617 -316.93375) (xy 61.123671 -316.860609) (xy 61.111612 -316.785764)
			(xy 61.107577 -316.71006) (xy 59.991498 -316.71006) (xy 59.990994 -316.747966) (xy 59.982935 -316.823347)
			(xy 59.96691 -316.897445) (xy 59.9431 -316.96942) (xy 59.911774 -317.038456) (xy 59.873287 -317.103771)
			(xy 59.828076 -317.164626) (xy 59.776652 -317.22033) (xy 59.719599 -317.270252) (xy 59.657563 -317.313827)
			(xy 59.591246 -317.350562) (xy 59.5214 -317.380039) (xy 59.448817 -317.401925) (xy 59.374319 -317.415972)
			(xy 59.298749 -317.422021) (xy 59.222965 -317.420002) (xy 59.147825 -317.40994) (xy 59.07418 -317.391948)
			(xy 59.002864 -317.36623) (xy 58.934687 -317.333078) (xy 58.870419 -317.292866) (xy 58.81079 -317.246051)
			(xy 58.756474 -317.193163) (xy 58.708088 -317.134801) (xy 58.66618 -317.071626) (xy 58.631224 -317.004355)
			(xy 58.603617 -316.93375) (xy 58.583671 -316.860609) (xy 58.571612 -316.785764) (xy 58.567577 -316.71006)
			(xy 57.451498 -316.71006) (xy 57.450994 -316.747966) (xy 57.442935 -316.823347) (xy 57.42691 -316.897445)
			(xy 57.4031 -316.96942) (xy 57.371774 -317.038456) (xy 57.333287 -317.103771) (xy 57.288076 -317.164626)
			(xy 57.236652 -317.22033) (xy 57.179599 -317.270252) (xy 57.117563 -317.313827) (xy 57.051246 -317.350562)
			(xy 56.9814 -317.380039) (xy 56.908817 -317.401925) (xy 56.834319 -317.415972) (xy 56.758749 -317.422021)
			(xy 56.682965 -317.420002) (xy 56.607825 -317.40994) (xy 56.53418 -317.391948) (xy 56.462864 -317.36623)
			(xy 56.394687 -317.333078) (xy 56.330419 -317.292866) (xy 56.27079 -317.246051) (xy 56.216474 -317.193163)
			(xy 56.168088 -317.134801) (xy 56.12618 -317.071626) (xy 56.091224 -317.004355) (xy 56.063617 -316.93375)
			(xy 56.043671 -316.860609) (xy 56.031612 -316.785764) (xy 56.027577 -316.71006) (xy 54.911498 -316.71006)
			(xy 54.910994 -316.747966) (xy 54.902935 -316.823347) (xy 54.88691 -316.897445) (xy 54.8631 -316.96942)
			(xy 54.831774 -317.038456) (xy 54.793287 -317.103771) (xy 54.748076 -317.164626) (xy 54.696652 -317.22033)
			(xy 54.639599 -317.270252) (xy 54.577563 -317.313827) (xy 54.511246 -317.350562) (xy 54.4414 -317.380039)
			(xy 54.368817 -317.401925) (xy 54.294319 -317.415972) (xy 54.218749 -317.422021) (xy 54.142965 -317.420002)
			(xy 54.067825 -317.40994) (xy 53.99418 -317.391948) (xy 53.922864 -317.36623) (xy 53.854687 -317.333078)
			(xy 53.790419 -317.292866) (xy 53.73079 -317.246051) (xy 53.676474 -317.193163) (xy 53.628088 -317.134801)
			(xy 53.58618 -317.071626) (xy 53.551224 -317.004355) (xy 53.523617 -316.93375) (xy 53.503671 -316.860609)
			(xy 53.491612 -316.785764) (xy 53.487577 -316.71006) (xy 52.371498 -316.71006) (xy 52.370994 -316.747966)
			(xy 52.362935 -316.823347) (xy 52.34691 -316.897445) (xy 52.3231 -316.96942) (xy 52.291774 -317.038456)
			(xy 52.253287 -317.103771) (xy 52.208076 -317.164626) (xy 52.156652 -317.22033) (xy 52.099599 -317.270252)
			(xy 52.037563 -317.313827) (xy 51.971246 -317.350562) (xy 51.9014 -317.380039) (xy 51.828817 -317.401925)
			(xy 51.754319 -317.415972) (xy 51.678749 -317.422021) (xy 51.602965 -317.420002) (xy 51.527825 -317.40994)
			(xy 51.45418 -317.391948) (xy 51.382864 -317.36623) (xy 51.314687 -317.333078) (xy 51.250419 -317.292866)
			(xy 51.19079 -317.246051) (xy 51.136474 -317.193163) (xy 51.088088 -317.134801) (xy 51.04618 -317.071626)
			(xy 51.011224 -317.004355) (xy 50.983617 -316.93375) (xy 50.963671 -316.860609) (xy 50.951612 -316.785764)
			(xy 50.947577 -316.71006) (xy 49.831498 -316.71006) (xy 49.830994 -316.747966) (xy 49.822935 -316.823347)
			(xy 49.80691 -316.897445) (xy 49.7831 -316.96942) (xy 49.751774 -317.038456) (xy 49.713287 -317.103771)
			(xy 49.668076 -317.164626) (xy 49.616652 -317.22033) (xy 49.559599 -317.270252) (xy 49.497563 -317.313827)
			(xy 49.431246 -317.350562) (xy 49.3614 -317.380039) (xy 49.288817 -317.401925) (xy 49.214319 -317.415972)
			(xy 49.138749 -317.422021) (xy 49.062965 -317.420002) (xy 48.987825 -317.40994) (xy 48.91418 -317.391948)
			(xy 48.842864 -317.36623) (xy 48.774687 -317.333078) (xy 48.710419 -317.292866) (xy 48.65079 -317.246051)
			(xy 48.596474 -317.193163) (xy 48.548088 -317.134801) (xy 48.50618 -317.071626) (xy 48.471224 -317.004355)
			(xy 48.443617 -316.93375) (xy 48.423671 -316.860609) (xy 48.411612 -316.785764) (xy 48.407577 -316.71006)
			(xy 47.291498 -316.71006) (xy 47.290994 -316.747966) (xy 47.282935 -316.823347) (xy 47.26691 -316.897445)
			(xy 47.2431 -316.96942) (xy 47.211774 -317.038456) (xy 47.173287 -317.103771) (xy 47.128076 -317.164626)
			(xy 47.076652 -317.22033) (xy 47.019599 -317.270252) (xy 46.957563 -317.313827) (xy 46.891246 -317.350562)
			(xy 46.8214 -317.380039) (xy 46.748817 -317.401925) (xy 46.674319 -317.415972) (xy 46.598749 -317.422021)
			(xy 46.522965 -317.420002) (xy 46.447825 -317.40994) (xy 46.37418 -317.391948) (xy 46.302864 -317.36623)
			(xy 46.234687 -317.333078) (xy 46.170419 -317.292866) (xy 46.11079 -317.246051) (xy 46.056474 -317.193163)
			(xy 46.008088 -317.134801) (xy 45.96618 -317.071626) (xy 45.931224 -317.004355) (xy 45.903617 -316.93375)
			(xy 45.883671 -316.860609) (xy 45.871612 -316.785764) (xy 45.867577 -316.71006) (xy 44.751498 -316.71006)
			(xy 44.750994 -316.747966) (xy 44.742935 -316.823347) (xy 44.72691 -316.897445) (xy 44.7031 -316.96942)
			(xy 44.671774 -317.038456) (xy 44.633287 -317.103771) (xy 44.588076 -317.164626) (xy 44.536652 -317.22033)
			(xy 44.479599 -317.270252) (xy 44.417563 -317.313827) (xy 44.351246 -317.350562) (xy 44.2814 -317.380039)
			(xy 44.208817 -317.401925) (xy 44.134319 -317.415972) (xy 44.058749 -317.422021) (xy 43.982965 -317.420002)
			(xy 43.907825 -317.40994) (xy 43.83418 -317.391948) (xy 43.762864 -317.36623) (xy 43.694687 -317.333078)
			(xy 43.630419 -317.292866) (xy 43.57079 -317.246051) (xy 43.516474 -317.193163) (xy 43.468088 -317.134801)
			(xy 43.42618 -317.071626) (xy 43.391224 -317.004355) (xy 43.363617 -316.93375) (xy 43.343671 -316.860609)
			(xy 43.331612 -316.785764) (xy 43.327577 -316.71006) (xy 42.502604 -316.71006) (xy 42.593088 -316.782218)
			(xy 42.678643 -316.860691) (xy 42.758581 -316.944879) (xy 42.83252 -317.034381) (xy 42.900108 -317.128772)
			(xy 42.961022 -317.2276) (xy 43.014974 -317.330396) (xy 43.056604 -317.42507) (xy 84.927697 -317.42507)
			(xy 84.931732 -317.349366) (xy 84.943791 -317.274521) (xy 84.963737 -317.20138) (xy 84.991344 -317.130775)
			(xy 85.0263 -317.063504) (xy 85.068208 -317.000329) (xy 85.116594 -316.941967) (xy 85.17091 -316.889079)
			(xy 85.230539 -316.842264) (xy 85.294807 -316.802052) (xy 85.362984 -316.7689) (xy 85.4343 -316.743182)
			(xy 85.507945 -316.72519) (xy 85.583085 -316.715128) (xy 85.658869 -316.713109) (xy 85.734439 -316.719158)
			(xy 85.808937 -316.733205) (xy 85.88152 -316.755091) (xy 85.951366 -316.784568) (xy 86.017683 -316.821303)
			(xy 86.079719 -316.864878) (xy 86.136772 -316.9148) (xy 86.188196 -316.970504) (xy 86.233407 -317.031359)
			(xy 86.271894 -317.096674) (xy 86.30322 -317.16571) (xy 86.32703 -317.237685) (xy 86.343055 -317.311783)
			(xy 86.351114 -317.387164) (xy 86.351618 -317.42507) (xy 87.467697 -317.42507) (xy 87.471732 -317.349366)
			(xy 87.483791 -317.274521) (xy 87.503737 -317.20138) (xy 87.531344 -317.130775) (xy 87.5663 -317.063504)
			(xy 87.608208 -317.000329) (xy 87.656594 -316.941967) (xy 87.71091 -316.889079) (xy 87.770539 -316.842264)
			(xy 87.834807 -316.802052) (xy 87.902984 -316.7689) (xy 87.9743 -316.743182) (xy 88.047945 -316.72519)
			(xy 88.123085 -316.715128) (xy 88.198869 -316.713109) (xy 88.274439 -316.719158) (xy 88.348937 -316.733205)
			(xy 88.42152 -316.755091) (xy 88.491366 -316.784568) (xy 88.557683 -316.821303) (xy 88.619719 -316.864878)
			(xy 88.676772 -316.9148) (xy 88.728196 -316.970504) (xy 88.773407 -317.031359) (xy 88.811894 -317.096674)
			(xy 88.84322 -317.16571) (xy 88.86703 -317.237685) (xy 88.883055 -317.311783) (xy 88.891114 -317.387164)
			(xy 88.891618 -317.42507) (xy 90.007697 -317.42507) (xy 90.011732 -317.349366) (xy 90.023791 -317.274521)
			(xy 90.043737 -317.20138) (xy 90.071344 -317.130775) (xy 90.1063 -317.063504) (xy 90.148208 -317.000329)
			(xy 90.196594 -316.941967) (xy 90.25091 -316.889079) (xy 90.310539 -316.842264) (xy 90.374807 -316.802052)
			(xy 90.442984 -316.7689) (xy 90.5143 -316.743182) (xy 90.587945 -316.72519) (xy 90.663085 -316.715128)
			(xy 90.738869 -316.713109) (xy 90.814439 -316.719158) (xy 90.888937 -316.733205) (xy 90.96152 -316.755091)
			(xy 91.031366 -316.784568) (xy 91.097683 -316.821303) (xy 91.159719 -316.864878) (xy 91.216772 -316.9148)
			(xy 91.268196 -316.970504) (xy 91.313407 -317.031359) (xy 91.351894 -317.096674) (xy 91.38322 -317.16571)
			(xy 91.40703 -317.237685) (xy 91.423055 -317.311783) (xy 91.431114 -317.387164) (xy 91.431618 -317.42507)
			(xy 91.431114 -317.462976) (xy 91.423055 -317.538357) (xy 91.40703 -317.612455) (xy 91.38322 -317.68443)
			(xy 91.351894 -317.753466) (xy 91.313407 -317.818781) (xy 91.268196 -317.879636) (xy 91.216772 -317.93534)
			(xy 91.159719 -317.985262) (xy 91.097683 -318.028837) (xy 91.031366 -318.065572) (xy 90.96152 -318.095049)
			(xy 90.888937 -318.116935) (xy 90.814439 -318.130982) (xy 90.738869 -318.137031) (xy 90.663085 -318.135012)
			(xy 90.587945 -318.12495) (xy 90.5143 -318.106958) (xy 90.442984 -318.08124) (xy 90.374807 -318.048088)
			(xy 90.310539 -318.007876) (xy 90.25091 -317.961061) (xy 90.196594 -317.908173) (xy 90.148208 -317.849811)
			(xy 90.1063 -317.786636) (xy 90.071344 -317.719365) (xy 90.043737 -317.64876) (xy 90.023791 -317.575619)
			(xy 90.011732 -317.500774) (xy 90.007697 -317.42507) (xy 88.891618 -317.42507) (xy 88.891114 -317.462976)
			(xy 88.883055 -317.538357) (xy 88.86703 -317.612455) (xy 88.84322 -317.68443) (xy 88.811894 -317.753466)
			(xy 88.773407 -317.818781) (xy 88.728196 -317.879636) (xy 88.676772 -317.93534) (xy 88.619719 -317.985262)
			(xy 88.557683 -318.028837) (xy 88.491366 -318.065572) (xy 88.42152 -318.095049) (xy 88.348937 -318.116935)
			(xy 88.274439 -318.130982) (xy 88.198869 -318.137031) (xy 88.123085 -318.135012) (xy 88.047945 -318.12495)
			(xy 87.9743 -318.106958) (xy 87.902984 -318.08124) (xy 87.834807 -318.048088) (xy 87.770539 -318.007876)
			(xy 87.71091 -317.961061) (xy 87.656594 -317.908173) (xy 87.608208 -317.849811) (xy 87.5663 -317.786636)
			(xy 87.531344 -317.719365) (xy 87.503737 -317.64876) (xy 87.483791 -317.575619) (xy 87.471732 -317.500774)
			(xy 87.467697 -317.42507) (xy 86.351618 -317.42507) (xy 86.351114 -317.462976) (xy 86.343055 -317.538357)
			(xy 86.32703 -317.612455) (xy 86.30322 -317.68443) (xy 86.271894 -317.753466) (xy 86.233407 -317.818781)
			(xy 86.188196 -317.879636) (xy 86.136772 -317.93534) (xy 86.079719 -317.985262) (xy 86.017683 -318.028837)
			(xy 85.951366 -318.065572) (xy 85.88152 -318.095049) (xy 85.808937 -318.116935) (xy 85.734439 -318.130982)
			(xy 85.658869 -318.137031) (xy 85.583085 -318.135012) (xy 85.507945 -318.12495) (xy 85.4343 -318.106958)
			(xy 85.362984 -318.08124) (xy 85.294807 -318.048088) (xy 85.230539 -318.007876) (xy 85.17091 -317.961061)
			(xy 85.116594 -317.908173) (xy 85.068208 -317.849811) (xy 85.0263 -317.786636) (xy 84.991344 -317.719365)
			(xy 84.963737 -317.64876) (xy 84.943791 -317.575619) (xy 84.931732 -317.500774) (xy 84.927697 -317.42507)
			(xy 43.056604 -317.42507) (xy 43.061704 -317.436669) (xy 43.100992 -317.545913) (xy 43.132649 -317.657606)
			(xy 43.156525 -317.771218) (xy 43.172506 -317.886206) (xy 43.180515 -318.002023) (xy 43.181016 -318.06007)
			(xy 43.180515 -318.118117) (xy 43.172506 -318.233934) (xy 43.156525 -318.348922) (xy 43.132649 -318.462534)
			(xy 43.100992 -318.574227) (xy 43.061704 -318.683471) (xy 43.056604 -318.69507) (xy 86.197697 -318.69507)
			(xy 86.201732 -318.619366) (xy 86.213791 -318.544521) (xy 86.233737 -318.47138) (xy 86.261344 -318.400775)
			(xy 86.2963 -318.333504) (xy 86.338208 -318.270329) (xy 86.386594 -318.211967) (xy 86.44091 -318.159079)
			(xy 86.500539 -318.112264) (xy 86.564807 -318.072052) (xy 86.632984 -318.0389) (xy 86.7043 -318.013182)
			(xy 86.777945 -317.99519) (xy 86.853085 -317.985128) (xy 86.928869 -317.983109) (xy 87.004439 -317.989158)
			(xy 87.078937 -318.003205) (xy 87.15152 -318.025091) (xy 87.221366 -318.054568) (xy 87.287683 -318.091303)
			(xy 87.349719 -318.134878) (xy 87.406772 -318.1848) (xy 87.458196 -318.240504) (xy 87.503407 -318.301359)
			(xy 87.541894 -318.366674) (xy 87.57322 -318.43571) (xy 87.59703 -318.507685) (xy 87.613055 -318.581783)
			(xy 87.621114 -318.657164) (xy 87.621618 -318.69507) (xy 88.737697 -318.69507) (xy 88.741732 -318.619366)
			(xy 88.753791 -318.544521) (xy 88.773737 -318.47138) (xy 88.801344 -318.400775) (xy 88.8363 -318.333504)
			(xy 88.878208 -318.270329) (xy 88.926594 -318.211967) (xy 88.98091 -318.159079) (xy 89.040539 -318.112264)
			(xy 89.104807 -318.072052) (xy 89.172984 -318.0389) (xy 89.2443 -318.013182) (xy 89.317945 -317.99519)
			(xy 89.393085 -317.985128) (xy 89.468869 -317.983109) (xy 89.544439 -317.989158) (xy 89.618937 -318.003205)
			(xy 89.69152 -318.025091) (xy 89.761366 -318.054568) (xy 89.827683 -318.091303) (xy 89.889719 -318.134878)
			(xy 89.946772 -318.1848) (xy 89.998196 -318.240504) (xy 90.043407 -318.301359) (xy 90.081894 -318.366674)
			(xy 90.11322 -318.43571) (xy 90.13703 -318.507685) (xy 90.153055 -318.581783) (xy 90.161114 -318.657164)
			(xy 90.161618 -318.69507) (xy 91.277697 -318.69507) (xy 91.281732 -318.619366) (xy 91.293791 -318.544521)
			(xy 91.313737 -318.47138) (xy 91.341344 -318.400775) (xy 91.3763 -318.333504) (xy 91.418208 -318.270329)
			(xy 91.466594 -318.211967) (xy 91.52091 -318.159079) (xy 91.580539 -318.112264) (xy 91.644807 -318.072052)
			(xy 91.712984 -318.0389) (xy 91.7843 -318.013182) (xy 91.857945 -317.99519) (xy 91.933085 -317.985128)
			(xy 92.008869 -317.983109) (xy 92.084439 -317.989158) (xy 92.158937 -318.003205) (xy 92.23152 -318.025091)
			(xy 92.301366 -318.054568) (xy 92.367683 -318.091303) (xy 92.429719 -318.134878) (xy 92.486772 -318.1848)
			(xy 92.538196 -318.240504) (xy 92.583407 -318.301359) (xy 92.621894 -318.366674) (xy 92.65322 -318.43571)
			(xy 92.67703 -318.507685) (xy 92.693055 -318.581783) (xy 92.701114 -318.657164) (xy 92.701618 -318.69507)
			(xy 92.701114 -318.732976) (xy 92.693055 -318.808357) (xy 92.67703 -318.882455) (xy 92.65322 -318.95443)
			(xy 92.621894 -319.023466) (xy 92.583407 -319.088781) (xy 92.538196 -319.149636) (xy 92.486772 -319.20534)
			(xy 92.429719 -319.255262) (xy 92.367683 -319.298837) (xy 92.301366 -319.335572) (xy 92.23152 -319.365049)
			(xy 92.158937 -319.386935) (xy 92.084439 -319.400982) (xy 92.008869 -319.407031) (xy 91.933085 -319.405012)
			(xy 91.857945 -319.39495) (xy 91.7843 -319.376958) (xy 91.712984 -319.35124) (xy 91.644807 -319.318088)
			(xy 91.580539 -319.277876) (xy 91.52091 -319.231061) (xy 91.466594 -319.178173) (xy 91.418208 -319.119811)
			(xy 91.3763 -319.056636) (xy 91.341344 -318.989365) (xy 91.313737 -318.91876) (xy 91.293791 -318.845619)
			(xy 91.281732 -318.770774) (xy 91.277697 -318.69507) (xy 90.161618 -318.69507) (xy 90.161114 -318.732976)
			(xy 90.153055 -318.808357) (xy 90.13703 -318.882455) (xy 90.11322 -318.95443) (xy 90.081894 -319.023466)
			(xy 90.043407 -319.088781) (xy 89.998196 -319.149636) (xy 89.946772 -319.20534) (xy 89.889719 -319.255262)
			(xy 89.827683 -319.298837) (xy 89.761366 -319.335572) (xy 89.69152 -319.365049) (xy 89.618937 -319.386935)
			(xy 89.544439 -319.400982) (xy 89.468869 -319.407031) (xy 89.393085 -319.405012) (xy 89.317945 -319.39495)
			(xy 89.2443 -319.376958) (xy 89.172984 -319.35124) (xy 89.104807 -319.318088) (xy 89.040539 -319.277876)
			(xy 88.98091 -319.231061) (xy 88.926594 -319.178173) (xy 88.878208 -319.119811) (xy 88.8363 -319.056636)
			(xy 88.801344 -318.989365) (xy 88.773737 -318.91876) (xy 88.753791 -318.845619) (xy 88.741732 -318.770774)
			(xy 88.737697 -318.69507) (xy 87.621618 -318.69507) (xy 87.621114 -318.732976) (xy 87.613055 -318.808357)
			(xy 87.59703 -318.882455) (xy 87.57322 -318.95443) (xy 87.541894 -319.023466) (xy 87.503407 -319.088781)
			(xy 87.458196 -319.149636) (xy 87.406772 -319.20534) (xy 87.349719 -319.255262) (xy 87.287683 -319.298837)
			(xy 87.221366 -319.335572) (xy 87.15152 -319.365049) (xy 87.078937 -319.386935) (xy 87.004439 -319.400982)
			(xy 86.928869 -319.407031) (xy 86.853085 -319.405012) (xy 86.777945 -319.39495) (xy 86.7043 -319.376958)
			(xy 86.632984 -319.35124) (xy 86.564807 -319.318088) (xy 86.500539 -319.277876) (xy 86.44091 -319.231061)
			(xy 86.386594 -319.178173) (xy 86.338208 -319.119811) (xy 86.2963 -319.056636) (xy 86.261344 -318.989365)
			(xy 86.233737 -318.91876) (xy 86.213791 -318.845619) (xy 86.201732 -318.770774) (xy 86.197697 -318.69507)
			(xy 43.056604 -318.69507) (xy 43.055152 -318.698372) (xy 43.328336 -318.698372) (xy 44.751244 -318.698372)
			(xy 44.751244 -319.41008) (xy 45.867577 -319.41008) (xy 45.871612 -319.334376) (xy 45.883671 -319.259531)
			(xy 45.903617 -319.18639) (xy 45.931224 -319.115785) (xy 45.96618 -319.048514) (xy 46.008088 -318.985339)
			(xy 46.056474 -318.926977) (xy 46.11079 -318.874089) (xy 46.170419 -318.827274) (xy 46.234687 -318.787062)
			(xy 46.302864 -318.75391) (xy 46.37418 -318.728192) (xy 46.447825 -318.7102) (xy 46.522965 -318.700138)
			(xy 46.598749 -318.698119) (xy 46.674319 -318.704168) (xy 46.748817 -318.718215) (xy 46.8214 -318.740101)
			(xy 46.891246 -318.769578) (xy 46.957563 -318.806313) (xy 47.019599 -318.849888) (xy 47.076652 -318.89981)
			(xy 47.128076 -318.955514) (xy 47.173287 -319.016369) (xy 47.211774 -319.081684) (xy 47.2431 -319.15072)
			(xy 47.26691 -319.222695) (xy 47.282935 -319.296793) (xy 47.290994 -319.372174) (xy 47.291498 -319.41008)
			(xy 48.407577 -319.41008) (xy 48.411612 -319.334376) (xy 48.423671 -319.259531) (xy 48.443617 -319.18639)
			(xy 48.471224 -319.115785) (xy 48.50618 -319.048514) (xy 48.548088 -318.985339) (xy 48.596474 -318.926977)
			(xy 48.65079 -318.874089) (xy 48.710419 -318.827274) (xy 48.774687 -318.787062) (xy 48.842864 -318.75391)
			(xy 48.91418 -318.728192) (xy 48.987825 -318.7102) (xy 49.062965 -318.700138) (xy 49.138749 -318.698119)
			(xy 49.214319 -318.704168) (xy 49.288817 -318.718215) (xy 49.3614 -318.740101) (xy 49.431246 -318.769578)
			(xy 49.497563 -318.806313) (xy 49.559599 -318.849888) (xy 49.616652 -318.89981) (xy 49.668076 -318.955514)
			(xy 49.713287 -319.016369) (xy 49.751774 -319.081684) (xy 49.7831 -319.15072) (xy 49.80691 -319.222695)
			(xy 49.822935 -319.296793) (xy 49.830994 -319.372174) (xy 49.831498 -319.41008) (xy 50.947577 -319.41008)
			(xy 50.951612 -319.334376) (xy 50.963671 -319.259531) (xy 50.983617 -319.18639) (xy 51.011224 -319.115785)
			(xy 51.04618 -319.048514) (xy 51.088088 -318.985339) (xy 51.136474 -318.926977) (xy 51.19079 -318.874089)
			(xy 51.250419 -318.827274) (xy 51.314687 -318.787062) (xy 51.382864 -318.75391) (xy 51.45418 -318.728192)
			(xy 51.527825 -318.7102) (xy 51.602965 -318.700138) (xy 51.678749 -318.698119) (xy 51.754319 -318.704168)
			(xy 51.828817 -318.718215) (xy 51.9014 -318.740101) (xy 51.971246 -318.769578) (xy 52.037563 -318.806313)
			(xy 52.099599 -318.849888) (xy 52.156652 -318.89981) (xy 52.208076 -318.955514) (xy 52.253287 -319.016369)
			(xy 52.291774 -319.081684) (xy 52.3231 -319.15072) (xy 52.34691 -319.222695) (xy 52.362935 -319.296793)
			(xy 52.370994 -319.372174) (xy 52.371498 -319.41008) (xy 53.487577 -319.41008) (xy 53.491612 -319.334376)
			(xy 53.503671 -319.259531) (xy 53.523617 -319.18639) (xy 53.551224 -319.115785) (xy 53.58618 -319.048514)
			(xy 53.628088 -318.985339) (xy 53.676474 -318.926977) (xy 53.73079 -318.874089) (xy 53.790419 -318.827274)
			(xy 53.854687 -318.787062) (xy 53.922864 -318.75391) (xy 53.99418 -318.728192) (xy 54.067825 -318.7102)
			(xy 54.142965 -318.700138) (xy 54.218749 -318.698119) (xy 54.294319 -318.704168) (xy 54.368817 -318.718215)
			(xy 54.4414 -318.740101) (xy 54.511246 -318.769578) (xy 54.577563 -318.806313) (xy 54.639599 -318.849888)
			(xy 54.696652 -318.89981) (xy 54.748076 -318.955514) (xy 54.793287 -319.016369) (xy 54.831774 -319.081684)
			(xy 54.8631 -319.15072) (xy 54.88691 -319.222695) (xy 54.902935 -319.296793) (xy 54.910994 -319.372174)
			(xy 54.911498 -319.41008) (xy 56.027577 -319.41008) (xy 56.031612 -319.334376) (xy 56.043671 -319.259531)
			(xy 56.063617 -319.18639) (xy 56.091224 -319.115785) (xy 56.12618 -319.048514) (xy 56.168088 -318.985339)
			(xy 56.216474 -318.926977) (xy 56.27079 -318.874089) (xy 56.330419 -318.827274) (xy 56.394687 -318.787062)
			(xy 56.462864 -318.75391) (xy 56.53418 -318.728192) (xy 56.607825 -318.7102) (xy 56.682965 -318.700138)
			(xy 56.758749 -318.698119) (xy 56.834319 -318.704168) (xy 56.908817 -318.718215) (xy 56.9814 -318.740101)
			(xy 57.051246 -318.769578) (xy 57.117563 -318.806313) (xy 57.179599 -318.849888) (xy 57.236652 -318.89981)
			(xy 57.288076 -318.955514) (xy 57.333287 -319.016369) (xy 57.371774 -319.081684) (xy 57.4031 -319.15072)
			(xy 57.42691 -319.222695) (xy 57.442935 -319.296793) (xy 57.450994 -319.372174) (xy 57.451498 -319.41008)
			(xy 58.567577 -319.41008) (xy 58.571612 -319.334376) (xy 58.583671 -319.259531) (xy 58.603617 -319.18639)
			(xy 58.631224 -319.115785) (xy 58.66618 -319.048514) (xy 58.708088 -318.985339) (xy 58.756474 -318.926977)
			(xy 58.81079 -318.874089) (xy 58.870419 -318.827274) (xy 58.934687 -318.787062) (xy 59.002864 -318.75391)
			(xy 59.07418 -318.728192) (xy 59.147825 -318.7102) (xy 59.222965 -318.700138) (xy 59.298749 -318.698119)
			(xy 59.374319 -318.704168) (xy 59.448817 -318.718215) (xy 59.5214 -318.740101) (xy 59.591246 -318.769578)
			(xy 59.657563 -318.806313) (xy 59.719599 -318.849888) (xy 59.776652 -318.89981) (xy 59.828076 -318.955514)
			(xy 59.873287 -319.016369) (xy 59.911774 -319.081684) (xy 59.9431 -319.15072) (xy 59.96691 -319.222695)
			(xy 59.982935 -319.296793) (xy 59.990994 -319.372174) (xy 59.991498 -319.41008) (xy 61.107577 -319.41008)
			(xy 61.111612 -319.334376) (xy 61.123671 -319.259531) (xy 61.143617 -319.18639) (xy 61.171224 -319.115785)
			(xy 61.20618 -319.048514) (xy 61.248088 -318.985339) (xy 61.296474 -318.926977) (xy 61.35079 -318.874089)
			(xy 61.410419 -318.827274) (xy 61.474687 -318.787062) (xy 61.542864 -318.75391) (xy 61.61418 -318.728192)
			(xy 61.687825 -318.7102) (xy 61.762965 -318.700138) (xy 61.838749 -318.698119) (xy 61.914319 -318.704168)
			(xy 61.988817 -318.718215) (xy 62.0614 -318.740101) (xy 62.131246 -318.769578) (xy 62.197563 -318.806313)
			(xy 62.259599 -318.849888) (xy 62.316652 -318.89981) (xy 62.368076 -318.955514) (xy 62.413287 -319.016369)
			(xy 62.451774 -319.081684) (xy 62.4831 -319.15072) (xy 62.50691 -319.222695) (xy 62.522935 -319.296793)
			(xy 62.530994 -319.372174) (xy 62.531498 -319.41008) (xy 62.530994 -319.447986) (xy 62.522935 -319.523367)
			(xy 62.50691 -319.597465) (xy 62.4831 -319.66944) (xy 62.451774 -319.738476) (xy 62.413287 -319.803791)
			(xy 62.368076 -319.864646) (xy 62.316652 -319.92035) (xy 62.265544 -319.96507) (xy 84.927697 -319.96507)
			(xy 84.931732 -319.889366) (xy 84.943791 -319.814521) (xy 84.963737 -319.74138) (xy 84.991344 -319.670775)
			(xy 85.0263 -319.603504) (xy 85.068208 -319.540329) (xy 85.116594 -319.481967) (xy 85.17091 -319.429079)
			(xy 85.230539 -319.382264) (xy 85.294807 -319.342052) (xy 85.362984 -319.3089) (xy 85.4343 -319.283182)
			(xy 85.507945 -319.26519) (xy 85.583085 -319.255128) (xy 85.658869 -319.253109) (xy 85.734439 -319.259158)
			(xy 85.808937 -319.273205) (xy 85.88152 -319.295091) (xy 85.951366 -319.324568) (xy 86.017683 -319.361303)
			(xy 86.079719 -319.404878) (xy 86.136772 -319.4548) (xy 86.188196 -319.510504) (xy 86.233407 -319.571359)
			(xy 86.271894 -319.636674) (xy 86.30322 -319.70571) (xy 86.32703 -319.777685) (xy 86.343055 -319.851783)
			(xy 86.351114 -319.927164) (xy 86.351618 -319.96507) (xy 87.467697 -319.96507) (xy 87.471732 -319.889366)
			(xy 87.483791 -319.814521) (xy 87.503737 -319.74138) (xy 87.531344 -319.670775) (xy 87.5663 -319.603504)
			(xy 87.608208 -319.540329) (xy 87.656594 -319.481967) (xy 87.71091 -319.429079) (xy 87.770539 -319.382264)
			(xy 87.834807 -319.342052) (xy 87.902984 -319.3089) (xy 87.9743 -319.283182) (xy 88.047945 -319.26519)
			(xy 88.123085 -319.255128) (xy 88.198869 -319.253109) (xy 88.274439 -319.259158) (xy 88.348937 -319.273205)
			(xy 88.42152 -319.295091) (xy 88.491366 -319.324568) (xy 88.557683 -319.361303) (xy 88.619719 -319.404878)
			(xy 88.676772 -319.4548) (xy 88.728196 -319.510504) (xy 88.773407 -319.571359) (xy 88.811894 -319.636674)
			(xy 88.84322 -319.70571) (xy 88.86703 -319.777685) (xy 88.883055 -319.851783) (xy 88.891114 -319.927164)
			(xy 88.891618 -319.96507) (xy 90.007697 -319.96507) (xy 90.011732 -319.889366) (xy 90.023791 -319.814521)
			(xy 90.043737 -319.74138) (xy 90.071344 -319.670775) (xy 90.1063 -319.603504) (xy 90.148208 -319.540329)
			(xy 90.196594 -319.481967) (xy 90.25091 -319.429079) (xy 90.310539 -319.382264) (xy 90.374807 -319.342052)
			(xy 90.442984 -319.3089) (xy 90.5143 -319.283182) (xy 90.587945 -319.26519) (xy 90.663085 -319.255128)
			(xy 90.738869 -319.253109) (xy 90.814439 -319.259158) (xy 90.888937 -319.273205) (xy 90.96152 -319.295091)
			(xy 91.031366 -319.324568) (xy 91.097683 -319.361303) (xy 91.159719 -319.404878) (xy 91.165664 -319.41008)
			(xy 93.154506 -319.41008) (xy 93.158522 -319.29381) (xy 93.170549 -319.178095) (xy 93.190531 -319.063485)
			(xy 93.218373 -318.950526) (xy 93.253942 -318.839758) (xy 93.297068 -318.731707) (xy 93.347545 -318.626889)
			(xy 93.405134 -318.525804) (xy 93.46956 -318.428932) (xy 93.540515 -318.336736) (xy 93.617662 -318.249655)
			(xy 93.700633 -318.168104) (xy 93.789033 -318.092472) (xy 93.88244 -318.023118) (xy 93.980409 -317.960375)
			(xy 94.082473 -317.904539) (xy 94.188147 -317.855878) (xy 94.296926 -317.814624) (xy 94.408291 -317.780973)
			(xy 94.521714 -317.755085) (xy 94.636651 -317.737084) (xy 94.752557 -317.727055) (xy 94.868879 -317.725047)
			(xy 94.985062 -317.731069) (xy 95.100553 -317.745092) (xy 95.214801 -317.76705) (xy 95.327262 -317.796837)
			(xy 95.4374 -317.834312) (xy 95.54469 -317.879297) (xy 95.648621 -317.931576) (xy 95.748697 -317.990901)
			(xy 95.844443 -318.056989) (xy 95.9354 -318.129525) (xy 96.021136 -318.208164) (xy 96.101243 -318.29253)
			(xy 96.175339 -318.382222) (xy 96.243069 -318.476812) (xy 96.304113 -318.57585) (xy 96.358178 -318.678863)
			(xy 96.405008 -318.78536) (xy 96.444379 -318.894835) (xy 96.476103 -319.006765) (xy 96.500029 -319.120617)
			(xy 96.516043 -319.235849) (xy 96.52407 -319.351911) (xy 96.524572 -319.41008) (xy 96.52407 -319.468249)
			(xy 96.516043 -319.584311) (xy 96.500029 -319.699543) (xy 96.476103 -319.813395) (xy 96.444379 -319.925325)
			(xy 96.405008 -320.0348) (xy 96.358178 -320.141297) (xy 96.304113 -320.24431) (xy 96.243069 -320.343348)
			(xy 96.175339 -320.437938) (xy 96.101243 -320.52763) (xy 96.021136 -320.611996) (xy 95.9354 -320.690635)
			(xy 95.844443 -320.763171) (xy 95.748697 -320.829259) (xy 95.648621 -320.888584) (xy 95.54469 -320.940863)
			(xy 95.4374 -320.985848) (xy 95.327262 -321.023323) (xy 95.214801 -321.05311) (xy 95.100553 -321.075068)
			(xy 94.985062 -321.089091) (xy 94.868879 -321.095113) (xy 94.752557 -321.093105) (xy 94.636651 -321.083076)
			(xy 94.521714 -321.065075) (xy 94.408291 -321.039187) (xy 94.296926 -321.005536) (xy 94.188147 -320.964282)
			(xy 94.082473 -320.915621) (xy 93.980409 -320.859785) (xy 93.88244 -320.797042) (xy 93.789033 -320.727688)
			(xy 93.700633 -320.652056) (xy 93.617662 -320.570505) (xy 93.540515 -320.483424) (xy 93.46956 -320.391228)
			(xy 93.405134 -320.294356) (xy 93.347545 -320.193271) (xy 93.297068 -320.088453) (xy 93.253942 -319.980402)
			(xy 93.218373 -319.869634) (xy 93.190531 -319.756675) (xy 93.170549 -319.642065) (xy 93.158522 -319.52635)
			(xy 93.154506 -319.41008) (xy 91.165664 -319.41008) (xy 91.216772 -319.4548) (xy 91.268196 -319.510504)
			(xy 91.313407 -319.571359) (xy 91.351894 -319.636674) (xy 91.38322 -319.70571) (xy 91.40703 -319.777685)
			(xy 91.423055 -319.851783) (xy 91.431114 -319.927164) (xy 91.431618 -319.96507) (xy 91.431114 -320.002976)
			(xy 91.423055 -320.078357) (xy 91.40703 -320.152455) (xy 91.38322 -320.22443) (xy 91.351894 -320.293466)
			(xy 91.313407 -320.358781) (xy 91.268196 -320.419636) (xy 91.216772 -320.47534) (xy 91.159719 -320.525262)
			(xy 91.097683 -320.568837) (xy 91.031366 -320.605572) (xy 90.96152 -320.635049) (xy 90.888937 -320.656935)
			(xy 90.814439 -320.670982) (xy 90.738869 -320.677031) (xy 90.663085 -320.675012) (xy 90.587945 -320.66495)
			(xy 90.5143 -320.646958) (xy 90.442984 -320.62124) (xy 90.374807 -320.588088) (xy 90.310539 -320.547876)
			(xy 90.25091 -320.501061) (xy 90.196594 -320.448173) (xy 90.148208 -320.389811) (xy 90.1063 -320.326636)
			(xy 90.071344 -320.259365) (xy 90.043737 -320.18876) (xy 90.023791 -320.115619) (xy 90.011732 -320.040774)
			(xy 90.007697 -319.96507) (xy 88.891618 -319.96507) (xy 88.891114 -320.002976) (xy 88.883055 -320.078357)
			(xy 88.86703 -320.152455) (xy 88.84322 -320.22443) (xy 88.811894 -320.293466) (xy 88.773407 -320.358781)
			(xy 88.728196 -320.419636) (xy 88.676772 -320.47534) (xy 88.619719 -320.525262) (xy 88.557683 -320.568837)
			(xy 88.491366 -320.605572) (xy 88.42152 -320.635049) (xy 88.348937 -320.656935) (xy 88.274439 -320.670982)
			(xy 88.198869 -320.677031) (xy 88.123085 -320.675012) (xy 88.047945 -320.66495) (xy 87.9743 -320.646958)
			(xy 87.902984 -320.62124) (xy 87.834807 -320.588088) (xy 87.770539 -320.547876) (xy 87.71091 -320.501061)
			(xy 87.656594 -320.448173) (xy 87.608208 -320.389811) (xy 87.5663 -320.326636) (xy 87.531344 -320.259365)
			(xy 87.503737 -320.18876) (xy 87.483791 -320.115619) (xy 87.471732 -320.040774) (xy 87.467697 -319.96507)
			(xy 86.351618 -319.96507) (xy 86.351114 -320.002976) (xy 86.343055 -320.078357) (xy 86.32703 -320.152455)
			(xy 86.30322 -320.22443) (xy 86.271894 -320.293466) (xy 86.233407 -320.358781) (xy 86.188196 -320.419636)
			(xy 86.136772 -320.47534) (xy 86.079719 -320.525262) (xy 86.017683 -320.568837) (xy 85.951366 -320.605572)
			(xy 85.88152 -320.635049) (xy 85.808937 -320.656935) (xy 85.734439 -320.670982) (xy 85.658869 -320.677031)
			(xy 85.583085 -320.675012) (xy 85.507945 -320.66495) (xy 85.4343 -320.646958) (xy 85.362984 -320.62124)
			(xy 85.294807 -320.588088) (xy 85.230539 -320.547876) (xy 85.17091 -320.501061) (xy 85.116594 -320.448173)
			(xy 85.068208 -320.389811) (xy 85.0263 -320.326636) (xy 84.991344 -320.259365) (xy 84.963737 -320.18876)
			(xy 84.943791 -320.115619) (xy 84.931732 -320.040774) (xy 84.927697 -319.96507) (xy 62.265544 -319.96507)
			(xy 62.259599 -319.970272) (xy 62.197563 -320.013847) (xy 62.131246 -320.050582) (xy 62.0614 -320.080059)
			(xy 61.988817 -320.101945) (xy 61.914319 -320.115992) (xy 61.838749 -320.122041) (xy 61.762965 -320.120022)
			(xy 61.687825 -320.10996) (xy 61.61418 -320.091968) (xy 61.542864 -320.06625) (xy 61.474687 -320.033098)
			(xy 61.410419 -319.992886) (xy 61.35079 -319.946071) (xy 61.296474 -319.893183) (xy 61.248088 -319.834821)
			(xy 61.20618 -319.771646) (xy 61.171224 -319.704375) (xy 61.143617 -319.63377) (xy 61.123671 -319.560629)
			(xy 61.111612 -319.485784) (xy 61.107577 -319.41008) (xy 59.991498 -319.41008) (xy 59.990994 -319.447986)
			(xy 59.982935 -319.523367) (xy 59.96691 -319.597465) (xy 59.9431 -319.66944) (xy 59.911774 -319.738476)
			(xy 59.873287 -319.803791) (xy 59.828076 -319.864646) (xy 59.776652 -319.92035) (xy 59.719599 -319.970272)
			(xy 59.657563 -320.013847) (xy 59.591246 -320.050582) (xy 59.5214 -320.080059) (xy 59.448817 -320.101945)
			(xy 59.374319 -320.115992) (xy 59.298749 -320.122041) (xy 59.222965 -320.120022) (xy 59.147825 -320.10996)
			(xy 59.07418 -320.091968) (xy 59.002864 -320.06625) (xy 58.934687 -320.033098) (xy 58.870419 -319.992886)
			(xy 58.81079 -319.946071) (xy 58.756474 -319.893183) (xy 58.708088 -319.834821) (xy 58.66618 -319.771646)
			(xy 58.631224 -319.704375) (xy 58.603617 -319.63377) (xy 58.583671 -319.560629) (xy 58.571612 -319.485784)
			(xy 58.567577 -319.41008) (xy 57.451498 -319.41008) (xy 57.450994 -319.447986) (xy 57.442935 -319.523367)
			(xy 57.42691 -319.597465) (xy 57.4031 -319.66944) (xy 57.371774 -319.738476) (xy 57.333287 -319.803791)
			(xy 57.288076 -319.864646) (xy 57.236652 -319.92035) (xy 57.179599 -319.970272) (xy 57.117563 -320.013847)
			(xy 57.051246 -320.050582) (xy 56.9814 -320.080059) (xy 56.908817 -320.101945) (xy 56.834319 -320.115992)
			(xy 56.758749 -320.122041) (xy 56.682965 -320.120022) (xy 56.607825 -320.10996) (xy 56.53418 -320.091968)
			(xy 56.462864 -320.06625) (xy 56.394687 -320.033098) (xy 56.330419 -319.992886) (xy 56.27079 -319.946071)
			(xy 56.216474 -319.893183) (xy 56.168088 -319.834821) (xy 56.12618 -319.771646) (xy 56.091224 -319.704375)
			(xy 56.063617 -319.63377) (xy 56.043671 -319.560629) (xy 56.031612 -319.485784) (xy 56.027577 -319.41008)
			(xy 54.911498 -319.41008) (xy 54.910994 -319.447986) (xy 54.902935 -319.523367) (xy 54.88691 -319.597465)
			(xy 54.8631 -319.66944) (xy 54.831774 -319.738476) (xy 54.793287 -319.803791) (xy 54.748076 -319.864646)
			(xy 54.696652 -319.92035) (xy 54.639599 -319.970272) (xy 54.577563 -320.013847) (xy 54.511246 -320.050582)
			(xy 54.4414 -320.080059) (xy 54.368817 -320.101945) (xy 54.294319 -320.115992) (xy 54.218749 -320.122041)
			(xy 54.142965 -320.120022) (xy 54.067825 -320.10996) (xy 53.99418 -320.091968) (xy 53.922864 -320.06625)
			(xy 53.854687 -320.033098) (xy 53.790419 -319.992886) (xy 53.73079 -319.946071) (xy 53.676474 -319.893183)
			(xy 53.628088 -319.834821) (xy 53.58618 -319.771646) (xy 53.551224 -319.704375) (xy 53.523617 -319.63377)
			(xy 53.503671 -319.560629) (xy 53.491612 -319.485784) (xy 53.487577 -319.41008) (xy 52.371498 -319.41008)
			(xy 52.370994 -319.447986) (xy 52.362935 -319.523367) (xy 52.34691 -319.597465) (xy 52.3231 -319.66944)
			(xy 52.291774 -319.738476) (xy 52.253287 -319.803791) (xy 52.208076 -319.864646) (xy 52.156652 -319.92035)
			(xy 52.099599 -319.970272) (xy 52.037563 -320.013847) (xy 51.971246 -320.050582) (xy 51.9014 -320.080059)
			(xy 51.828817 -320.101945) (xy 51.754319 -320.115992) (xy 51.678749 -320.122041) (xy 51.602965 -320.120022)
			(xy 51.527825 -320.10996) (xy 51.45418 -320.091968) (xy 51.382864 -320.06625) (xy 51.314687 -320.033098)
			(xy 51.250419 -319.992886) (xy 51.19079 -319.946071) (xy 51.136474 -319.893183) (xy 51.088088 -319.834821)
			(xy 51.04618 -319.771646) (xy 51.011224 -319.704375) (xy 50.983617 -319.63377) (xy 50.963671 -319.560629)
			(xy 50.951612 -319.485784) (xy 50.947577 -319.41008) (xy 49.831498 -319.41008) (xy 49.830994 -319.447986)
			(xy 49.822935 -319.523367) (xy 49.80691 -319.597465) (xy 49.7831 -319.66944) (xy 49.751774 -319.738476)
			(xy 49.713287 -319.803791) (xy 49.668076 -319.864646) (xy 49.616652 -319.92035) (xy 49.559599 -319.970272)
			(xy 49.497563 -320.013847) (xy 49.431246 -320.050582) (xy 49.3614 -320.080059) (xy 49.288817 -320.101945)
			(xy 49.214319 -320.115992) (xy 49.138749 -320.122041) (xy 49.062965 -320.120022) (xy 48.987825 -320.10996)
			(xy 48.91418 -320.091968) (xy 48.842864 -320.06625) (xy 48.774687 -320.033098) (xy 48.710419 -319.992886)
			(xy 48.65079 -319.946071) (xy 48.596474 -319.893183) (xy 48.548088 -319.834821) (xy 48.50618 -319.771646)
			(xy 48.471224 -319.704375) (xy 48.443617 -319.63377) (xy 48.423671 -319.560629) (xy 48.411612 -319.485784)
			(xy 48.407577 -319.41008) (xy 47.291498 -319.41008) (xy 47.290994 -319.447986) (xy 47.282935 -319.523367)
			(xy 47.26691 -319.597465) (xy 47.2431 -319.66944) (xy 47.211774 -319.738476) (xy 47.173287 -319.803791)
			(xy 47.128076 -319.864646) (xy 47.076652 -319.92035) (xy 47.019599 -319.970272) (xy 46.957563 -320.013847)
			(xy 46.891246 -320.050582) (xy 46.8214 -320.080059) (xy 46.748817 -320.101945) (xy 46.674319 -320.115992)
			(xy 46.598749 -320.122041) (xy 46.522965 -320.120022) (xy 46.447825 -320.10996) (xy 46.37418 -320.091968)
			(xy 46.302864 -320.06625) (xy 46.234687 -320.033098) (xy 46.170419 -319.992886) (xy 46.11079 -319.946071)
			(xy 46.056474 -319.893183) (xy 46.008088 -319.834821) (xy 45.96618 -319.771646) (xy 45.931224 -319.704375)
			(xy 45.903617 -319.63377) (xy 45.883671 -319.560629) (xy 45.871612 -319.485784) (xy 45.867577 -319.41008)
			(xy 44.751244 -319.41008) (xy 44.751244 -320.121788) (xy 43.328336 -320.121788) (xy 43.328336 -318.698372)
			(xy 43.055152 -318.698372) (xy 43.014974 -318.789744) (xy 42.961022 -318.89254) (xy 42.900108 -318.991368)
			(xy 42.83252 -319.085759) (xy 42.758581 -319.175261) (xy 42.678643 -319.259449) (xy 42.593088 -319.337922)
			(xy 42.502322 -319.410305) (xy 42.406779 -319.476254) (xy 42.306914 -319.535454) (xy 42.203202 -319.587623)
			(xy 42.096139 -319.632512) (xy 41.986233 -319.669908) (xy 41.874009 -319.699633) (xy 41.760003 -319.721544)
			(xy 41.644756 -319.735537) (xy 41.528818 -319.741546) (xy 41.412742 -319.739543) (xy 41.29708 -319.729535)
			(xy 41.182385 -319.711572) (xy 41.069202 -319.685739) (xy 40.958071 -319.652159) (xy 40.849522 -319.610991)
			(xy 40.744072 -319.562433) (xy 40.642223 -319.506716) (xy 40.54446 -319.444104) (xy 40.45125 -319.374897)
			(xy 40.363037 -319.299424) (xy 40.280241 -319.218045) (xy 40.203257 -319.131148) (xy 40.132452 -319.039147)
			(xy 40.068162 -318.94248) (xy 40.010695 -318.841608) (xy 39.960324 -318.737011) (xy 39.917289 -318.629188)
			(xy 39.881795 -318.518654) (xy 39.854012 -318.405934) (xy 39.834072 -318.291566) (xy 39.82207 -318.176094)
			(xy 39.818063 -318.06007) (xy 36.479871 -318.06007) (xy 36.479486 -318.09336) (xy 36.471468 -318.179889)
			(xy 36.4555 -318.265309) (xy 36.431719 -318.348891) (xy 36.400327 -318.429923) (xy 36.361593 -318.507712)
			(xy 36.315846 -318.581596) (xy 36.263477 -318.650943) (xy 36.204933 -318.715163) (xy 36.140713 -318.773707)
			(xy 36.071366 -318.826076) (xy 35.997482 -318.871823) (xy 35.919693 -318.910557) (xy 35.838661 -318.941949)
			(xy 35.755079 -318.96573) (xy 35.669659 -318.981698) (xy 35.58313 -318.989716) (xy 35.49623 -318.989716)
			(xy 35.409701 -318.981698) (xy 35.324281 -318.96573) (xy 35.240699 -318.941949) (xy 35.159667 -318.910557)
			(xy 35.081878 -318.871823) (xy 35.007994 -318.826076) (xy 34.938647 -318.773707) (xy 34.874427 -318.715163)
			(xy 34.815883 -318.650943) (xy 34.763514 -318.581596) (xy 34.717767 -318.507712) (xy 34.679033 -318.429923)
			(xy 34.647641 -318.348891) (xy 34.62386 -318.265309) (xy 34.607892 -318.179889) (xy 34.599874 -318.09336)
			(xy 31.399486 -318.09336) (xy 31.391468 -318.179889) (xy 31.3755 -318.265309) (xy 31.351719 -318.348891)
			(xy 31.320327 -318.429923) (xy 31.281593 -318.507712) (xy 31.235846 -318.581596) (xy 31.183477 -318.650943)
			(xy 31.124933 -318.715163) (xy 31.060713 -318.773707) (xy 30.991366 -318.826076) (xy 30.917482 -318.871823)
			(xy 30.839693 -318.910557) (xy 30.758661 -318.941949) (xy 30.675079 -318.96573) (xy 30.589659 -318.981698)
			(xy 30.50313 -318.989716) (xy 30.41623 -318.989716) (xy 30.329701 -318.981698) (xy 30.244281 -318.96573)
			(xy 30.160699 -318.941949) (xy 30.079667 -318.910557) (xy 30.001878 -318.871823) (xy 29.927994 -318.826076)
			(xy 29.858647 -318.773707) (xy 29.794427 -318.715163) (xy 29.735883 -318.650943) (xy 29.683514 -318.581596)
			(xy 29.637767 -318.507712) (xy 29.599033 -318.429923) (xy 29.567641 -318.348891) (xy 29.54386 -318.265309)
			(xy 29.527892 -318.179889) (xy 29.519874 -318.09336) (xy 28.067 -318.09336) (xy 28.067 -324.309486)
			(xy 84.26145 -324.309486) (xy 84.265521 -324.253864) (xy 84.277647 -324.199427) (xy 84.29757 -324.147336)
			(xy 84.324866 -324.098701) (xy 84.358952 -324.054558) (xy 84.399101 -324.015849) (xy 84.444459 -323.983398)
			(xy 84.494059 -323.957897) (xy 84.546843 -323.93989) (xy 84.601686 -323.92976) (xy 84.65742 -323.927723)
			(xy 84.712857 -323.933823) (xy 84.766814 -323.947929) (xy 84.818143 -323.969741) (xy 84.865749 -323.998795)
			(xy 84.908617 -324.03447) (xy 84.945834 -324.076007) (xy 84.976607 -324.12252) (xy 85.000279 -324.173017)
			(xy 85.016347 -324.226424) (xy 85.024467 -324.2816) (xy 85.024976 -324.309486) (xy 85.024467 -324.337372)
			(xy 85.016347 -324.392548) (xy 85.000279 -324.445955) (xy 84.976607 -324.496452) (xy 84.945834 -324.542965)
			(xy 84.908617 -324.584502) (xy 84.865749 -324.620177) (xy 84.818143 -324.649231) (xy 84.766814 -324.671043)
			(xy 84.712857 -324.685149) (xy 84.65742 -324.691249) (xy 84.601686 -324.689212) (xy 84.546843 -324.679082)
			(xy 84.494059 -324.661075) (xy 84.444459 -324.635574) (xy 84.399101 -324.603123) (xy 84.358952 -324.564414)
			(xy 84.324866 -324.520271) (xy 84.29757 -324.471636) (xy 84.277647 -324.419545) (xy 84.265521 -324.365108)
			(xy 84.26145 -324.309486) (xy 28.067 -324.309486) (xy 28.067 -324.979538) (xy 82.79079 -324.979538)
			(xy 82.794861 -324.923916) (xy 82.806987 -324.869479) (xy 82.82691 -324.817388) (xy 82.854206 -324.768753)
			(xy 82.888292 -324.72461) (xy 82.928441 -324.685901) (xy 82.973799 -324.65345) (xy 83.023399 -324.627949)
			(xy 83.076183 -324.609942) (xy 83.131026 -324.599812) (xy 83.18676 -324.597775) (xy 83.242197 -324.603875)
			(xy 83.296154 -324.617981) (xy 83.347483 -324.639793) (xy 83.395089 -324.668847) (xy 83.437957 -324.704522)
			(xy 83.475174 -324.746059) (xy 83.505947 -324.792572) (xy 83.529619 -324.843069) (xy 83.545687 -324.896476)
			(xy 83.553807 -324.951652) (xy 83.554316 -324.979538) (xy 83.553807 -325.007424) (xy 83.545687 -325.0626)
			(xy 83.529619 -325.116007) (xy 83.505947 -325.166504) (xy 83.475174 -325.213017) (xy 83.437957 -325.254554)
			(xy 83.395089 -325.290229) (xy 83.347483 -325.319283) (xy 83.296154 -325.341095) (xy 83.242197 -325.355201)
			(xy 83.18676 -325.361301) (xy 83.131026 -325.359264) (xy 83.076183 -325.349134) (xy 83.023399 -325.331127)
			(xy 82.973799 -325.305626) (xy 82.928441 -325.273175) (xy 82.888292 -325.234466) (xy 82.854206 -325.190323)
			(xy 82.82691 -325.141688) (xy 82.806987 -325.089597) (xy 82.794861 -325.03516) (xy 82.79079 -324.979538)
			(xy 28.067 -324.979538) (xy 28.067 -325.649844) (xy 81.400394 -325.649844) (xy 81.404465 -325.594222)
			(xy 81.416591 -325.539785) (xy 81.436514 -325.487694) (xy 81.46381 -325.439059) (xy 81.497896 -325.394916)
			(xy 81.538045 -325.356207) (xy 81.583403 -325.323756) (xy 81.633003 -325.298255) (xy 81.685787 -325.280248)
			(xy 81.74063 -325.270118) (xy 81.796364 -325.268081) (xy 81.851801 -325.274181) (xy 81.905758 -325.288287)
			(xy 81.957087 -325.310099) (xy 82.004693 -325.339153) (xy 82.047561 -325.374828) (xy 82.084778 -325.416365)
			(xy 82.115551 -325.462878) (xy 82.139223 -325.513375) (xy 82.155291 -325.566782) (xy 82.163411 -325.621958)
			(xy 82.16392 -325.649844) (xy 82.163411 -325.67773) (xy 82.155291 -325.732906) (xy 82.139223 -325.786313)
			(xy 82.115551 -325.83681) (xy 82.084778 -325.883323) (xy 82.047561 -325.92486) (xy 82.004693 -325.960535)
			(xy 81.957087 -325.989589) (xy 81.905758 -326.011401) (xy 81.851801 -326.025507) (xy 81.796364 -326.031607)
			(xy 81.74063 -326.02957) (xy 81.685787 -326.01944) (xy 81.633003 -326.001433) (xy 81.583403 -325.975932)
			(xy 81.538045 -325.943481) (xy 81.497896 -325.904772) (xy 81.46381 -325.860629) (xy 81.436514 -325.811994)
			(xy 81.416591 -325.759903) (xy 81.404465 -325.705466) (xy 81.400394 -325.649844) (xy 28.067 -325.649844)
			(xy 28.067 -326.140064) (xy 83.341208 -326.140064) (xy 83.345279 -326.084442) (xy 83.357405 -326.030005)
			(xy 83.377328 -325.977914) (xy 83.404624 -325.929279) (xy 83.43871 -325.885136) (xy 83.478859 -325.846427)
			(xy 83.524217 -325.813976) (xy 83.573817 -325.788475) (xy 83.626601 -325.770468) (xy 83.681444 -325.760338)
			(xy 83.737178 -325.758301) (xy 83.792615 -325.764401) (xy 83.846572 -325.778507) (xy 83.850429 -325.780146)
			(xy 85.48192 -325.780146) (xy 85.485991 -325.724524) (xy 85.498117 -325.670087) (xy 85.51804 -325.617996)
			(xy 85.545336 -325.569361) (xy 85.579422 -325.525218) (xy 85.619571 -325.486509) (xy 85.664929 -325.454058)
			(xy 85.714529 -325.428557) (xy 85.767313 -325.41055) (xy 85.822156 -325.40042) (xy 85.87789 -325.398383)
			(xy 85.933327 -325.404483) (xy 85.987284 -325.418589) (xy 86.038613 -325.440401) (xy 86.086219 -325.469455)
			(xy 86.129087 -325.50513) (xy 86.166304 -325.546667) (xy 86.197077 -325.59318) (xy 86.220749 -325.643677)
			(xy 86.236817 -325.697084) (xy 86.244937 -325.75226) (xy 86.245446 -325.780146) (xy 86.244937 -325.808032)
			(xy 86.236817 -325.863208) (xy 86.220749 -325.916615) (xy 86.197077 -325.967112) (xy 86.166304 -326.013625)
			(xy 86.129087 -326.055162) (xy 86.086219 -326.090837) (xy 86.038613 -326.119891) (xy 85.987284 -326.141703)
			(xy 85.933327 -326.155809) (xy 85.87789 -326.161909) (xy 85.822156 -326.159872) (xy 85.767313 -326.149742)
			(xy 85.714529 -326.131735) (xy 85.664929 -326.106234) (xy 85.619571 -326.073783) (xy 85.579422 -326.035074)
			(xy 85.545336 -325.990931) (xy 85.51804 -325.942296) (xy 85.498117 -325.890205) (xy 85.485991 -325.835768)
			(xy 85.48192 -325.780146) (xy 83.850429 -325.780146) (xy 83.897901 -325.800319) (xy 83.945507 -325.829373)
			(xy 83.988375 -325.865048) (xy 84.025592 -325.906585) (xy 84.056365 -325.953098) (xy 84.080037 -326.003595)
			(xy 84.096105 -326.057002) (xy 84.104225 -326.112178) (xy 84.104734 -326.140064) (xy 84.104225 -326.16795)
			(xy 84.096105 -326.223126) (xy 84.080037 -326.276533) (xy 84.056365 -326.32703) (xy 84.025592 -326.373543)
			(xy 83.988375 -326.41508) (xy 83.945507 -326.450755) (xy 83.897901 -326.479809) (xy 83.846572 -326.501621)
			(xy 83.792615 -326.515727) (xy 83.737178 -326.521827) (xy 83.681444 -326.51979) (xy 83.626601 -326.50966)
			(xy 83.573817 -326.491653) (xy 83.524217 -326.466152) (xy 83.478859 -326.433701) (xy 83.43871 -326.394992)
			(xy 83.404624 -326.350849) (xy 83.377328 -326.302214) (xy 83.357405 -326.250123) (xy 83.345279 -326.195686)
			(xy 83.341208 -326.140064) (xy 28.067 -326.140064) (xy 28.067 -328.665586) (xy 71.578724 -328.665586)
			(xy 71.578724 -327.767188) (xy 71.579405 -327.731122) (xy 71.589734 -327.65973) (xy 71.599298 -327.624948)
			(xy 71.604124 -327.607422) (xy 71.604124 -327.23328) (xy 72.57034 -327.23328) (xy 72.57034 -327.607422)
			(xy 72.575166 -327.624948) (xy 72.584712 -327.659734) (xy 72.595036 -327.731123) (xy 72.59574 -327.767188)
			(xy 72.59574 -327.821036) (xy 72.950832 -327.821036) (xy 72.950832 -326.922638) (xy 72.951344 -326.889903)
			(xy 72.959781 -326.824978) (xy 72.976482 -326.761672) (xy 73.00117 -326.701034) (xy 73.033436 -326.644067)
			(xy 73.052686 -326.617584) (xy 73.077832 -326.583802) (xy 73.077832 -326.566784) (xy 73.093326 -326.566784)
			(xy 73.12914 -326.536304) (xy 73.154317 -326.515451) (xy 73.209049 -326.4797) (xy 73.267914 -326.451261)
			(xy 73.329939 -326.430606) (xy 73.394101 -326.418075) (xy 73.45934 -326.413875) (xy 73.524579 -326.418075)
			(xy 73.588741 -326.430606) (xy 73.650766 -326.451261) (xy 73.709631 -326.4797) (xy 73.764363 -326.515451)
			(xy 73.78954 -326.536304) (xy 73.825354 -326.566784) (xy 73.840848 -326.566784) (xy 73.840848 -326.583802)
			(xy 73.865994 -326.617584) (xy 73.876154 -326.631808) (xy 73.889266 -326.649756) (xy 73.920681 -326.681194)
			(xy 73.957081 -326.706697) (xy 73.997357 -326.725489) (xy 74.040286 -326.736997) (xy 74.084561 -326.740873)
			(xy 74.128836 -326.736997) (xy 74.171765 -326.725489) (xy 74.212041 -326.706697) (xy 74.248441 -326.681194)
			(xy 74.279856 -326.649756) (xy 74.292968 -326.631808) (xy 74.303128 -326.617584) (xy 74.328528 -326.583802)
			(xy 74.328528 -326.566784) (xy 74.343768 -326.566784) (xy 74.379582 -326.536304) (xy 74.404759 -326.515451)
			(xy 74.459491 -326.4797) (xy 74.518356 -326.451261) (xy 74.580381 -326.430606) (xy 74.644543 -326.418075)
			(xy 74.709782 -326.413875) (xy 74.775021 -326.418075) (xy 74.839183 -326.430606) (xy 74.901208 -326.451261)
			(xy 74.960073 -326.4797) (xy 75.014805 -326.515451) (xy 75.039982 -326.536304) (xy 75.075796 -326.566784)
			(xy 75.091036 -326.566784) (xy 75.091036 -326.583802) (xy 75.116436 -326.617584) (xy 75.135668 -326.644071)
			(xy 75.167896 -326.701043) (xy 75.192536 -326.761685) (xy 75.209179 -326.82499) (xy 75.217548 -326.889909)
			(xy 75.218036 -326.922638) (xy 75.218036 -327.462134) (xy 82.91271 -327.462134) (xy 82.916781 -327.406512)
			(xy 82.928907 -327.352075) (xy 82.94883 -327.299984) (xy 82.976126 -327.251349) (xy 83.010212 -327.207206)
			(xy 83.050361 -327.168497) (xy 83.095719 -327.136046) (xy 83.145319 -327.110545) (xy 83.198103 -327.092538)
			(xy 83.252946 -327.082408) (xy 83.30868 -327.080371) (xy 83.364117 -327.086471) (xy 83.418074 -327.100577)
			(xy 83.469403 -327.122389) (xy 83.517009 -327.151443) (xy 83.559877 -327.187118) (xy 83.597094 -327.228655)
			(xy 83.627867 -327.275168) (xy 83.651539 -327.325665) (xy 83.667607 -327.379072) (xy 83.675727 -327.434248)
			(xy 83.676236 -327.462134) (xy 83.675727 -327.49002) (xy 83.667607 -327.545196) (xy 83.651539 -327.598603)
			(xy 83.627867 -327.6491) (xy 83.597094 -327.695613) (xy 83.559877 -327.73715) (xy 83.517009 -327.772825)
			(xy 83.469403 -327.801879) (xy 83.418074 -327.823691) (xy 83.364117 -327.837797) (xy 83.30868 -327.843897)
			(xy 83.252946 -327.84186) (xy 83.198103 -327.83173) (xy 83.145319 -327.813723) (xy 83.095719 -327.788222)
			(xy 83.050361 -327.755771) (xy 83.010212 -327.717062) (xy 82.976126 -327.672919) (xy 82.94883 -327.624284)
			(xy 82.928907 -327.572193) (xy 82.916781 -327.517756) (xy 82.91271 -327.462134) (xy 75.218036 -327.462134)
			(xy 75.218036 -327.821036) (xy 75.217585 -327.853225) (xy 75.209451 -327.917088) (xy 75.193318 -327.979413)
			(xy 75.169443 -328.039201) (xy 75.138211 -328.095496) (xy 75.100119 -328.147397) (xy 75.055779 -328.194072)
			(xy 75.005899 -328.234774) (xy 74.951279 -328.268852) (xy 74.892794 -328.29576) (xy 74.831378 -328.315067)
			(xy 74.768016 -328.326465) (xy 74.703722 -328.32977) (xy 74.639526 -328.32493) (xy 74.576454 -328.312022)
			(xy 74.515518 -328.291253) (xy 74.457691 -328.262956) (xy 74.403901 -328.227583) (xy 74.355008 -328.185701)
			(xy 74.311795 -328.13798) (xy 74.292968 -328.111866) (xy 74.279875 -328.09389) (xy 74.248484 -328.062394)
			(xy 74.212091 -328.036841) (xy 74.171806 -328.01801) (xy 74.128859 -328.006477) (xy 74.084561 -328.002593)
			(xy 74.040263 -328.006477) (xy 73.997316 -328.01801) (xy 73.957031 -328.036841) (xy 73.920638 -328.062394)
			(xy 73.889247 -328.09389) (xy 73.876154 -328.111866) (xy 73.857265 -328.13794) (xy 73.814049 -328.185664)
			(xy 73.765152 -328.22755) (xy 73.711357 -328.262926) (xy 73.653527 -328.291227) (xy 73.592586 -328.312)
			(xy 73.52951 -328.324911) (xy 73.465308 -328.329755) (xy 73.401009 -328.326454) (xy 73.337641 -328.31506)
			(xy 73.276219 -328.295756) (xy 73.217726 -328.268852) (xy 73.163098 -328.234777) (xy 73.11321 -328.194078)
			(xy 73.06886 -328.147405) (xy 73.030758 -328.095505) (xy 72.999514 -328.03921) (xy 72.975628 -327.979421)
			(xy 72.959483 -327.917094) (xy 72.951336 -327.853228) (xy 72.950832 -327.821036) (xy 72.59574 -327.821036)
			(xy 72.59574 -328.665586) (xy 72.595238 -328.697547) (xy 72.587227 -328.760965) (xy 72.57133 -328.822879)
			(xy 72.547798 -328.882312) (xy 72.517004 -328.938327) (xy 72.479431 -328.990042) (xy 72.435674 -329.036639)
			(xy 72.386421 -329.077384) (xy 72.33245 -329.111635) (xy 72.274611 -329.138852) (xy 72.213818 -329.158605)
			(xy 72.151028 -329.170583) (xy 72.087232 -329.174597) (xy 72.023436 -329.170583) (xy 71.960646 -329.158605)
			(xy 71.899853 -329.138852) (xy 71.842014 -329.111635) (xy 71.788043 -329.077384) (xy 71.73879 -329.036639)
			(xy 71.695033 -328.990042) (xy 71.65746 -328.938327) (xy 71.626666 -328.882312) (xy 71.603134 -328.822879)
			(xy 71.587237 -328.760965) (xy 71.579226 -328.697547) (xy 71.578724 -328.665586) (xy 28.067 -328.665586)
			(xy 28.067 -330.012971) (xy 47.903374 -330.012971) (xy 47.903374 -329.931861) (xy 47.911324 -329.851142)
			(xy 47.927147 -329.771591) (xy 47.950692 -329.693975) (xy 47.981731 -329.619039) (xy 48.019966 -329.547507)
			(xy 48.065028 -329.480067) (xy 48.116483 -329.417368) (xy 48.173836 -329.360015) (xy 48.236535 -329.30856)
			(xy 48.303975 -329.263498) (xy 48.375507 -329.225263) (xy 48.450443 -329.194224) (xy 48.528059 -329.170679)
			(xy 48.60761 -329.154856) (xy 48.688329 -329.146906) (xy 48.769439 -329.146906) (xy 48.850158 -329.154856)
			(xy 48.929709 -329.170679) (xy 49.007325 -329.194224) (xy 49.082261 -329.225263) (xy 49.153793 -329.263498)
			(xy 49.221233 -329.30856) (xy 49.283932 -329.360015) (xy 49.341285 -329.417368) (xy 49.39274 -329.480067)
			(xy 49.437802 -329.547507) (xy 49.476037 -329.619039) (xy 49.507076 -329.693975) (xy 49.530621 -329.771591)
			(xy 49.546444 -329.851142) (xy 49.554394 -329.931861) (xy 49.554892 -329.972416) (xy 49.554394 -330.012971)
			(xy 49.546444 -330.09369) (xy 49.530621 -330.173241) (xy 49.507076 -330.250857) (xy 49.476037 -330.325793)
			(xy 49.437802 -330.397325) (xy 49.39274 -330.464765) (xy 49.341285 -330.527464) (xy 49.283932 -330.584817)
			(xy 49.221233 -330.636272) (xy 49.153793 -330.681334) (xy 49.082261 -330.719569) (xy 49.007325 -330.750608)
			(xy 48.929709 -330.774153) (xy 48.850158 -330.789976) (xy 48.769439 -330.797926) (xy 48.688329 -330.797926)
			(xy 48.60761 -330.789976) (xy 48.528059 -330.774153) (xy 48.450443 -330.750608) (xy 48.375507 -330.719569)
			(xy 48.303975 -330.681334) (xy 48.236535 -330.636272) (xy 48.173836 -330.584817) (xy 48.116483 -330.527464)
			(xy 48.065028 -330.464765) (xy 48.019966 -330.397325) (xy 47.981731 -330.325793) (xy 47.950692 -330.250857)
			(xy 47.927147 -330.173241) (xy 47.911324 -330.09369) (xy 47.903374 -330.012971) (xy 28.067 -330.012971)
			(xy 28.067 -331.16012) (xy 86.39887 -331.16012) (xy 86.402874 -330.960022) (xy 86.414881 -330.760244)
			(xy 86.434872 -330.561107) (xy 86.462814 -330.362929) (xy 86.498662 -330.166027) (xy 86.54236 -329.970718)
			(xy 86.593837 -329.777313) (xy 86.653011 -329.586123) (xy 86.719787 -329.397453) (xy 86.794059 -329.211606)
			(xy 86.875706 -329.028879) (xy 86.964599 -328.849566) (xy 87.060595 -328.673952) (xy 87.16354 -328.50232)
			(xy 87.27327 -328.334944) (xy 87.389608 -328.172093) (xy 87.512369 -328.014026) (xy 87.641356 -327.860998)
			(xy 87.776363 -327.713253) (xy 87.917172 -327.571027) (xy 88.063559 -327.43455) (xy 88.215289 -327.304038)
			(xy 88.37212 -327.179702) (xy 88.533799 -327.06174) (xy 88.700069 -326.950341) (xy 88.870662 -326.845684)
			(xy 89.045306 -326.747936) (xy 89.223722 -326.657253) (xy 89.405622 -326.573782) (xy 89.590717 -326.497655)
			(xy 89.778709 -326.428995) (xy 89.969298 -326.367911) (xy 90.162178 -326.314501) (xy 90.35704 -326.268852)
			(xy 90.553573 -326.231035) (xy 90.751462 -326.201111) (xy 90.950389 -326.179129) (xy 91.150037 -326.165124)
			(xy 91.350085 -326.159118) (xy 91.550213 -326.16112) (xy 91.750101 -326.171128) (xy 91.949428 -326.189125)
			(xy 92.147876 -326.215083) (xy 92.345126 -326.24896) (xy 92.540863 -326.290702) (xy 92.734773 -326.340241)
			(xy 92.926546 -326.397499) (xy 93.115875 -326.462384) (xy 93.302455 -326.534792) (xy 93.48599 -326.614608)
			(xy 93.666184 -326.701702) (xy 93.842749 -326.795936) (xy 94.015402 -326.897159) (xy 94.183867 -327.005209)
			(xy 94.347875 -327.119912) (xy 94.507162 -327.241086) (xy 94.661473 -327.368535) (xy 94.810561 -327.502056)
			(xy 94.954188 -327.641436) (xy 95.092124 -327.78645) (xy 95.224147 -327.936867) (xy 95.350046 -328.092445)
			(xy 95.46962 -328.252937) (xy 95.582676 -328.418083) (xy 95.689035 -328.587621) (xy 95.788526 -328.761279)
			(xy 95.880989 -328.938778) (xy 95.966276 -329.119834) (xy 96.044251 -329.304158) (xy 96.114788 -329.491454)
			(xy 96.177776 -329.681422) (xy 96.233113 -329.873758) (xy 96.28071 -330.068154) (xy 96.320491 -330.264299)
			(xy 96.352393 -330.461878) (xy 96.376364 -330.660575) (xy 96.392366 -330.860073) (xy 96.400373 -331.060051)
			(xy 96.400874 -331.16012) (xy 96.400373 -331.260189) (xy 96.392366 -331.460167) (xy 96.376364 -331.659665)
			(xy 96.352393 -331.858362) (xy 96.320491 -332.055941) (xy 96.28071 -332.252086) (xy 96.233113 -332.446482)
			(xy 96.177776 -332.638818) (xy 96.114788 -332.828786) (xy 96.044251 -333.016082) (xy 95.966276 -333.200406)
			(xy 95.880989 -333.381462) (xy 95.788526 -333.558961) (xy 95.689035 -333.732619) (xy 95.582676 -333.902157)
			(xy 95.46962 -334.067303) (xy 95.350046 -334.227795) (xy 95.224147 -334.383373) (xy 95.092124 -334.53379)
			(xy 94.954188 -334.678804) (xy 94.810561 -334.818184) (xy 94.661473 -334.951705) (xy 94.507162 -335.079154)
			(xy 94.347875 -335.200328) (xy 94.183867 -335.315031) (xy 94.015402 -335.423081) (xy 93.842749 -335.524304)
			(xy 93.666184 -335.618538) (xy 93.48599 -335.705632) (xy 93.302455 -335.785448) (xy 93.115875 -335.857856)
			(xy 92.926546 -335.922741) (xy 92.734773 -335.979999) (xy 92.540863 -336.029538) (xy 92.345126 -336.07128)
			(xy 92.147876 -336.105157) (xy 91.949428 -336.131115) (xy 91.750101 -336.149112) (xy 91.550213 -336.15912)
			(xy 91.350085 -336.161122) (xy 91.150037 -336.155116) (xy 90.950389 -336.141111) (xy 90.751462 -336.119129)
			(xy 90.553573 -336.089205) (xy 90.35704 -336.051388) (xy 90.162178 -336.005739) (xy 89.969298 -335.952329)
			(xy 89.778709 -335.891245) (xy 89.590717 -335.822585) (xy 89.405622 -335.746458) (xy 89.223722 -335.662987)
			(xy 89.045306 -335.572304) (xy 88.870662 -335.474556) (xy 88.700069 -335.369899) (xy 88.533799 -335.2585)
			(xy 88.37212 -335.140538) (xy 88.215289 -335.016202) (xy 88.063559 -334.88569) (xy 87.917172 -334.749213)
			(xy 87.776363 -334.606987) (xy 87.641356 -334.459242) (xy 87.512369 -334.306214) (xy 87.389608 -334.148147)
			(xy 87.27327 -333.985296) (xy 87.16354 -333.81792) (xy 87.060595 -333.646288) (xy 86.964599 -333.470674)
			(xy 86.875706 -333.291361) (xy 86.794059 -333.108634) (xy 86.719787 -332.922787) (xy 86.653011 -332.734117)
			(xy 86.593837 -332.542927) (xy 86.54236 -332.349522) (xy 86.498662 -332.154213) (xy 86.462814 -331.957311)
			(xy 86.434872 -331.759133) (xy 86.414881 -331.559996) (xy 86.402874 -331.360218) (xy 86.39887 -331.16012)
			(xy 28.067 -331.16012) (xy 28.067 -340.182708) (xy 28.08351 -340.199218) (xy 28.08351 -341.250016)
			(xy 69.997584 -341.250016) (xy 70.001572 -340.997396) (xy 70.013533 -340.745028) (xy 70.033455 -340.493164)
			(xy 70.061319 -340.242054) (xy 70.097095 -339.991948) (xy 70.140749 -339.743097) (xy 70.192238 -339.495748)
			(xy 70.251509 -339.250147) (xy 70.318504 -339.00654) (xy 70.393155 -338.76517) (xy 70.47539 -338.526276)
			(xy 70.565124 -338.290098) (xy 70.66227 -338.05687) (xy 70.76673 -337.826824) (xy 70.878401 -337.600192)
			(xy 70.99717 -337.377197) (xy 71.122919 -337.158063) (xy 71.255524 -336.943008) (xy 71.394851 -336.732246)
			(xy 71.540763 -336.525988) (xy 71.693113 -336.324439) (xy 71.851749 -336.127799) (xy 72.016514 -335.936266)
			(xy 72.187244 -335.750029) (xy 72.363768 -335.569275) (xy 72.54591 -335.394184) (xy 72.733488 -335.22493)
			(xy 72.926316 -335.061681) (xy 73.124201 -334.904602) (xy 73.326947 -334.753847) (xy 73.534351 -334.609569)
			(xy 73.746206 -334.471909) (xy 73.962301 -334.341006) (xy 74.182421 -334.21699) (xy 74.406346 -334.099985)
			(xy 74.633853 -333.990107) (xy 74.864715 -333.887466) (xy 75.098703 -333.792164) (xy 75.335582 -333.704297)
			(xy 75.575118 -333.62395) (xy 75.81707 -333.551206) (xy 76.061198 -333.486136) (xy 76.307259 -333.428806)
			(xy 76.555007 -333.379272) (xy 76.804195 -333.337583) (xy 77.054575 -333.303782) (xy 77.305897 -333.277901)
			(xy 77.557911 -333.259968) (xy 77.810365 -333.249999) (xy 78.063009 -333.248005) (xy 78.315589 -333.253987)
			(xy 78.567855 -333.26794) (xy 78.819554 -333.28985) (xy 79.070437 -333.319694) (xy 79.320252 -333.357444)
			(xy 79.568751 -333.403061) (xy 79.815686 -333.4565) (xy 80.060811 -333.517708) (xy 80.303881 -333.586623)
			(xy 80.544655 -333.663178) (xy 80.782892 -333.747295) (xy 81.018355 -333.838892) (xy 81.250809 -333.937876)
			(xy 81.480023 -334.044148) (xy 81.705767 -334.157604) (xy 81.927817 -334.278129) (xy 82.145951 -334.405605)
			(xy 82.359953 -334.539903) (xy 82.569609 -334.680889) (xy 82.774709 -334.828424) (xy 82.975049 -334.98236)
			(xy 83.17043 -335.142544) (xy 83.360657 -335.308816) (xy 83.54554 -335.481011) (xy 83.724896 -335.658955)
			(xy 83.898544 -335.842474) (xy 84.066312 -336.031382) (xy 84.228033 -336.225493) (xy 84.383546 -336.424612)
			(xy 84.532695 -336.628541) (xy 84.675332 -336.837077) (xy 84.811315 -337.050012) (xy 84.940508 -337.267134)
			(xy 85.062783 -337.488226) (xy 85.178017 -337.713067) (xy 85.207756 -337.775905) (xy 89.380306 -337.775905)
			(xy 89.380306 -337.704583) (xy 89.388292 -337.633709) (xy 89.404162 -337.564174) (xy 89.427719 -337.496854)
			(xy 89.458664 -337.432595) (xy 89.49661 -337.372204) (xy 89.541079 -337.316442) (xy 89.591512 -337.266009)
			(xy 89.647274 -337.22154) (xy 89.707665 -337.183594) (xy 89.771924 -337.152649) (xy 89.839244 -337.129092)
			(xy 89.908779 -337.113222) (xy 89.979653 -337.105236) (xy 90.050975 -337.105236) (xy 90.121849 -337.113222)
			(xy 90.191384 -337.129092) (xy 90.258704 -337.152649) (xy 90.322963 -337.183594) (xy 90.383354 -337.22154)
			(xy 90.439116 -337.266009) (xy 90.489549 -337.316442) (xy 90.534018 -337.372204) (xy 90.571964 -337.432595)
			(xy 90.602909 -337.496854) (xy 90.626466 -337.564174) (xy 90.642336 -337.633709) (xy 90.650322 -337.704583)
			(xy 90.650822 -337.740244) (xy 90.650322 -337.775905) (xy 92.371918 -337.775905) (xy 92.371918 -337.704583)
			(xy 92.379904 -337.633709) (xy 92.395774 -337.564174) (xy 92.419331 -337.496854) (xy 92.450276 -337.432595)
			(xy 92.488222 -337.372204) (xy 92.532691 -337.316442) (xy 92.583124 -337.266009) (xy 92.638886 -337.22154)
			(xy 92.699277 -337.183594) (xy 92.763536 -337.152649) (xy 92.830856 -337.129092) (xy 92.900391 -337.113222)
			(xy 92.971265 -337.105236) (xy 93.042587 -337.105236) (xy 93.113461 -337.113222) (xy 93.182996 -337.129092)
			(xy 93.250316 -337.152649) (xy 93.314575 -337.183594) (xy 93.374966 -337.22154) (xy 93.430728 -337.266009)
			(xy 93.481161 -337.316442) (xy 93.52563 -337.372204) (xy 93.563576 -337.432595) (xy 93.594521 -337.496854)
			(xy 93.618078 -337.564174) (xy 93.633948 -337.633709) (xy 93.641934 -337.704583) (xy 93.642434 -337.740244)
			(xy 93.641934 -337.775905) (xy 93.633948 -337.846779) (xy 93.618078 -337.916314) (xy 93.594521 -337.983634)
			(xy 93.563576 -338.047893) (xy 93.52563 -338.108284) (xy 93.481161 -338.164046) (xy 93.430728 -338.214479)
			(xy 93.374966 -338.258948) (xy 93.314575 -338.296894) (xy 93.250316 -338.327839) (xy 93.182996 -338.351396)
			(xy 93.113461 -338.367266) (xy 93.042587 -338.375252) (xy 92.971265 -338.375252) (xy 92.900391 -338.367266)
			(xy 92.830856 -338.351396) (xy 92.763536 -338.327839) (xy 92.699277 -338.296894) (xy 92.638886 -338.258948)
			(xy 92.583124 -338.214479) (xy 92.532691 -338.164046) (xy 92.488222 -338.108284) (xy 92.450276 -338.047893)
			(xy 92.419331 -337.983634) (xy 92.395774 -337.916314) (xy 92.379904 -337.846779) (xy 92.371918 -337.775905)
			(xy 90.650322 -337.775905) (xy 90.642336 -337.846779) (xy 90.626466 -337.916314) (xy 90.602909 -337.983634)
			(xy 90.571964 -338.047893) (xy 90.534018 -338.108284) (xy 90.489549 -338.164046) (xy 90.439116 -338.214479)
			(xy 90.383354 -338.258948) (xy 90.322963 -338.296894) (xy 90.258704 -338.327839) (xy 90.191384 -338.351396)
			(xy 90.121849 -338.367266) (xy 90.050975 -338.375252) (xy 89.979653 -338.375252) (xy 89.908779 -338.367266)
			(xy 89.839244 -338.351396) (xy 89.771924 -338.327839) (xy 89.707665 -338.296894) (xy 89.647274 -338.258948)
			(xy 89.591512 -338.214479) (xy 89.541079 -338.164046) (xy 89.49661 -338.108284) (xy 89.458664 -338.047893)
			(xy 89.427719 -337.983634) (xy 89.404162 -337.916314) (xy 89.388292 -337.846779) (xy 89.380306 -337.775905)
			(xy 85.207756 -337.775905) (xy 85.286096 -337.941435) (xy 85.386911 -338.1731) (xy 85.480363 -338.407833)
			(xy 85.566358 -338.645398) (xy 85.644811 -338.88556) (xy 85.715643 -339.128079) (xy 85.778784 -339.372714)
			(xy 85.834171 -339.619219) (xy 85.881748 -339.86735) (xy 85.921468 -340.11686) (xy 85.953292 -340.367499)
			(xy 85.960818 -340.446715) (xy 89.380306 -340.446715) (xy 89.380306 -340.375393) (xy 89.388292 -340.304519)
			(xy 89.404162 -340.234984) (xy 89.427719 -340.167664) (xy 89.458664 -340.103405) (xy 89.49661 -340.043014)
			(xy 89.541079 -339.987252) (xy 89.591512 -339.936819) (xy 89.647274 -339.89235) (xy 89.707665 -339.854404)
			(xy 89.771924 -339.823459) (xy 89.839244 -339.799902) (xy 89.908779 -339.784032) (xy 89.979653 -339.776046)
			(xy 90.050975 -339.776046) (xy 90.121849 -339.784032) (xy 90.191384 -339.799902) (xy 90.258704 -339.823459)
			(xy 90.322963 -339.854404) (xy 90.383354 -339.89235) (xy 90.439116 -339.936819) (xy 90.489549 -339.987252)
			(xy 90.534018 -340.043014) (xy 90.571964 -340.103405) (xy 90.602909 -340.167664) (xy 90.626466 -340.234984)
			(xy 90.642336 -340.304519) (xy 90.650322 -340.375393) (xy 90.650822 -340.411054) (xy 90.650322 -340.446715)
			(xy 92.371918 -340.446715) (xy 92.371918 -340.375393) (xy 92.379904 -340.304519) (xy 92.395774 -340.234984)
			(xy 92.419331 -340.167664) (xy 92.450276 -340.103405) (xy 92.488222 -340.043014) (xy 92.532691 -339.987252)
			(xy 92.583124 -339.936819) (xy 92.638886 -339.89235) (xy 92.699277 -339.854404) (xy 92.763536 -339.823459)
			(xy 92.830856 -339.799902) (xy 92.900391 -339.784032) (xy 92.971265 -339.776046) (xy 93.042587 -339.776046)
			(xy 93.113461 -339.784032) (xy 93.182996 -339.799902) (xy 93.250316 -339.823459) (xy 93.314575 -339.854404)
			(xy 93.374966 -339.89235) (xy 93.430728 -339.936819) (xy 93.481161 -339.987252) (xy 93.52563 -340.043014)
			(xy 93.563576 -340.103405) (xy 93.594521 -340.167664) (xy 93.618078 -340.234984) (xy 93.633948 -340.304519)
			(xy 93.641934 -340.375393) (xy 93.642434 -340.411054) (xy 93.641934 -340.446715) (xy 93.633948 -340.517589)
			(xy 93.618078 -340.587124) (xy 93.594521 -340.654444) (xy 93.563576 -340.718703) (xy 93.52563 -340.779094)
			(xy 93.481161 -340.834856) (xy 93.430728 -340.885289) (xy 93.374966 -340.929758) (xy 93.314575 -340.967704)
			(xy 93.250316 -340.998649) (xy 93.182996 -341.022206) (xy 93.113461 -341.038076) (xy 93.042587 -341.046062)
			(xy 92.971265 -341.046062) (xy 92.900391 -341.038076) (xy 92.830856 -341.022206) (xy 92.763536 -340.998649)
			(xy 92.699277 -340.967704) (xy 92.638886 -340.929758) (xy 92.583124 -340.885289) (xy 92.532691 -340.834856)
			(xy 92.488222 -340.779094) (xy 92.450276 -340.718703) (xy 92.419331 -340.654444) (xy 92.395774 -340.587124)
			(xy 92.379904 -340.517589) (xy 92.371918 -340.446715) (xy 90.650322 -340.446715) (xy 90.642336 -340.517589)
			(xy 90.626466 -340.587124) (xy 90.602909 -340.654444) (xy 90.571964 -340.718703) (xy 90.534018 -340.779094)
			(xy 90.489549 -340.834856) (xy 90.439116 -340.885289) (xy 90.383354 -340.929758) (xy 90.322963 -340.967704)
			(xy 90.258704 -340.998649) (xy 90.191384 -341.022206) (xy 90.121849 -341.038076) (xy 90.050975 -341.046062)
			(xy 89.979653 -341.046062) (xy 89.908779 -341.038076) (xy 89.839244 -341.022206) (xy 89.771924 -340.998649)
			(xy 89.707665 -340.967704) (xy 89.647274 -340.929758) (xy 89.591512 -340.885289) (xy 89.541079 -340.834856)
			(xy 89.49661 -340.779094) (xy 89.458664 -340.718703) (xy 89.427719 -340.654444) (xy 89.404162 -340.587124)
			(xy 89.388292 -340.517589) (xy 89.380306 -340.446715) (xy 85.960818 -340.446715) (xy 85.977188 -340.619017)
			(xy 85.993132 -340.871165) (xy 86.001107 -341.12369) (xy 86.001606 -341.250016) (xy 86.001107 -341.376342)
			(xy 85.993132 -341.628867) (xy 85.977188 -341.881015) (xy 85.953292 -342.132533) (xy 85.921468 -342.383172)
			(xy 85.881748 -342.632682) (xy 85.834171 -342.880813) (xy 85.781555 -343.114985) (xy 89.380306 -343.114985)
			(xy 89.380306 -343.043663) (xy 89.388292 -342.972789) (xy 89.404162 -342.903254) (xy 89.427719 -342.835934)
			(xy 89.458664 -342.771675) (xy 89.49661 -342.711284) (xy 89.541079 -342.655522) (xy 89.591512 -342.605089)
			(xy 89.647274 -342.56062) (xy 89.707665 -342.522674) (xy 89.771924 -342.491729) (xy 89.839244 -342.468172)
			(xy 89.908779 -342.452302) (xy 89.979653 -342.444316) (xy 90.050975 -342.444316) (xy 90.121849 -342.452302)
			(xy 90.191384 -342.468172) (xy 90.258704 -342.491729) (xy 90.322963 -342.522674) (xy 90.383354 -342.56062)
			(xy 90.439116 -342.605089) (xy 90.489549 -342.655522) (xy 90.534018 -342.711284) (xy 90.571964 -342.771675)
			(xy 90.602909 -342.835934) (xy 90.626466 -342.903254) (xy 90.642336 -342.972789) (xy 90.650322 -343.043663)
			(xy 90.650822 -343.079324) (xy 90.650322 -343.114985) (xy 92.371918 -343.114985) (xy 92.371918 -343.043663)
			(xy 92.379904 -342.972789) (xy 92.395774 -342.903254) (xy 92.419331 -342.835934) (xy 92.450276 -342.771675)
			(xy 92.488222 -342.711284) (xy 92.532691 -342.655522) (xy 92.583124 -342.605089) (xy 92.638886 -342.56062)
			(xy 92.699277 -342.522674) (xy 92.763536 -342.491729) (xy 92.830856 -342.468172) (xy 92.900391 -342.452302)
			(xy 92.971265 -342.444316) (xy 93.042587 -342.444316) (xy 93.113461 -342.452302) (xy 93.182996 -342.468172)
			(xy 93.250316 -342.491729) (xy 93.314575 -342.522674) (xy 93.374966 -342.56062) (xy 93.430728 -342.605089)
			(xy 93.481161 -342.655522) (xy 93.52563 -342.711284) (xy 93.563576 -342.771675) (xy 93.594521 -342.835934)
			(xy 93.618078 -342.903254) (xy 93.633948 -342.972789) (xy 93.641934 -343.043663) (xy 93.642434 -343.079324)
			(xy 93.641934 -343.114985) (xy 93.633948 -343.185859) (xy 93.618078 -343.255394) (xy 93.594521 -343.322714)
			(xy 93.563576 -343.386973) (xy 93.52563 -343.447364) (xy 93.481161 -343.503126) (xy 93.430728 -343.553559)
			(xy 93.374966 -343.598028) (xy 93.314575 -343.635974) (xy 93.250316 -343.666919) (xy 93.182996 -343.690476)
			(xy 93.113461 -343.706346) (xy 93.042587 -343.714332) (xy 92.971265 -343.714332) (xy 92.900391 -343.706346)
			(xy 92.830856 -343.690476) (xy 92.763536 -343.666919) (xy 92.699277 -343.635974) (xy 92.638886 -343.598028)
			(xy 92.583124 -343.553559) (xy 92.532691 -343.503126) (xy 92.488222 -343.447364) (xy 92.450276 -343.386973)
			(xy 92.419331 -343.322714) (xy 92.395774 -343.255394) (xy 92.379904 -343.185859) (xy 92.371918 -343.114985)
			(xy 90.650322 -343.114985) (xy 90.642336 -343.185859) (xy 90.626466 -343.255394) (xy 90.602909 -343.322714)
			(xy 90.571964 -343.386973) (xy 90.534018 -343.447364) (xy 90.489549 -343.503126) (xy 90.439116 -343.553559)
			(xy 90.383354 -343.598028) (xy 90.322963 -343.635974) (xy 90.258704 -343.666919) (xy 90.191384 -343.690476)
			(xy 90.121849 -343.706346) (xy 90.050975 -343.714332) (xy 89.979653 -343.714332) (xy 89.908779 -343.706346)
			(xy 89.839244 -343.690476) (xy 89.771924 -343.666919) (xy 89.707665 -343.635974) (xy 89.647274 -343.598028)
			(xy 89.591512 -343.553559) (xy 89.541079 -343.503126) (xy 89.49661 -343.447364) (xy 89.458664 -343.386973)
			(xy 89.427719 -343.322714) (xy 89.404162 -343.255394) (xy 89.388292 -343.185859) (xy 89.380306 -343.114985)
			(xy 85.781555 -343.114985) (xy 85.778784 -343.127318) (xy 85.715643 -343.371953) (xy 85.644811 -343.614472)
			(xy 85.566358 -343.854634) (xy 85.480363 -344.092199) (xy 85.386911 -344.326932) (xy 85.286096 -344.558597)
			(xy 85.178017 -344.786965) (xy 85.062783 -345.011806) (xy 84.940508 -345.232898) (xy 84.811315 -345.45002)
			(xy 84.787965 -345.486583) (xy 89.380306 -345.486583) (xy 89.380306 -345.415261) (xy 89.388292 -345.344387)
			(xy 89.404162 -345.274852) (xy 89.427719 -345.207532) (xy 89.458664 -345.143273) (xy 89.49661 -345.082882)
			(xy 89.541079 -345.02712) (xy 89.591512 -344.976687) (xy 89.647274 -344.932218) (xy 89.707665 -344.894272)
			(xy 89.771924 -344.863327) (xy 89.839244 -344.83977) (xy 89.908779 -344.8239) (xy 89.979653 -344.815914)
			(xy 90.050975 -344.815914) (xy 90.121849 -344.8239) (xy 90.191384 -344.83977) (xy 90.258704 -344.863327)
			(xy 90.322963 -344.894272) (xy 90.383354 -344.932218) (xy 90.439116 -344.976687) (xy 90.489549 -345.02712)
			(xy 90.534018 -345.082882) (xy 90.571964 -345.143273) (xy 90.602909 -345.207532) (xy 90.626466 -345.274852)
			(xy 90.642336 -345.344387) (xy 90.650322 -345.415261) (xy 90.650822 -345.450922) (xy 90.650322 -345.486583)
			(xy 92.371918 -345.486583) (xy 92.371918 -345.415261) (xy 92.379904 -345.344387) (xy 92.395774 -345.274852)
			(xy 92.419331 -345.207532) (xy 92.450276 -345.143273) (xy 92.488222 -345.082882) (xy 92.532691 -345.02712)
			(xy 92.583124 -344.976687) (xy 92.638886 -344.932218) (xy 92.699277 -344.894272) (xy 92.763536 -344.863327)
			(xy 92.830856 -344.83977) (xy 92.900391 -344.8239) (xy 92.971265 -344.815914) (xy 93.042587 -344.815914)
			(xy 93.113461 -344.8239) (xy 93.182996 -344.83977) (xy 93.250316 -344.863327) (xy 93.314575 -344.894272)
			(xy 93.374966 -344.932218) (xy 93.430728 -344.976687) (xy 93.481161 -345.02712) (xy 93.52563 -345.082882)
			(xy 93.563576 -345.143273) (xy 93.594521 -345.207532) (xy 93.618078 -345.274852) (xy 93.633948 -345.344387)
			(xy 93.641934 -345.415261) (xy 93.642434 -345.450922) (xy 93.641934 -345.486583) (xy 93.633948 -345.557457)
			(xy 93.618078 -345.626992) (xy 93.594521 -345.694312) (xy 93.563576 -345.758571) (xy 93.52563 -345.818962)
			(xy 93.481161 -345.874724) (xy 93.430728 -345.925157) (xy 93.374966 -345.969626) (xy 93.314575 -346.007572)
			(xy 93.250316 -346.038517) (xy 93.182996 -346.062074) (xy 93.113461 -346.077944) (xy 93.042587 -346.08593)
			(xy 92.971265 -346.08593) (xy 92.900391 -346.077944) (xy 92.830856 -346.062074) (xy 92.763536 -346.038517)
			(xy 92.699277 -346.007572) (xy 92.638886 -345.969626) (xy 92.583124 -345.925157) (xy 92.532691 -345.874724)
			(xy 92.488222 -345.818962) (xy 92.450276 -345.758571) (xy 92.419331 -345.694312) (xy 92.395774 -345.626992)
			(xy 92.379904 -345.557457) (xy 92.371918 -345.486583) (xy 90.650322 -345.486583) (xy 90.642336 -345.557457)
			(xy 90.626466 -345.626992) (xy 90.602909 -345.694312) (xy 90.571964 -345.758571) (xy 90.534018 -345.818962)
			(xy 90.489549 -345.874724) (xy 90.439116 -345.925157) (xy 90.383354 -345.969626) (xy 90.322963 -346.007572)
			(xy 90.258704 -346.038517) (xy 90.191384 -346.062074) (xy 90.121849 -346.077944) (xy 90.050975 -346.08593)
			(xy 89.979653 -346.08593) (xy 89.908779 -346.077944) (xy 89.839244 -346.062074) (xy 89.771924 -346.038517)
			(xy 89.707665 -346.007572) (xy 89.647274 -345.969626) (xy 89.591512 -345.925157) (xy 89.541079 -345.874724)
			(xy 89.49661 -345.818962) (xy 89.458664 -345.758571) (xy 89.427719 -345.694312) (xy 89.404162 -345.626992)
			(xy 89.388292 -345.557457) (xy 89.380306 -345.486583) (xy 84.787965 -345.486583) (xy 84.675332 -345.662955)
			(xy 84.532695 -345.871491) (xy 84.383546 -346.07542) (xy 84.228033 -346.274539) (xy 84.066312 -346.46865)
			(xy 83.898544 -346.657558) (xy 83.724896 -346.841077) (xy 83.54554 -347.019021) (xy 83.360657 -347.191216)
			(xy 83.17043 -347.357488) (xy 83.058206 -347.449495) (xy 89.380306 -347.449495) (xy 89.380306 -347.378173)
			(xy 89.388292 -347.307299) (xy 89.404162 -347.237764) (xy 89.427719 -347.170444) (xy 89.458664 -347.106185)
			(xy 89.49661 -347.045794) (xy 89.541079 -346.990032) (xy 89.591512 -346.939599) (xy 89.647274 -346.89513)
			(xy 89.707665 -346.857184) (xy 89.771924 -346.826239) (xy 89.839244 -346.802682) (xy 89.908779 -346.786812)
			(xy 89.979653 -346.778826) (xy 90.050975 -346.778826) (xy 90.121849 -346.786812) (xy 90.191384 -346.802682)
			(xy 90.258704 -346.826239) (xy 90.322963 -346.857184) (xy 90.383354 -346.89513) (xy 90.439116 -346.939599)
			(xy 90.489549 -346.990032) (xy 90.534018 -347.045794) (xy 90.571964 -347.106185) (xy 90.602909 -347.170444)
			(xy 90.626466 -347.237764) (xy 90.642336 -347.307299) (xy 90.650322 -347.378173) (xy 90.650822 -347.413834)
			(xy 90.650322 -347.449495) (xy 92.371918 -347.449495) (xy 92.371918 -347.378173) (xy 92.379904 -347.307299)
			(xy 92.395774 -347.237764) (xy 92.419331 -347.170444) (xy 92.450276 -347.106185) (xy 92.488222 -347.045794)
			(xy 92.532691 -346.990032) (xy 92.583124 -346.939599) (xy 92.638886 -346.89513) (xy 92.699277 -346.857184)
			(xy 92.763536 -346.826239) (xy 92.830856 -346.802682) (xy 92.900391 -346.786812) (xy 92.971265 -346.778826)
			(xy 93.042587 -346.778826) (xy 93.113461 -346.786812) (xy 93.182996 -346.802682) (xy 93.250316 -346.826239)
			(xy 93.314575 -346.857184) (xy 93.374966 -346.89513) (xy 93.430728 -346.939599) (xy 93.481161 -346.990032)
			(xy 93.52563 -347.045794) (xy 93.563576 -347.106185) (xy 93.594521 -347.170444) (xy 93.618078 -347.237764)
			(xy 93.633948 -347.307299) (xy 93.641934 -347.378173) (xy 93.642434 -347.413834) (xy 93.641934 -347.449495)
			(xy 93.633948 -347.520369) (xy 93.618078 -347.589904) (xy 93.594521 -347.657224) (xy 93.563576 -347.721483)
			(xy 93.52563 -347.781874) (xy 93.481161 -347.837636) (xy 93.430728 -347.888069) (xy 93.374966 -347.932538)
			(xy 93.314575 -347.970484) (xy 93.250316 -348.001429) (xy 93.182996 -348.024986) (xy 93.113461 -348.040856)
			(xy 93.042587 -348.048842) (xy 92.971265 -348.048842) (xy 92.900391 -348.040856) (xy 92.830856 -348.024986)
			(xy 92.763536 -348.001429) (xy 92.699277 -347.970484) (xy 92.638886 -347.932538) (xy 92.583124 -347.888069)
			(xy 92.532691 -347.837636) (xy 92.488222 -347.781874) (xy 92.450276 -347.721483) (xy 92.419331 -347.657224)
			(xy 92.395774 -347.589904) (xy 92.379904 -347.520369) (xy 92.371918 -347.449495) (xy 90.650322 -347.449495)
			(xy 90.642336 -347.520369) (xy 90.626466 -347.589904) (xy 90.602909 -347.657224) (xy 90.571964 -347.721483)
			(xy 90.534018 -347.781874) (xy 90.489549 -347.837636) (xy 90.439116 -347.888069) (xy 90.383354 -347.932538)
			(xy 90.322963 -347.970484) (xy 90.258704 -348.001429) (xy 90.191384 -348.024986) (xy 90.121849 -348.040856)
			(xy 90.050975 -348.048842) (xy 89.979653 -348.048842) (xy 89.908779 -348.040856) (xy 89.839244 -348.024986)
			(xy 89.771924 -348.001429) (xy 89.707665 -347.970484) (xy 89.647274 -347.932538) (xy 89.591512 -347.888069)
			(xy 89.541079 -347.837636) (xy 89.49661 -347.781874) (xy 89.458664 -347.721483) (xy 89.427719 -347.657224)
			(xy 89.404162 -347.589904) (xy 89.388292 -347.520369) (xy 89.380306 -347.449495) (xy 83.058206 -347.449495)
			(xy 82.975049 -347.517672) (xy 82.774709 -347.671608) (xy 82.569609 -347.819143) (xy 82.359953 -347.960129)
			(xy 82.145951 -348.094427) (xy 81.927817 -348.221903) (xy 81.705767 -348.342428) (xy 81.480023 -348.455884)
			(xy 81.250809 -348.562156) (xy 81.018355 -348.66114) (xy 80.782892 -348.752737) (xy 80.544655 -348.836854)
			(xy 80.303881 -348.913409) (xy 80.060811 -348.982324) (xy 79.815686 -349.043532) (xy 79.568751 -349.096971)
			(xy 79.320252 -349.142588) (xy 79.070437 -349.180338) (xy 78.819554 -349.210182) (xy 78.567855 -349.232092)
			(xy 78.315589 -349.246045) (xy 78.063009 -349.252027) (xy 77.810365 -349.250033) (xy 77.557911 -349.240064)
			(xy 77.305897 -349.222131) (xy 77.054575 -349.19625) (xy 76.804195 -349.162449) (xy 76.555007 -349.12076)
			(xy 76.307259 -349.071226) (xy 76.061198 -349.013896) (xy 75.81707 -348.948826) (xy 75.575118 -348.876082)
			(xy 75.335582 -348.795735) (xy 75.098703 -348.707868) (xy 74.864715 -348.612566) (xy 74.633853 -348.509925)
			(xy 74.406346 -348.400047) (xy 74.182421 -348.283042) (xy 73.962301 -348.159026) (xy 73.746206 -348.028123)
			(xy 73.534351 -347.890463) (xy 73.326947 -347.746185) (xy 73.124201 -347.59543) (xy 72.926316 -347.438351)
			(xy 72.733488 -347.275102) (xy 72.54591 -347.105848) (xy 72.363768 -346.930757) (xy 72.187244 -346.750003)
			(xy 72.016514 -346.563766) (xy 71.851749 -346.372233) (xy 71.693113 -346.175593) (xy 71.540763 -345.974044)
			(xy 71.394851 -345.767786) (xy 71.255524 -345.557024) (xy 71.122919 -345.341969) (xy 70.99717 -345.122835)
			(xy 70.878401 -344.89984) (xy 70.76673 -344.673208) (xy 70.66227 -344.443162) (xy 70.565124 -344.209934)
			(xy 70.47539 -343.973756) (xy 70.393155 -343.734862) (xy 70.318504 -343.493492) (xy 70.251509 -343.249885)
			(xy 70.192238 -343.004284) (xy 70.140749 -342.756935) (xy 70.097095 -342.508084) (xy 70.061319 -342.257978)
			(xy 70.033455 -342.006868) (xy 70.013533 -341.755004) (xy 70.001572 -341.502636) (xy 69.997584 -341.250016)
			(xy 28.08351 -341.250016) (xy 28.08351 -349.593001) (xy 89.380306 -349.593001) (xy 89.380306 -349.521679)
			(xy 89.388292 -349.450805) (xy 89.404162 -349.38127) (xy 89.427719 -349.31395) (xy 89.458664 -349.249691)
			(xy 89.49661 -349.1893) (xy 89.541079 -349.133538) (xy 89.591512 -349.083105) (xy 89.647274 -349.038636)
			(xy 89.707665 -349.00069) (xy 89.771924 -348.969745) (xy 89.839244 -348.946188) (xy 89.908779 -348.930318)
			(xy 89.979653 -348.922332) (xy 90.050975 -348.922332) (xy 90.121849 -348.930318) (xy 90.191384 -348.946188)
			(xy 90.258704 -348.969745) (xy 90.322963 -349.00069) (xy 90.383354 -349.038636) (xy 90.439116 -349.083105)
			(xy 90.489549 -349.133538) (xy 90.534018 -349.1893) (xy 90.571964 -349.249691) (xy 90.602909 -349.31395)
			(xy 90.626466 -349.38127) (xy 90.642336 -349.450805) (xy 90.650322 -349.521679) (xy 90.650822 -349.55734)
			(xy 90.650322 -349.593001) (xy 92.371918 -349.593001) (xy 92.371918 -349.521679) (xy 92.379904 -349.450805)
			(xy 92.395774 -349.38127) (xy 92.419331 -349.31395) (xy 92.450276 -349.249691) (xy 92.488222 -349.1893)
			(xy 92.532691 -349.133538) (xy 92.583124 -349.083105) (xy 92.638886 -349.038636) (xy 92.699277 -349.00069)
			(xy 92.763536 -348.969745) (xy 92.830856 -348.946188) (xy 92.900391 -348.930318) (xy 92.971265 -348.922332)
			(xy 93.042587 -348.922332) (xy 93.113461 -348.930318) (xy 93.182996 -348.946188) (xy 93.250316 -348.969745)
			(xy 93.314575 -349.00069) (xy 93.374966 -349.038636) (xy 93.430728 -349.083105) (xy 93.481161 -349.133538)
			(xy 93.52563 -349.1893) (xy 93.563576 -349.249691) (xy 93.594521 -349.31395) (xy 93.618078 -349.38127)
			(xy 93.633948 -349.450805) (xy 93.641934 -349.521679) (xy 93.642434 -349.55734) (xy 93.641934 -349.593001)
			(xy 93.633948 -349.663875) (xy 93.618078 -349.73341) (xy 93.594521 -349.80073) (xy 93.563576 -349.864989)
			(xy 93.52563 -349.92538) (xy 93.481161 -349.981142) (xy 93.430728 -350.031575) (xy 93.374966 -350.076044)
			(xy 93.314575 -350.11399) (xy 93.250316 -350.144935) (xy 93.182996 -350.168492) (xy 93.113461 -350.184362)
			(xy 93.042587 -350.192348) (xy 92.971265 -350.192348) (xy 92.900391 -350.184362) (xy 92.830856 -350.168492)
			(xy 92.763536 -350.144935) (xy 92.699277 -350.11399) (xy 92.638886 -350.076044) (xy 92.583124 -350.031575)
			(xy 92.532691 -349.981142) (xy 92.488222 -349.92538) (xy 92.450276 -349.864989) (xy 92.419331 -349.80073)
			(xy 92.395774 -349.73341) (xy 92.379904 -349.663875) (xy 92.371918 -349.593001) (xy 90.650322 -349.593001)
			(xy 90.642336 -349.663875) (xy 90.626466 -349.73341) (xy 90.602909 -349.80073) (xy 90.571964 -349.864989)
			(xy 90.534018 -349.92538) (xy 90.489549 -349.981142) (xy 90.439116 -350.031575) (xy 90.383354 -350.076044)
			(xy 90.322963 -350.11399) (xy 90.258704 -350.144935) (xy 90.191384 -350.168492) (xy 90.121849 -350.184362)
			(xy 90.050975 -350.192348) (xy 89.979653 -350.192348) (xy 89.908779 -350.184362) (xy 89.839244 -350.168492)
			(xy 89.771924 -350.144935) (xy 89.707665 -350.11399) (xy 89.647274 -350.076044) (xy 89.591512 -350.031575)
			(xy 89.541079 -349.981142) (xy 89.49661 -349.92538) (xy 89.458664 -349.864989) (xy 89.427719 -349.80073)
			(xy 89.404162 -349.73341) (xy 89.388292 -349.663875) (xy 89.380306 -349.593001) (xy 28.08351 -349.593001)
			(xy 28.08351 -350.772671) (xy 47.573723 -350.772671) (xy 47.577027 -350.691171) (xy 47.588349 -350.610394)
			(xy 47.607577 -350.531126) (xy 47.634525 -350.454139) (xy 47.66893 -350.380184) (xy 47.710457 -350.30998)
			(xy 47.758702 -350.244211) (xy 47.813194 -350.183517) (xy 47.873404 -350.12849) (xy 47.938744 -350.079666)
			(xy 48.008578 -350.03752) (xy 48.082227 -350.002462) (xy 48.158972 -349.974835) (xy 48.238067 -349.954907)
			(xy 48.318741 -349.942871) (xy 48.400208 -349.938847) (xy 48.481675 -349.942871) (xy 48.562349 -349.954907)
			(xy 48.641444 -349.974835) (xy 48.718189 -350.002462) (xy 48.791838 -350.03752) (xy 48.861672 -350.079666)
			(xy 48.927012 -350.12849) (xy 48.987222 -350.183517) (xy 49.041714 -350.244211) (xy 49.089959 -350.30998)
			(xy 49.131486 -350.380184) (xy 49.165891 -350.454139) (xy 49.192839 -350.531126) (xy 49.212067 -350.610394)
			(xy 49.223389 -350.691171) (xy 49.226693 -350.772671) (xy 49.221948 -350.854099) (xy 49.2092 -350.934664)
			(xy 49.188573 -351.013579) (xy 49.160269 -351.090077) (xy 49.124561 -351.163413) (xy 49.0818 -351.232872)
			(xy 49.0324 -351.297778) (xy 49.004982 -351.327974) (xy 49.002188 -351.331276) (xy 48.974667 -351.359865)
			(xy 48.915017 -351.412207) (xy 48.850623 -351.458589) (xy 48.782078 -351.498583) (xy 48.710015 -351.53182)
			(xy 48.635096 -351.557994) (xy 48.558013 -351.576864) (xy 48.479476 -351.588256) (xy 48.400208 -351.592065)
			(xy 48.32094 -351.588256) (xy 48.242403 -351.576864) (xy 48.16532 -351.557994) (xy 48.090401 -351.53182)
			(xy 48.018338 -351.498583) (xy 47.949793 -351.458589) (xy 47.885399 -351.412207) (xy 47.825749 -351.359865)
			(xy 47.798228 -351.331276) (xy 47.795434 -351.327974) (xy 47.768016 -351.297778) (xy 47.718616 -351.232872)
			(xy 47.675855 -351.163413) (xy 47.640147 -351.090077) (xy 47.611843 -351.013579) (xy 47.591216 -350.934664)
			(xy 47.578468 -350.854099) (xy 47.573723 -350.772671) (xy 28.08351 -350.772671) (xy 28.08351 -352.845116)
			(xy 28.127452 -352.889058) (xy 28.127452 -353.908614) (xy 68.218812 -353.908614) (xy 68.218812 -352.965004)
			(xy 68.219298 -352.932459) (xy 68.227581 -352.867897) (xy 68.244039 -352.804922) (xy 68.268401 -352.744563)
			(xy 68.300269 -352.687808) (xy 68.339122 -352.635585) (xy 68.384324 -352.58875) (xy 68.435135 -352.548068)
			(xy 68.490724 -352.514205) (xy 68.55018 -352.487717) (xy 68.612532 -352.469035) (xy 68.676759 -352.458465)
			(xy 68.741809 -352.456181) (xy 68.806618 -352.462221) (xy 68.870127 -352.476484) (xy 68.931295 -352.498738)
			(xy 68.989121 -352.528619) (xy 69.04266 -352.565637) (xy 69.091035 -352.609187) (xy 69.112638 -352.633534)
			(xy 69.12854 -352.651184) (xy 69.165635 -352.680853) (xy 69.207598 -352.703108) (xy 69.252968 -352.717176)
			(xy 69.300161 -352.722564) (xy 69.347533 -352.719086) (xy 69.393434 -352.706863) (xy 69.436262 -352.68632)
			(xy 69.474525 -352.658174) (xy 69.491098 -352.641154) (xy 69.513103 -352.618275) (xy 69.561795 -352.577549)
			(xy 69.615179 -352.543201) (xy 69.672424 -352.515767) (xy 69.732639 -352.495674) (xy 69.794887 -352.483233)
			(xy 69.8582 -352.478639) (xy 69.921592 -352.481963) (xy 69.984077 -352.493154) (xy 70.044682 -352.512036)
			(xy 70.102466 -352.538317) (xy 70.156527 -352.571588) (xy 70.206026 -352.61133) (xy 70.22846 -352.633788)
			(xy 70.245368 -352.650444) (xy 70.284102 -352.67786) (xy 70.327256 -352.697601) (xy 70.373325 -352.70898)
			(xy 70.420707 -352.711601) (xy 70.467751 -352.705372) (xy 70.512818 -352.690512) (xy 70.55434 -352.667536)
			(xy 70.590869 -352.637246) (xy 70.606412 -352.61931) (xy 70.627485 -352.594705) (xy 70.674865 -352.550521)
			(xy 70.727472 -352.512711) (xy 70.784455 -352.481888) (xy 70.84489 -352.458551) (xy 70.9078 -352.443077)
			(xy 70.972166 -352.435718) (xy 71.036945 -352.436592) (xy 71.101088 -352.445685) (xy 71.163558 -352.462851)
			(xy 71.223342 -352.48781) (xy 71.279472 -352.520159) (xy 71.33104 -352.559375) (xy 71.37721 -352.604821)
			(xy 71.397622 -352.629978) (xy 71.412221 -352.647766) (xy 71.446673 -352.678267) (xy 71.486052 -352.702068)
			(xy 71.529072 -352.718392) (xy 71.574328 -352.726704) (xy 71.620341 -352.726734) (xy 71.665608 -352.718481)
			(xy 71.708649 -352.702214) (xy 71.748059 -352.678464) (xy 71.78255 -352.648008) (xy 71.797164 -352.630232)
			(xy 71.816991 -352.605771) (xy 71.861685 -352.561417) (xy 71.911514 -352.522923) (xy 71.965716 -352.490877)
			(xy 72.023461 -352.465771) (xy 72.083865 -352.447988) (xy 72.146002 -352.437802) (xy 72.208921 -352.435367)
			(xy 72.27166 -352.440721) (xy 72.333257 -352.453783) (xy 72.392769 -352.474352) (xy 72.449285 -352.502114)
			(xy 72.50194 -352.536643) (xy 72.549928 -352.57741) (xy 72.592514 -352.623792) (xy 72.629045 -352.675078)
			(xy 72.658962 -352.730483) (xy 72.681809 -352.789159) (xy 72.697233 -352.850207) (xy 72.705 -352.912693)
			(xy 72.705468 -352.944176) (xy 72.705468 -353.908868) (xy 72.704959 -353.941603) (xy 72.696521 -354.006529)
			(xy 72.67982 -354.069834) (xy 72.655131 -354.130472) (xy 72.622864 -354.18744) (xy 72.603614 -354.213922)
			(xy 72.578468 -354.247704) (xy 72.578468 -354.264976) (xy 72.562974 -354.264976) (xy 72.52716 -354.295202)
			(xy 72.501983 -354.316055) (xy 72.447251 -354.351806) (xy 72.388386 -354.380245) (xy 72.326361 -354.4009)
			(xy 72.262199 -354.413431) (xy 72.19696 -354.417631) (xy 72.131721 -354.413431) (xy 72.067559 -354.4009)
			(xy 72.005534 -354.380245) (xy 71.946669 -354.351806) (xy 71.891937 -354.316055) (xy 71.86676 -354.295202)
			(xy 71.830946 -354.264976) (xy 71.815452 -354.264976) (xy 71.815452 -354.247704) (xy 71.790306 -354.213922)
			(xy 71.767494 -354.182239) (xy 71.730756 -354.113357) (xy 71.717154 -354.076762) (xy 71.711533 -354.062094)
			(xy 71.69424 -354.035883) (xy 71.671066 -354.014694) (xy 71.643416 -353.99981) (xy 71.612967 -353.992136)
			(xy 71.581565 -353.992136) (xy 71.551116 -353.99981) (xy 71.523466 -354.014694) (xy 71.500292 -354.035883)
			(xy 71.482999 -354.062094) (xy 71.477378 -354.076762) (xy 71.463806 -354.11331) (xy 71.427065 -354.182071)
			(xy 71.404226 -354.213668) (xy 71.37908 -354.24745) (xy 71.37908 -354.264468) (xy 71.363586 -354.264468)
			(xy 71.327772 -354.294948) (xy 71.302595 -354.315801) (xy 71.247863 -354.351552) (xy 71.188998 -354.379991)
			(xy 71.126973 -354.400646) (xy 71.062811 -354.413177) (xy 70.997572 -354.417377) (xy 70.932333 -354.413177)
			(xy 70.868171 -354.400646) (xy 70.806146 -354.379991) (xy 70.747281 -354.351552) (xy 70.692549 -354.315801)
			(xy 70.667372 -354.294948) (xy 70.631558 -354.264468) (xy 70.616064 -354.264468) (xy 70.616064 -354.24745)
			(xy 70.590918 -354.213668) (xy 70.577659 -354.195621) (xy 70.554004 -354.157591) (xy 70.543674 -354.137722)
			(xy 70.536252 -354.124015) (xy 70.515881 -354.100433) (xy 70.490395 -354.082503) (xy 70.461318 -354.071297)
			(xy 70.43039 -354.067485) (xy 70.399462 -354.071297) (xy 70.370385 -354.082503) (xy 70.344899 -354.100433)
			(xy 70.324528 -354.124015) (xy 70.317106 -354.137722) (xy 70.30678 -354.157594) (xy 70.283125 -354.195623)
			(xy 70.269862 -354.213668) (xy 70.244716 -354.24745) (xy 70.244716 -354.264468) (xy 70.229222 -354.264468)
			(xy 70.193408 -354.294948) (xy 70.168231 -354.315801) (xy 70.113499 -354.351552) (xy 70.054634 -354.379991)
			(xy 69.992609 -354.400646) (xy 69.928447 -354.413177) (xy 69.863208 -354.417377) (xy 69.797969 -354.413177)
			(xy 69.733807 -354.400646) (xy 69.671782 -354.379991) (xy 69.612917 -354.351552) (xy 69.558185 -354.315801)
			(xy 69.533008 -354.294948) (xy 69.497194 -354.264468) (xy 69.4817 -354.264468) (xy 69.4817 -354.24745)
			(xy 69.456554 -354.213668) (xy 69.443116 -354.195332) (xy 69.419206 -354.156665) (xy 69.408802 -354.136452)
			(xy 69.4014 -354.122642) (xy 69.381008 -354.098865) (xy 69.355435 -354.080776) (xy 69.326224 -354.069467)
			(xy 69.295137 -354.06562) (xy 69.26405 -354.069467) (xy 69.234839 -354.080776) (xy 69.209266 -354.098865)
			(xy 69.188874 -354.122642) (xy 69.181472 -354.136452) (xy 69.171064 -354.156662) (xy 69.147151 -354.195327)
			(xy 69.13372 -354.213668) (xy 69.10832 -354.24745) (xy 69.10832 -354.264468) (xy 69.09308 -354.264468)
			(xy 69.057266 -354.294948) (xy 69.032089 -354.315801) (xy 68.977357 -354.351552) (xy 68.918492 -354.379991)
			(xy 68.856467 -354.400646) (xy 68.792305 -354.413177) (xy 68.727066 -354.417377) (xy 68.661827 -354.413177)
			(xy 68.597665 -354.400646) (xy 68.53564 -354.379991) (xy 68.476775 -354.351552) (xy 68.422043 -354.315801)
			(xy 68.396866 -354.294948) (xy 68.361052 -354.264468) (xy 68.345812 -354.264468) (xy 68.345812 -354.24745)
			(xy 68.320412 -354.213668) (xy 68.301196 -354.18717) (xy 68.268966 -354.1302) (xy 68.244324 -354.069561)
			(xy 68.227677 -354.006259) (xy 68.219303 -353.941342) (xy 68.218812 -353.908614) (xy 28.127452 -353.908614)
			(xy 28.127452 -354.132896) (xy 28.447746 -354.45319) (xy 31.82747 -354.45319) (xy 32.834072 -355.459792)
			(xy 39.906954 -355.459792) (xy 39.911025 -355.40417) (xy 39.923151 -355.349733) (xy 39.943074 -355.297642)
			(xy 39.97037 -355.249007) (xy 40.004456 -355.204864) (xy 40.044605 -355.166155) (xy 40.089963 -355.133704)
			(xy 40.139563 -355.108203) (xy 40.192347 -355.090196) (xy 40.24719 -355.080066) (xy 40.302924 -355.078029)
			(xy 40.358361 -355.084129) (xy 40.412318 -355.098235) (xy 40.463647 -355.120047) (xy 40.511253 -355.149101)
			(xy 40.554121 -355.184776) (xy 40.591338 -355.226313) (xy 40.622111 -355.272826) (xy 40.645783 -355.323323)
			(xy 40.661851 -355.37673) (xy 40.669971 -355.431906) (xy 40.67048 -355.459792) (xy 40.669971 -355.487678)
			(xy 40.661851 -355.542854) (xy 40.645783 -355.596261) (xy 40.622111 -355.646758) (xy 40.615068 -355.657404)
			(xy 41.28338 -355.657404) (xy 41.287451 -355.601782) (xy 41.299577 -355.547345) (xy 41.3195 -355.495254)
			(xy 41.346796 -355.446619) (xy 41.380882 -355.402476) (xy 41.421031 -355.363767) (xy 41.466389 -355.331316)
			(xy 41.515989 -355.305815) (xy 41.568773 -355.287808) (xy 41.623616 -355.277678) (xy 41.67935 -355.275641)
			(xy 41.734787 -355.281741) (xy 41.788744 -355.295847) (xy 41.840073 -355.317659) (xy 41.887679 -355.346713)
			(xy 41.921617 -355.374956) (xy 82.329526 -355.374956) (xy 82.333597 -355.319334) (xy 82.345723 -355.264897)
			(xy 82.365646 -355.212806) (xy 82.392942 -355.164171) (xy 82.427028 -355.120028) (xy 82.467177 -355.081319)
			(xy 82.512535 -355.048868) (xy 82.562135 -355.023367) (xy 82.614919 -355.00536) (xy 82.669762 -354.99523)
			(xy 82.725496 -354.993193) (xy 82.780933 -354.999293) (xy 82.83489 -355.013399) (xy 82.886219 -355.035211)
			(xy 82.933825 -355.064265) (xy 82.976693 -355.09994) (xy 83.01391 -355.141477) (xy 83.044683 -355.18799)
			(xy 83.068355 -355.238487) (xy 83.084423 -355.291894) (xy 83.092543 -355.34707) (xy 83.093052 -355.374956)
			(xy 83.092543 -355.402842) (xy 83.084423 -355.458018) (xy 83.068355 -355.511425) (xy 83.044683 -355.561922)
			(xy 83.01391 -355.608435) (xy 82.976693 -355.649972) (xy 82.933825 -355.685647) (xy 82.886219 -355.714701)
			(xy 82.83489 -355.736513) (xy 82.780933 -355.750619) (xy 82.725496 -355.756719) (xy 82.669762 -355.754682)
			(xy 82.614919 -355.744552) (xy 82.562135 -355.726545) (xy 82.512535 -355.701044) (xy 82.467177 -355.668593)
			(xy 82.427028 -355.629884) (xy 82.392942 -355.585741) (xy 82.365646 -355.537106) (xy 82.345723 -355.485015)
			(xy 82.333597 -355.430578) (xy 82.329526 -355.374956) (xy 41.921617 -355.374956) (xy 41.930547 -355.382388)
			(xy 41.967764 -355.423925) (xy 41.998537 -355.470438) (xy 42.022209 -355.520935) (xy 42.038277 -355.574342)
			(xy 42.046397 -355.629518) (xy 42.046906 -355.657404) (xy 42.046397 -355.68529) (xy 42.038277 -355.740466)
			(xy 42.022209 -355.793873) (xy 41.998537 -355.84437) (xy 41.967764 -355.890883) (xy 41.930547 -355.93242)
			(xy 41.925889 -355.936296) (xy 42.887136 -355.936296) (xy 42.891207 -355.880674) (xy 42.903333 -355.826237)
			(xy 42.923256 -355.774146) (xy 42.950552 -355.725511) (xy 42.984638 -355.681368) (xy 43.024787 -355.642659)
			(xy 43.070145 -355.610208) (xy 43.119745 -355.584707) (xy 43.172529 -355.5667) (xy 43.227372 -355.55657)
			(xy 43.283106 -355.554533) (xy 43.338543 -355.560633) (xy 43.3925 -355.574739) (xy 43.443829 -355.596551)
			(xy 43.491435 -355.625605) (xy 43.534303 -355.66128) (xy 43.57152 -355.702817) (xy 43.602293 -355.74933)
			(xy 43.625965 -355.799827) (xy 43.642033 -355.853234) (xy 43.650153 -355.90841) (xy 43.650662 -355.936296)
			(xy 43.650153 -355.964182) (xy 43.642033 -356.019358) (xy 43.625965 -356.072765) (xy 43.602293 -356.123262)
			(xy 43.57152 -356.169775) (xy 43.553816 -356.189534) (xy 44.343064 -356.189534) (xy 44.347135 -356.133912)
			(xy 44.359261 -356.079475) (xy 44.379184 -356.027384) (xy 44.40648 -355.978749) (xy 44.440566 -355.934606)
			(xy 44.480715 -355.895897) (xy 44.526073 -355.863446) (xy 44.575673 -355.837945) (xy 44.628457 -355.819938)
			(xy 44.6833 -355.809808) (xy 44.739034 -355.807771) (xy 44.794471 -355.813871) (xy 44.848428 -355.827977)
			(xy 44.899757 -355.849789) (xy 44.947363 -355.878843) (xy 44.990231 -355.914518) (xy 45.014751 -355.941884)
			(xy 80.746598 -355.941884) (xy 80.750669 -355.886262) (xy 80.762795 -355.831825) (xy 80.782718 -355.779734)
			(xy 80.810014 -355.731099) (xy 80.8441 -355.686956) (xy 80.884249 -355.648247) (xy 80.929607 -355.615796)
			(xy 80.979207 -355.590295) (xy 81.031991 -355.572288) (xy 81.086834 -355.562158) (xy 81.142568 -355.560121)
			(xy 81.198005 -355.566221) (xy 81.251962 -355.580327) (xy 81.303291 -355.602139) (xy 81.350897 -355.631193)
			(xy 81.393765 -355.666868) (xy 81.430982 -355.708405) (xy 81.461755 -355.754918) (xy 81.484865 -355.804216)
			(xy 84.618066 -355.804216) (xy 84.622137 -355.748594) (xy 84.634263 -355.694157) (xy 84.654186 -355.642066)
			(xy 84.681482 -355.593431) (xy 84.715568 -355.549288) (xy 84.755717 -355.510579) (xy 84.801075 -355.478128)
			(xy 84.850675 -355.452627) (xy 84.903459 -355.43462) (xy 84.958302 -355.42449) (xy 85.014036 -355.422453)
			(xy 85.069473 -355.428553) (xy 85.12343 -355.442659) (xy 85.174759 -355.464471) (xy 85.222365 -355.493525)
			(xy 85.265233 -355.5292) (xy 85.30245 -355.570737) (xy 85.333223 -355.61725) (xy 85.356895 -355.667747)
			(xy 85.372963 -355.721154) (xy 85.381083 -355.77633) (xy 85.381592 -355.804216) (xy 85.381083 -355.832102)
			(xy 85.372963 -355.887278) (xy 85.356895 -355.940685) (xy 85.333223 -355.991182) (xy 85.311392 -356.02418)
			(xy 87.027002 -356.02418) (xy 87.031073 -355.968558) (xy 87.043199 -355.914121) (xy 87.063122 -355.86203)
			(xy 87.090418 -355.813395) (xy 87.124504 -355.769252) (xy 87.164653 -355.730543) (xy 87.210011 -355.698092)
			(xy 87.259611 -355.672591) (xy 87.312395 -355.654584) (xy 87.367238 -355.644454) (xy 87.422972 -355.642417)
			(xy 87.478409 -355.648517) (xy 87.532366 -355.662623) (xy 87.583695 -355.684435) (xy 87.631301 -355.713489)
			(xy 87.674169 -355.749164) (xy 87.711386 -355.790701) (xy 87.742159 -355.837214) (xy 87.765831 -355.887711)
			(xy 87.781899 -355.941118) (xy 87.790019 -355.996294) (xy 87.790528 -356.02418) (xy 87.790019 -356.052066)
			(xy 87.781899 -356.107242) (xy 87.765831 -356.160649) (xy 87.742159 -356.211146) (xy 87.711386 -356.257659)
			(xy 87.674169 -356.299196) (xy 87.631301 -356.334871) (xy 87.583695 -356.363925) (xy 87.532366 -356.385737)
			(xy 87.478409 -356.399843) (xy 87.422972 -356.405943) (xy 87.367238 -356.403906) (xy 87.312395 -356.393776)
			(xy 87.259611 -356.375769) (xy 87.210011 -356.350268) (xy 87.164653 -356.317817) (xy 87.124504 -356.279108)
			(xy 87.090418 -356.234965) (xy 87.063122 -356.18633) (xy 87.043199 -356.134239) (xy 87.031073 -356.079802)
			(xy 87.027002 -356.02418) (xy 85.311392 -356.02418) (xy 85.30245 -356.037695) (xy 85.265233 -356.079232)
			(xy 85.222365 -356.114907) (xy 85.174759 -356.143961) (xy 85.12343 -356.165773) (xy 85.069473 -356.179879)
			(xy 85.014036 -356.185979) (xy 84.958302 -356.183942) (xy 84.903459 -356.173812) (xy 84.850675 -356.155805)
			(xy 84.801075 -356.130304) (xy 84.755717 -356.097853) (xy 84.715568 -356.059144) (xy 84.681482 -356.015001)
			(xy 84.654186 -355.966366) (xy 84.634263 -355.914275) (xy 84.622137 -355.859838) (xy 84.618066 -355.804216)
			(xy 81.484865 -355.804216) (xy 81.485427 -355.805415) (xy 81.501495 -355.858822) (xy 81.509615 -355.913998)
			(xy 81.510124 -355.941884) (xy 81.509615 -355.96977) (xy 81.501495 -356.024946) (xy 81.485427 -356.078353)
			(xy 81.461755 -356.12885) (xy 81.430982 -356.175363) (xy 81.393765 -356.2169) (xy 81.350897 -356.252575)
			(xy 81.303291 -356.281629) (xy 81.251962 -356.303441) (xy 81.198005 -356.317547) (xy 81.142568 -356.323647)
			(xy 81.086834 -356.32161) (xy 81.031991 -356.31148) (xy 80.979207 -356.293473) (xy 80.929607 -356.267972)
			(xy 80.884249 -356.235521) (xy 80.8441 -356.196812) (xy 80.810014 -356.152669) (xy 80.782718 -356.104034)
			(xy 80.762795 -356.051943) (xy 80.750669 -355.997506) (xy 80.746598 -355.941884) (xy 45.014751 -355.941884)
			(xy 45.027448 -355.956055) (xy 45.058221 -356.002568) (xy 45.081893 -356.053065) (xy 45.097961 -356.106472)
			(xy 45.106081 -356.161648) (xy 45.10659 -356.189534) (xy 45.106081 -356.21742) (xy 45.097961 -356.272596)
			(xy 45.081893 -356.326003) (xy 45.058221 -356.3765) (xy 45.027448 -356.423013) (xy 44.990231 -356.46455)
			(xy 44.984353 -356.469442) (xy 79.420464 -356.469442) (xy 79.424535 -356.41382) (xy 79.436661 -356.359383)
			(xy 79.456584 -356.307292) (xy 79.48388 -356.258657) (xy 79.517966 -356.214514) (xy 79.558115 -356.175805)
			(xy 79.603473 -356.143354) (xy 79.653073 -356.117853) (xy 79.705857 -356.099846) (xy 79.7607 -356.089716)
			(xy 79.816434 -356.087679) (xy 79.871871 -356.093779) (xy 79.925828 -356.107885) (xy 79.977157 -356.129697)
			(xy 80.024763 -356.158751) (xy 80.067631 -356.194426) (xy 80.104848 -356.235963) (xy 80.135621 -356.282476)
			(xy 80.159293 -356.332973) (xy 80.175361 -356.38638) (xy 80.180856 -356.423722) (xy 88.693242 -356.423722)
			(xy 88.697313 -356.3681) (xy 88.709439 -356.313663) (xy 88.729362 -356.261572) (xy 88.756658 -356.212937)
			(xy 88.790744 -356.168794) (xy 88.830893 -356.130085) (xy 88.876251 -356.097634) (xy 88.925851 -356.072133)
			(xy 88.978635 -356.054126) (xy 89.033478 -356.043996) (xy 89.089212 -356.041959) (xy 89.144649 -356.048059)
			(xy 89.198606 -356.062165) (xy 89.249935 -356.083977) (xy 89.297541 -356.113031) (xy 89.340409 -356.148706)
			(xy 89.377626 -356.190243) (xy 89.408399 -356.236756) (xy 89.432071 -356.287253) (xy 89.448139 -356.34066)
			(xy 89.456259 -356.395836) (xy 89.456768 -356.423722) (xy 89.456259 -356.451608) (xy 89.448139 -356.506784)
			(xy 89.432071 -356.560191) (xy 89.408399 -356.610688) (xy 89.377626 -356.657201) (xy 89.340409 -356.698738)
			(xy 89.297541 -356.734413) (xy 89.249935 -356.763467) (xy 89.198606 -356.785279) (xy 89.144649 -356.799385)
			(xy 89.089212 -356.805485) (xy 89.033478 -356.803448) (xy 88.978635 -356.793318) (xy 88.925851 -356.775311)
			(xy 88.876251 -356.74981) (xy 88.830893 -356.717359) (xy 88.790744 -356.67865) (xy 88.756658 -356.634507)
			(xy 88.729362 -356.585872) (xy 88.709439 -356.533781) (xy 88.697313 -356.479344) (xy 88.693242 -356.423722)
			(xy 80.180856 -356.423722) (xy 80.183481 -356.441556) (xy 80.18399 -356.469442) (xy 80.183481 -356.497328)
			(xy 80.175361 -356.552504) (xy 80.159293 -356.605911) (xy 80.135621 -356.656408) (xy 80.104848 -356.702921)
			(xy 80.067631 -356.744458) (xy 80.024763 -356.780133) (xy 79.977157 -356.809187) (xy 79.925828 -356.830999)
			(xy 79.871871 -356.845105) (xy 79.816434 -356.851205) (xy 79.7607 -356.849168) (xy 79.705857 -356.839038)
			(xy 79.653073 -356.821031) (xy 79.603473 -356.79553) (xy 79.558115 -356.763079) (xy 79.517966 -356.72437)
			(xy 79.48388 -356.680227) (xy 79.456584 -356.631592) (xy 79.436661 -356.579501) (xy 79.424535 -356.525064)
			(xy 79.420464 -356.469442) (xy 44.984353 -356.469442) (xy 44.947363 -356.500225) (xy 44.899757 -356.529279)
			(xy 44.848428 -356.551091) (xy 44.794471 -356.565197) (xy 44.739034 -356.571297) (xy 44.6833 -356.56926)
			(xy 44.628457 -356.55913) (xy 44.575673 -356.541123) (xy 44.526073 -356.515622) (xy 44.480715 -356.483171)
			(xy 44.440566 -356.444462) (xy 44.40648 -356.400319) (xy 44.379184 -356.351684) (xy 44.359261 -356.299593)
			(xy 44.347135 -356.245156) (xy 44.343064 -356.189534) (xy 43.553816 -356.189534) (xy 43.534303 -356.211312)
			(xy 43.491435 -356.246987) (xy 43.443829 -356.276041) (xy 43.3925 -356.297853) (xy 43.338543 -356.311959)
			(xy 43.283106 -356.318059) (xy 43.227372 -356.316022) (xy 43.172529 -356.305892) (xy 43.119745 -356.287885)
			(xy 43.070145 -356.262384) (xy 43.024787 -356.229933) (xy 42.984638 -356.191224) (xy 42.950552 -356.147081)
			(xy 42.923256 -356.098446) (xy 42.903333 -356.046355) (xy 42.891207 -355.991918) (xy 42.887136 -355.936296)
			(xy 41.925889 -355.936296) (xy 41.887679 -355.968095) (xy 41.840073 -355.997149) (xy 41.788744 -356.018961)
			(xy 41.734787 -356.033067) (xy 41.67935 -356.039167) (xy 41.623616 -356.03713) (xy 41.568773 -356.027)
			(xy 41.515989 -356.008993) (xy 41.466389 -355.983492) (xy 41.421031 -355.951041) (xy 41.380882 -355.912332)
			(xy 41.346796 -355.868189) (xy 41.3195 -355.819554) (xy 41.299577 -355.767463) (xy 41.287451 -355.713026)
			(xy 41.28338 -355.657404) (xy 40.615068 -355.657404) (xy 40.591338 -355.693271) (xy 40.554121 -355.734808)
			(xy 40.511253 -355.770483) (xy 40.463647 -355.799537) (xy 40.412318 -355.821349) (xy 40.358361 -355.835455)
			(xy 40.302924 -355.841555) (xy 40.24719 -355.839518) (xy 40.192347 -355.829388) (xy 40.139563 -355.811381)
			(xy 40.089963 -355.78588) (xy 40.044605 -355.753429) (xy 40.004456 -355.71472) (xy 39.97037 -355.670577)
			(xy 39.943074 -355.621942) (xy 39.923151 -355.569851) (xy 39.911025 -355.515414) (xy 39.906954 -355.459792)
			(xy 32.834072 -355.459792) (xy 34.1757 -356.80142) (xy 34.1757 -358.233488) (xy 34.599874 -358.233488)
			(xy 34.599874 -358.146588) (xy 34.607892 -358.060059) (xy 34.62386 -357.974639) (xy 34.647641 -357.891057)
			(xy 34.679033 -357.810025) (xy 34.717767 -357.732236) (xy 34.763514 -357.658352) (xy 34.815883 -357.589005)
			(xy 34.874427 -357.524785) (xy 34.938647 -357.466241) (xy 35.007994 -357.413872) (xy 35.081878 -357.368125)
			(xy 35.159667 -357.329391) (xy 35.240699 -357.297999) (xy 35.324281 -357.274218) (xy 35.409701 -357.25825)
			(xy 35.49623 -357.250232) (xy 35.58313 -357.250232) (xy 35.669659 -357.25825) (xy 35.755079 -357.274218)
			(xy 35.838661 -357.297999) (xy 35.919693 -357.329391) (xy 35.997482 -357.368125) (xy 36.071366 -357.413872)
			(xy 36.140713 -357.466241) (xy 36.204933 -357.524785) (xy 36.263477 -357.589005) (xy 36.315846 -357.658352)
			(xy 36.361593 -357.732236) (xy 36.400327 -357.810025) (xy 36.431719 -357.891057) (xy 36.4555 -357.974639)
			(xy 36.471468 -358.060059) (xy 36.479486 -358.146588) (xy 36.479988 -358.190038) (xy 36.479486 -358.233488)
			(xy 36.471468 -358.320017) (xy 36.4555 -358.405437) (xy 36.431719 -358.489019) (xy 36.400327 -358.570051)
			(xy 36.361593 -358.64784) (xy 36.315846 -358.721724) (xy 36.263477 -358.791071) (xy 36.204933 -358.855291)
			(xy 36.140713 -358.913835) (xy 36.071366 -358.966204) (xy 35.997482 -359.011951) (xy 35.919693 -359.050685)
			(xy 35.838661 -359.082077) (xy 35.755079 -359.105858) (xy 35.669659 -359.121826) (xy 35.58313 -359.129844)
			(xy 35.49623 -359.129844) (xy 35.409701 -359.121826) (xy 35.324281 -359.105858) (xy 35.240699 -359.082077)
			(xy 35.159667 -359.050685) (xy 35.081878 -359.011951) (xy 35.007994 -358.966204) (xy 34.938647 -358.913835)
			(xy 34.874427 -358.855291) (xy 34.815883 -358.791071) (xy 34.763514 -358.721724) (xy 34.717767 -358.64784)
			(xy 34.679033 -358.570051) (xy 34.647641 -358.489019) (xy 34.62386 -358.405437) (xy 34.607892 -358.320017)
			(xy 34.599874 -358.233488) (xy 34.1757 -358.233488) (xy 34.1757 -360.773488) (xy 34.599874 -360.773488)
			(xy 34.599874 -360.686588) (xy 34.607892 -360.600059) (xy 34.62386 -360.514639) (xy 34.647641 -360.431057)
			(xy 34.679033 -360.350025) (xy 34.717767 -360.272236) (xy 34.763514 -360.198352) (xy 34.815883 -360.129005)
			(xy 34.874427 -360.064785) (xy 34.938647 -360.006241) (xy 35.007994 -359.953872) (xy 35.081878 -359.908125)
			(xy 35.159667 -359.869391) (xy 35.240699 -359.837999) (xy 35.324281 -359.814218) (xy 35.409701 -359.79825)
			(xy 35.49623 -359.790232) (xy 35.58313 -359.790232) (xy 35.669659 -359.79825) (xy 35.755079 -359.814218)
			(xy 35.838661 -359.837999) (xy 35.919693 -359.869391) (xy 35.997482 -359.908125) (xy 36.071366 -359.953872)
			(xy 36.140713 -360.006241) (xy 36.204933 -360.064785) (xy 36.263477 -360.129005) (xy 36.315846 -360.198352)
			(xy 36.361593 -360.272236) (xy 36.400327 -360.350025) (xy 36.431719 -360.431057) (xy 36.4555 -360.514639)
			(xy 36.471468 -360.600059) (xy 36.479486 -360.686588) (xy 36.479988 -360.730038) (xy 36.479486 -360.773488)
			(xy 36.471468 -360.860017) (xy 36.4555 -360.945437) (xy 36.431719 -361.029019) (xy 36.400327 -361.110051)
			(xy 36.361593 -361.18784) (xy 36.315846 -361.261724) (xy 36.263477 -361.331071) (xy 36.204933 -361.395291)
			(xy 36.140713 -361.453835) (xy 36.071366 -361.506204) (xy 35.997482 -361.551951) (xy 35.919693 -361.590685)
			(xy 35.838661 -361.622077) (xy 35.755079 -361.645858) (xy 35.669659 -361.661826) (xy 35.58313 -361.669844)
			(xy 35.49623 -361.669844) (xy 35.409701 -361.661826) (xy 35.324281 -361.645858) (xy 35.240699 -361.622077)
			(xy 35.159667 -361.590685) (xy 35.081878 -361.551951) (xy 35.007994 -361.506204) (xy 34.938647 -361.453835)
			(xy 34.874427 -361.395291) (xy 34.815883 -361.331071) (xy 34.763514 -361.261724) (xy 34.717767 -361.18784)
			(xy 34.679033 -361.110051) (xy 34.647641 -361.029019) (xy 34.62386 -360.945437) (xy 34.607892 -360.860017)
			(xy 34.599874 -360.773488) (xy 34.1757 -360.773488) (xy 34.1757 -363.313488) (xy 34.599874 -363.313488)
			(xy 34.599874 -363.226588) (xy 34.607892 -363.140059) (xy 34.62386 -363.054639) (xy 34.647641 -362.971057)
			(xy 34.679033 -362.890025) (xy 34.717767 -362.812236) (xy 34.763514 -362.738352) (xy 34.815883 -362.669005)
			(xy 34.874427 -362.604785) (xy 34.938647 -362.546241) (xy 35.007994 -362.493872) (xy 35.081878 -362.448125)
			(xy 35.159667 -362.409391) (xy 35.240699 -362.377999) (xy 35.324281 -362.354218) (xy 35.409701 -362.33825)
			(xy 35.49623 -362.330232) (xy 35.58313 -362.330232) (xy 35.669659 -362.33825) (xy 35.755079 -362.354218)
			(xy 35.838661 -362.377999) (xy 35.919693 -362.409391) (xy 35.997482 -362.448125) (xy 36.071366 -362.493872)
			(xy 36.092815 -362.51007) (xy 39.818063 -362.51007) (xy 39.82207 -362.394046) (xy 39.834072 -362.278574)
			(xy 39.854012 -362.164206) (xy 39.881795 -362.051486) (xy 39.917289 -361.940952) (xy 39.960324 -361.833129)
			(xy 40.010695 -361.728532) (xy 40.068162 -361.62766) (xy 40.132452 -361.530993) (xy 40.203257 -361.438992)
			(xy 40.280241 -361.352095) (xy 40.363037 -361.270716) (xy 40.45125 -361.195243) (xy 40.54446 -361.126036)
			(xy 40.642223 -361.063424) (xy 40.744072 -361.007707) (xy 40.849522 -360.959149) (xy 40.958071 -360.917981)
			(xy 41.069202 -360.884401) (xy 41.182385 -360.858568) (xy 41.29708 -360.840605) (xy 41.412742 -360.830597)
			(xy 41.528818 -360.828594) (xy 41.644756 -360.834603) (xy 41.760003 -360.848596) (xy 41.874009 -360.870507)
			(xy 41.986233 -360.900232) (xy 42.096139 -360.937628) (xy 42.203202 -360.982517) (xy 42.306914 -361.034686)
			(xy 42.406779 -361.093886) (xy 42.502322 -361.159835) (xy 42.502604 -361.16006) (xy 43.327577 -361.16006)
			(xy 43.331612 -361.084356) (xy 43.343671 -361.009511) (xy 43.363617 -360.93637) (xy 43.391224 -360.865765)
			(xy 43.42618 -360.798494) (xy 43.468088 -360.735319) (xy 43.516474 -360.676957) (xy 43.57079 -360.624069)
			(xy 43.630419 -360.577254) (xy 43.694687 -360.537042) (xy 43.762864 -360.50389) (xy 43.83418 -360.478172)
			(xy 43.907825 -360.46018) (xy 43.982965 -360.450118) (xy 44.058749 -360.448099) (xy 44.134319 -360.454148)
			(xy 44.208817 -360.468195) (xy 44.2814 -360.490081) (xy 44.351246 -360.519558) (xy 44.417563 -360.556293)
			(xy 44.479599 -360.599868) (xy 44.536652 -360.64979) (xy 44.588076 -360.705494) (xy 44.633287 -360.766349)
			(xy 44.671774 -360.831664) (xy 44.7031 -360.9007) (xy 44.72691 -360.972675) (xy 44.742935 -361.046773)
			(xy 44.750994 -361.122154) (xy 44.751498 -361.16006) (xy 45.867577 -361.16006) (xy 45.871612 -361.084356)
			(xy 45.883671 -361.009511) (xy 45.903617 -360.93637) (xy 45.931224 -360.865765) (xy 45.96618 -360.798494)
			(xy 46.008088 -360.735319) (xy 46.056474 -360.676957) (xy 46.11079 -360.624069) (xy 46.170419 -360.577254)
			(xy 46.234687 -360.537042) (xy 46.302864 -360.50389) (xy 46.37418 -360.478172) (xy 46.447825 -360.46018)
			(xy 46.522965 -360.450118) (xy 46.598749 -360.448099) (xy 46.674319 -360.454148) (xy 46.748817 -360.468195)
			(xy 46.8214 -360.490081) (xy 46.891246 -360.519558) (xy 46.957563 -360.556293) (xy 47.019599 -360.599868)
			(xy 47.076652 -360.64979) (xy 47.128076 -360.705494) (xy 47.173287 -360.766349) (xy 47.211774 -360.831664)
			(xy 47.2431 -360.9007) (xy 47.26691 -360.972675) (xy 47.282935 -361.046773) (xy 47.290994 -361.122154)
			(xy 47.291498 -361.16006) (xy 48.407577 -361.16006) (xy 48.411612 -361.084356) (xy 48.423671 -361.009511)
			(xy 48.443617 -360.93637) (xy 48.471224 -360.865765) (xy 48.50618 -360.798494) (xy 48.548088 -360.735319)
			(xy 48.596474 -360.676957) (xy 48.65079 -360.624069) (xy 48.710419 -360.577254) (xy 48.774687 -360.537042)
			(xy 48.842864 -360.50389) (xy 48.91418 -360.478172) (xy 48.987825 -360.46018) (xy 49.062965 -360.450118)
			(xy 49.138749 -360.448099) (xy 49.214319 -360.454148) (xy 49.288817 -360.468195) (xy 49.3614 -360.490081)
			(xy 49.431246 -360.519558) (xy 49.497563 -360.556293) (xy 49.559599 -360.599868) (xy 49.616652 -360.64979)
			(xy 49.668076 -360.705494) (xy 49.713287 -360.766349) (xy 49.751774 -360.831664) (xy 49.7831 -360.9007)
			(xy 49.80691 -360.972675) (xy 49.822935 -361.046773) (xy 49.830994 -361.122154) (xy 49.831498 -361.16006)
			(xy 50.947577 -361.16006) (xy 50.951612 -361.084356) (xy 50.963671 -361.009511) (xy 50.983617 -360.93637)
			(xy 51.011224 -360.865765) (xy 51.04618 -360.798494) (xy 51.088088 -360.735319) (xy 51.136474 -360.676957)
			(xy 51.19079 -360.624069) (xy 51.250419 -360.577254) (xy 51.314687 -360.537042) (xy 51.382864 -360.50389)
			(xy 51.45418 -360.478172) (xy 51.527825 -360.46018) (xy 51.602965 -360.450118) (xy 51.678749 -360.448099)
			(xy 51.754319 -360.454148) (xy 51.828817 -360.468195) (xy 51.9014 -360.490081) (xy 51.971246 -360.519558)
			(xy 52.037563 -360.556293) (xy 52.099599 -360.599868) (xy 52.156652 -360.64979) (xy 52.208076 -360.705494)
			(xy 52.253287 -360.766349) (xy 52.291774 -360.831664) (xy 52.3231 -360.9007) (xy 52.34691 -360.972675)
			(xy 52.362935 -361.046773) (xy 52.370994 -361.122154) (xy 52.371498 -361.16006) (xy 53.487577 -361.16006)
			(xy 53.491612 -361.084356) (xy 53.503671 -361.009511) (xy 53.523617 -360.93637) (xy 53.551224 -360.865765)
			(xy 53.58618 -360.798494) (xy 53.628088 -360.735319) (xy 53.676474 -360.676957) (xy 53.73079 -360.624069)
			(xy 53.790419 -360.577254) (xy 53.854687 -360.537042) (xy 53.922864 -360.50389) (xy 53.99418 -360.478172)
			(xy 54.067825 -360.46018) (xy 54.142965 -360.450118) (xy 54.218749 -360.448099) (xy 54.294319 -360.454148)
			(xy 54.368817 -360.468195) (xy 54.4414 -360.490081) (xy 54.511246 -360.519558) (xy 54.577563 -360.556293)
			(xy 54.639599 -360.599868) (xy 54.696652 -360.64979) (xy 54.748076 -360.705494) (xy 54.793287 -360.766349)
			(xy 54.831774 -360.831664) (xy 54.8631 -360.9007) (xy 54.88691 -360.972675) (xy 54.902935 -361.046773)
			(xy 54.910994 -361.122154) (xy 54.911498 -361.16006) (xy 56.027577 -361.16006) (xy 56.031612 -361.084356)
			(xy 56.043671 -361.009511) (xy 56.063617 -360.93637) (xy 56.091224 -360.865765) (xy 56.12618 -360.798494)
			(xy 56.168088 -360.735319) (xy 56.216474 -360.676957) (xy 56.27079 -360.624069) (xy 56.330419 -360.577254)
			(xy 56.394687 -360.537042) (xy 56.462864 -360.50389) (xy 56.53418 -360.478172) (xy 56.607825 -360.46018)
			(xy 56.682965 -360.450118) (xy 56.758749 -360.448099) (xy 56.834319 -360.454148) (xy 56.908817 -360.468195)
			(xy 56.9814 -360.490081) (xy 57.051246 -360.519558) (xy 57.117563 -360.556293) (xy 57.179599 -360.599868)
			(xy 57.236652 -360.64979) (xy 57.288076 -360.705494) (xy 57.333287 -360.766349) (xy 57.371774 -360.831664)
			(xy 57.4031 -360.9007) (xy 57.42691 -360.972675) (xy 57.442935 -361.046773) (xy 57.450994 -361.122154)
			(xy 57.451498 -361.16006) (xy 58.567577 -361.16006) (xy 58.571612 -361.084356) (xy 58.583671 -361.009511)
			(xy 58.603617 -360.93637) (xy 58.631224 -360.865765) (xy 58.66618 -360.798494) (xy 58.708088 -360.735319)
			(xy 58.756474 -360.676957) (xy 58.81079 -360.624069) (xy 58.870419 -360.577254) (xy 58.934687 -360.537042)
			(xy 59.002864 -360.50389) (xy 59.07418 -360.478172) (xy 59.147825 -360.46018) (xy 59.222965 -360.450118)
			(xy 59.298749 -360.448099) (xy 59.374319 -360.454148) (xy 59.448817 -360.468195) (xy 59.5214 -360.490081)
			(xy 59.591246 -360.519558) (xy 59.657563 -360.556293) (xy 59.719599 -360.599868) (xy 59.776652 -360.64979)
			(xy 59.828076 -360.705494) (xy 59.873287 -360.766349) (xy 59.911774 -360.831664) (xy 59.9431 -360.9007)
			(xy 59.96691 -360.972675) (xy 59.982935 -361.046773) (xy 59.990994 -361.122154) (xy 59.991498 -361.16006)
			(xy 61.107577 -361.16006) (xy 61.111612 -361.084356) (xy 61.123671 -361.009511) (xy 61.143617 -360.93637)
			(xy 61.171224 -360.865765) (xy 61.20618 -360.798494) (xy 61.248088 -360.735319) (xy 61.296474 -360.676957)
			(xy 61.35079 -360.624069) (xy 61.410419 -360.577254) (xy 61.474687 -360.537042) (xy 61.542864 -360.50389)
			(xy 61.61418 -360.478172) (xy 61.687825 -360.46018) (xy 61.762965 -360.450118) (xy 61.838749 -360.448099)
			(xy 61.914319 -360.454148) (xy 61.988817 -360.468195) (xy 62.0614 -360.490081) (xy 62.131246 -360.519558)
			(xy 62.197563 -360.556293) (xy 62.259599 -360.599868) (xy 62.265544 -360.60507) (xy 86.197697 -360.60507)
			(xy 86.201732 -360.529366) (xy 86.213791 -360.454521) (xy 86.233737 -360.38138) (xy 86.261344 -360.310775)
			(xy 86.2963 -360.243504) (xy 86.338208 -360.180329) (xy 86.386594 -360.121967) (xy 86.44091 -360.069079)
			(xy 86.500539 -360.022264) (xy 86.564807 -359.982052) (xy 86.632984 -359.9489) (xy 86.7043 -359.923182)
			(xy 86.777945 -359.90519) (xy 86.853085 -359.895128) (xy 86.928869 -359.893109) (xy 87.004439 -359.899158)
			(xy 87.078937 -359.913205) (xy 87.15152 -359.935091) (xy 87.221366 -359.964568) (xy 87.287683 -360.001303)
			(xy 87.349719 -360.044878) (xy 87.406772 -360.0948) (xy 87.458196 -360.150504) (xy 87.503407 -360.211359)
			(xy 87.541894 -360.276674) (xy 87.57322 -360.34571) (xy 87.59703 -360.417685) (xy 87.613055 -360.491783)
			(xy 87.621114 -360.567164) (xy 87.621618 -360.60507) (xy 88.737697 -360.60507) (xy 88.741732 -360.529366)
			(xy 88.753791 -360.454521) (xy 88.773737 -360.38138) (xy 88.801344 -360.310775) (xy 88.8363 -360.243504)
			(xy 88.878208 -360.180329) (xy 88.926594 -360.121967) (xy 88.98091 -360.069079) (xy 89.040539 -360.022264)
			(xy 89.104807 -359.982052) (xy 89.172984 -359.9489) (xy 89.2443 -359.923182) (xy 89.317945 -359.90519)
			(xy 89.393085 -359.895128) (xy 89.468869 -359.893109) (xy 89.544439 -359.899158) (xy 89.618937 -359.913205)
			(xy 89.69152 -359.935091) (xy 89.761366 -359.964568) (xy 89.827683 -360.001303) (xy 89.889719 -360.044878)
			(xy 89.946772 -360.0948) (xy 89.998196 -360.150504) (xy 90.043407 -360.211359) (xy 90.081894 -360.276674)
			(xy 90.11322 -360.34571) (xy 90.13703 -360.417685) (xy 90.153055 -360.491783) (xy 90.161114 -360.567164)
			(xy 90.161618 -360.60507) (xy 91.277697 -360.60507) (xy 91.281732 -360.529366) (xy 91.293791 -360.454521)
			(xy 91.313737 -360.38138) (xy 91.341344 -360.310775) (xy 91.3763 -360.243504) (xy 91.418208 -360.180329)
			(xy 91.466594 -360.121967) (xy 91.52091 -360.069079) (xy 91.580539 -360.022264) (xy 91.644807 -359.982052)
			(xy 91.712984 -359.9489) (xy 91.7843 -359.923182) (xy 91.857945 -359.90519) (xy 91.933085 -359.895128)
			(xy 92.008869 -359.893109) (xy 92.084439 -359.899158) (xy 92.158937 -359.913205) (xy 92.23152 -359.935091)
			(xy 92.301366 -359.964568) (xy 92.367683 -360.001303) (xy 92.429719 -360.044878) (xy 92.486772 -360.0948)
			(xy 92.538196 -360.150504) (xy 92.583407 -360.211359) (xy 92.621894 -360.276674) (xy 92.65322 -360.34571)
			(xy 92.67703 -360.417685) (xy 92.693055 -360.491783) (xy 92.701114 -360.567164) (xy 92.701618 -360.60507)
			(xy 92.701114 -360.642976) (xy 92.693055 -360.718357) (xy 92.67703 -360.792455) (xy 92.65322 -360.86443)
			(xy 92.621894 -360.933466) (xy 92.583407 -360.998781) (xy 92.538196 -361.059636) (xy 92.486772 -361.11534)
			(xy 92.429719 -361.165262) (xy 92.367683 -361.208837) (xy 92.301366 -361.245572) (xy 92.23152 -361.275049)
			(xy 92.158937 -361.296935) (xy 92.084439 -361.310982) (xy 92.008869 -361.317031) (xy 91.933085 -361.315012)
			(xy 91.857945 -361.30495) (xy 91.7843 -361.286958) (xy 91.712984 -361.26124) (xy 91.644807 -361.228088)
			(xy 91.580539 -361.187876) (xy 91.52091 -361.141061) (xy 91.466594 -361.088173) (xy 91.418208 -361.029811)
			(xy 91.3763 -360.966636) (xy 91.341344 -360.899365) (xy 91.313737 -360.82876) (xy 91.293791 -360.755619)
			(xy 91.281732 -360.680774) (xy 91.277697 -360.60507) (xy 90.161618 -360.60507) (xy 90.161114 -360.642976)
			(xy 90.153055 -360.718357) (xy 90.13703 -360.792455) (xy 90.11322 -360.86443) (xy 90.081894 -360.933466)
			(xy 90.043407 -360.998781) (xy 89.998196 -361.059636) (xy 89.946772 -361.11534) (xy 89.889719 -361.165262)
			(xy 89.827683 -361.208837) (xy 89.761366 -361.245572) (xy 89.69152 -361.275049) (xy 89.618937 -361.296935)
			(xy 89.544439 -361.310982) (xy 89.468869 -361.317031) (xy 89.393085 -361.315012) (xy 89.317945 -361.30495)
			(xy 89.2443 -361.286958) (xy 89.172984 -361.26124) (xy 89.104807 -361.228088) (xy 89.040539 -361.187876)
			(xy 88.98091 -361.141061) (xy 88.926594 -361.088173) (xy 88.878208 -361.029811) (xy 88.8363 -360.966636)
			(xy 88.801344 -360.899365) (xy 88.773737 -360.82876) (xy 88.753791 -360.755619) (xy 88.741732 -360.680774)
			(xy 88.737697 -360.60507) (xy 87.621618 -360.60507) (xy 87.621114 -360.642976) (xy 87.613055 -360.718357)
			(xy 87.59703 -360.792455) (xy 87.57322 -360.86443) (xy 87.541894 -360.933466) (xy 87.503407 -360.998781)
			(xy 87.458196 -361.059636) (xy 87.406772 -361.11534) (xy 87.349719 -361.165262) (xy 87.287683 -361.208837)
			(xy 87.221366 -361.245572) (xy 87.15152 -361.275049) (xy 87.078937 -361.296935) (xy 87.004439 -361.310982)
			(xy 86.928869 -361.317031) (xy 86.853085 -361.315012) (xy 86.777945 -361.30495) (xy 86.7043 -361.286958)
			(xy 86.632984 -361.26124) (xy 86.564807 -361.228088) (xy 86.500539 -361.187876) (xy 86.44091 -361.141061)
			(xy 86.386594 -361.088173) (xy 86.338208 -361.029811) (xy 86.2963 -360.966636) (xy 86.261344 -360.899365)
			(xy 86.233737 -360.82876) (xy 86.213791 -360.755619) (xy 86.201732 -360.680774) (xy 86.197697 -360.60507)
			(xy 62.265544 -360.60507) (xy 62.316652 -360.64979) (xy 62.368076 -360.705494) (xy 62.413287 -360.766349)
			(xy 62.451774 -360.831664) (xy 62.4831 -360.9007) (xy 62.50691 -360.972675) (xy 62.522935 -361.046773)
			(xy 62.530994 -361.122154) (xy 62.531498 -361.16006) (xy 62.530994 -361.197966) (xy 62.522935 -361.273347)
			(xy 62.50691 -361.347445) (xy 62.4831 -361.41942) (xy 62.451774 -361.488456) (xy 62.413287 -361.553771)
			(xy 62.368076 -361.614626) (xy 62.316652 -361.67033) (xy 62.259599 -361.720252) (xy 62.197563 -361.763827)
			(xy 62.131246 -361.800562) (xy 62.0614 -361.830039) (xy 61.988817 -361.851925) (xy 61.914319 -361.865972)
			(xy 61.838749 -361.872021) (xy 61.762965 -361.870002) (xy 61.687825 -361.85994) (xy 61.61418 -361.841948)
			(xy 61.542864 -361.81623) (xy 61.474687 -361.783078) (xy 61.410419 -361.742866) (xy 61.35079 -361.696051)
			(xy 61.296474 -361.643163) (xy 61.248088 -361.584801) (xy 61.20618 -361.521626) (xy 61.171224 -361.454355)
			(xy 61.143617 -361.38375) (xy 61.123671 -361.310609) (xy 61.111612 -361.235764) (xy 61.107577 -361.16006)
			(xy 59.991498 -361.16006) (xy 59.990994 -361.197966) (xy 59.982935 -361.273347) (xy 59.96691 -361.347445)
			(xy 59.9431 -361.41942) (xy 59.911774 -361.488456) (xy 59.873287 -361.553771) (xy 59.828076 -361.614626)
			(xy 59.776652 -361.67033) (xy 59.719599 -361.720252) (xy 59.657563 -361.763827) (xy 59.591246 -361.800562)
			(xy 59.5214 -361.830039) (xy 59.448817 -361.851925) (xy 59.374319 -361.865972) (xy 59.298749 -361.872021)
			(xy 59.222965 -361.870002) (xy 59.147825 -361.85994) (xy 59.07418 -361.841948) (xy 59.002864 -361.81623)
			(xy 58.934687 -361.783078) (xy 58.870419 -361.742866) (xy 58.81079 -361.696051) (xy 58.756474 -361.643163)
			(xy 58.708088 -361.584801) (xy 58.66618 -361.521626) (xy 58.631224 -361.454355) (xy 58.603617 -361.38375)
			(xy 58.583671 -361.310609) (xy 58.571612 -361.235764) (xy 58.567577 -361.16006) (xy 57.451498 -361.16006)
			(xy 57.450994 -361.197966) (xy 57.442935 -361.273347) (xy 57.42691 -361.347445) (xy 57.4031 -361.41942)
			(xy 57.371774 -361.488456) (xy 57.333287 -361.553771) (xy 57.288076 -361.614626) (xy 57.236652 -361.67033)
			(xy 57.179599 -361.720252) (xy 57.117563 -361.763827) (xy 57.051246 -361.800562) (xy 56.9814 -361.830039)
			(xy 56.908817 -361.851925) (xy 56.834319 -361.865972) (xy 56.758749 -361.872021) (xy 56.682965 -361.870002)
			(xy 56.607825 -361.85994) (xy 56.53418 -361.841948) (xy 56.462864 -361.81623) (xy 56.394687 -361.783078)
			(xy 56.330419 -361.742866) (xy 56.27079 -361.696051) (xy 56.216474 -361.643163) (xy 56.168088 -361.584801)
			(xy 56.12618 -361.521626) (xy 56.091224 -361.454355) (xy 56.063617 -361.38375) (xy 56.043671 -361.310609)
			(xy 56.031612 -361.235764) (xy 56.027577 -361.16006) (xy 54.911498 -361.16006) (xy 54.910994 -361.197966)
			(xy 54.902935 -361.273347) (xy 54.88691 -361.347445) (xy 54.8631 -361.41942) (xy 54.831774 -361.488456)
			(xy 54.793287 -361.553771) (xy 54.748076 -361.614626) (xy 54.696652 -361.67033) (xy 54.639599 -361.720252)
			(xy 54.577563 -361.763827) (xy 54.511246 -361.800562) (xy 54.4414 -361.830039) (xy 54.368817 -361.851925)
			(xy 54.294319 -361.865972) (xy 54.218749 -361.872021) (xy 54.142965 -361.870002) (xy 54.067825 -361.85994)
			(xy 53.99418 -361.841948) (xy 53.922864 -361.81623) (xy 53.854687 -361.783078) (xy 53.790419 -361.742866)
			(xy 53.73079 -361.696051) (xy 53.676474 -361.643163) (xy 53.628088 -361.584801) (xy 53.58618 -361.521626)
			(xy 53.551224 -361.454355) (xy 53.523617 -361.38375) (xy 53.503671 -361.310609) (xy 53.491612 -361.235764)
			(xy 53.487577 -361.16006) (xy 52.371498 -361.16006) (xy 52.370994 -361.197966) (xy 52.362935 -361.273347)
			(xy 52.34691 -361.347445) (xy 52.3231 -361.41942) (xy 52.291774 -361.488456) (xy 52.253287 -361.553771)
			(xy 52.208076 -361.614626) (xy 52.156652 -361.67033) (xy 52.099599 -361.720252) (xy 52.037563 -361.763827)
			(xy 51.971246 -361.800562) (xy 51.9014 -361.830039) (xy 51.828817 -361.851925) (xy 51.754319 -361.865972)
			(xy 51.678749 -361.872021) (xy 51.602965 -361.870002) (xy 51.527825 -361.85994) (xy 51.45418 -361.841948)
			(xy 51.382864 -361.81623) (xy 51.314687 -361.783078) (xy 51.250419 -361.742866) (xy 51.19079 -361.696051)
			(xy 51.136474 -361.643163) (xy 51.088088 -361.584801) (xy 51.04618 -361.521626) (xy 51.011224 -361.454355)
			(xy 50.983617 -361.38375) (xy 50.963671 -361.310609) (xy 50.951612 -361.235764) (xy 50.947577 -361.16006)
			(xy 49.831498 -361.16006) (xy 49.830994 -361.197966) (xy 49.822935 -361.273347) (xy 49.80691 -361.347445)
			(xy 49.7831 -361.41942) (xy 49.751774 -361.488456) (xy 49.713287 -361.553771) (xy 49.668076 -361.614626)
			(xy 49.616652 -361.67033) (xy 49.559599 -361.720252) (xy 49.497563 -361.763827) (xy 49.431246 -361.800562)
			(xy 49.3614 -361.830039) (xy 49.288817 -361.851925) (xy 49.214319 -361.865972) (xy 49.138749 -361.872021)
			(xy 49.062965 -361.870002) (xy 48.987825 -361.85994) (xy 48.91418 -361.841948) (xy 48.842864 -361.81623)
			(xy 48.774687 -361.783078) (xy 48.710419 -361.742866) (xy 48.65079 -361.696051) (xy 48.596474 -361.643163)
			(xy 48.548088 -361.584801) (xy 48.50618 -361.521626) (xy 48.471224 -361.454355) (xy 48.443617 -361.38375)
			(xy 48.423671 -361.310609) (xy 48.411612 -361.235764) (xy 48.407577 -361.16006) (xy 47.291498 -361.16006)
			(xy 47.290994 -361.197966) (xy 47.282935 -361.273347) (xy 47.26691 -361.347445) (xy 47.2431 -361.41942)
			(xy 47.211774 -361.488456) (xy 47.173287 -361.553771) (xy 47.128076 -361.614626) (xy 47.076652 -361.67033)
			(xy 47.019599 -361.720252) (xy 46.957563 -361.763827) (xy 46.891246 -361.800562) (xy 46.8214 -361.830039)
			(xy 46.748817 -361.851925) (xy 46.674319 -361.865972) (xy 46.598749 -361.872021) (xy 46.522965 -361.870002)
			(xy 46.447825 -361.85994) (xy 46.37418 -361.841948) (xy 46.302864 -361.81623) (xy 46.234687 -361.783078)
			(xy 46.170419 -361.742866) (xy 46.11079 -361.696051) (xy 46.056474 -361.643163) (xy 46.008088 -361.584801)
			(xy 45.96618 -361.521626) (xy 45.931224 -361.454355) (xy 45.903617 -361.38375) (xy 45.883671 -361.310609)
			(xy 45.871612 -361.235764) (xy 45.867577 -361.16006) (xy 44.751498 -361.16006) (xy 44.750994 -361.197966)
			(xy 44.742935 -361.273347) (xy 44.72691 -361.347445) (xy 44.7031 -361.41942) (xy 44.671774 -361.488456)
			(xy 44.633287 -361.553771) (xy 44.588076 -361.614626) (xy 44.536652 -361.67033) (xy 44.479599 -361.720252)
			(xy 44.417563 -361.763827) (xy 44.351246 -361.800562) (xy 44.2814 -361.830039) (xy 44.208817 -361.851925)
			(xy 44.134319 -361.865972) (xy 44.058749 -361.872021) (xy 43.982965 -361.870002) (xy 43.907825 -361.85994)
			(xy 43.83418 -361.841948) (xy 43.762864 -361.81623) (xy 43.694687 -361.783078) (xy 43.630419 -361.742866)
			(xy 43.57079 -361.696051) (xy 43.516474 -361.643163) (xy 43.468088 -361.584801) (xy 43.42618 -361.521626)
			(xy 43.391224 -361.454355) (xy 43.363617 -361.38375) (xy 43.343671 -361.310609) (xy 43.331612 -361.235764)
			(xy 43.327577 -361.16006) (xy 42.502604 -361.16006) (xy 42.593088 -361.232218) (xy 42.678643 -361.310691)
			(xy 42.758581 -361.394879) (xy 42.83252 -361.484381) (xy 42.900108 -361.578772) (xy 42.961022 -361.6776)
			(xy 43.014974 -361.780396) (xy 43.056604 -361.87507) (xy 84.927697 -361.87507) (xy 84.931732 -361.799366)
			(xy 84.943791 -361.724521) (xy 84.963737 -361.65138) (xy 84.991344 -361.580775) (xy 85.0263 -361.513504)
			(xy 85.068208 -361.450329) (xy 85.116594 -361.391967) (xy 85.17091 -361.339079) (xy 85.230539 -361.292264)
			(xy 85.294807 -361.252052) (xy 85.362984 -361.2189) (xy 85.4343 -361.193182) (xy 85.507945 -361.17519)
			(xy 85.583085 -361.165128) (xy 85.658869 -361.163109) (xy 85.734439 -361.169158) (xy 85.808937 -361.183205)
			(xy 85.88152 -361.205091) (xy 85.951366 -361.234568) (xy 86.017683 -361.271303) (xy 86.079719 -361.314878)
			(xy 86.136772 -361.3648) (xy 86.188196 -361.420504) (xy 86.233407 -361.481359) (xy 86.271894 -361.546674)
			(xy 86.30322 -361.61571) (xy 86.32703 -361.687685) (xy 86.343055 -361.761783) (xy 86.351114 -361.837164)
			(xy 86.351618 -361.87507) (xy 87.467697 -361.87507) (xy 87.471732 -361.799366) (xy 87.483791 -361.724521)
			(xy 87.503737 -361.65138) (xy 87.531344 -361.580775) (xy 87.5663 -361.513504) (xy 87.608208 -361.450329)
			(xy 87.656594 -361.391967) (xy 87.71091 -361.339079) (xy 87.770539 -361.292264) (xy 87.834807 -361.252052)
			(xy 87.902984 -361.2189) (xy 87.9743 -361.193182) (xy 88.047945 -361.17519) (xy 88.123085 -361.165128)
			(xy 88.198869 -361.163109) (xy 88.274439 -361.169158) (xy 88.348937 -361.183205) (xy 88.42152 -361.205091)
			(xy 88.491366 -361.234568) (xy 88.557683 -361.271303) (xy 88.619719 -361.314878) (xy 88.676772 -361.3648)
			(xy 88.728196 -361.420504) (xy 88.773407 -361.481359) (xy 88.811894 -361.546674) (xy 88.84322 -361.61571)
			(xy 88.86703 -361.687685) (xy 88.883055 -361.761783) (xy 88.891114 -361.837164) (xy 88.891618 -361.87507)
			(xy 90.007697 -361.87507) (xy 90.011732 -361.799366) (xy 90.023791 -361.724521) (xy 90.043737 -361.65138)
			(xy 90.071344 -361.580775) (xy 90.1063 -361.513504) (xy 90.148208 -361.450329) (xy 90.196594 -361.391967)
			(xy 90.25091 -361.339079) (xy 90.310539 -361.292264) (xy 90.374807 -361.252052) (xy 90.442984 -361.2189)
			(xy 90.5143 -361.193182) (xy 90.587945 -361.17519) (xy 90.663085 -361.165128) (xy 90.738869 -361.163109)
			(xy 90.814439 -361.169158) (xy 90.888937 -361.183205) (xy 90.96152 -361.205091) (xy 91.031366 -361.234568)
			(xy 91.097683 -361.271303) (xy 91.159719 -361.314878) (xy 91.216772 -361.3648) (xy 91.268196 -361.420504)
			(xy 91.313407 -361.481359) (xy 91.351894 -361.546674) (xy 91.38322 -361.61571) (xy 91.40703 -361.687685)
			(xy 91.423055 -361.761783) (xy 91.431114 -361.837164) (xy 91.431618 -361.87507) (xy 91.431114 -361.912976)
			(xy 91.423055 -361.988357) (xy 91.40703 -362.062455) (xy 91.38322 -362.13443) (xy 91.351894 -362.203466)
			(xy 91.313407 -362.268781) (xy 91.268196 -362.329636) (xy 91.216772 -362.38534) (xy 91.159719 -362.435262)
			(xy 91.097683 -362.478837) (xy 91.031366 -362.515572) (xy 90.96152 -362.545049) (xy 90.888937 -362.566935)
			(xy 90.814439 -362.580982) (xy 90.738869 -362.587031) (xy 90.663085 -362.585012) (xy 90.587945 -362.57495)
			(xy 90.5143 -362.556958) (xy 90.442984 -362.53124) (xy 90.374807 -362.498088) (xy 90.310539 -362.457876)
			(xy 90.25091 -362.411061) (xy 90.196594 -362.358173) (xy 90.148208 -362.299811) (xy 90.1063 -362.236636)
			(xy 90.071344 -362.169365) (xy 90.043737 -362.09876) (xy 90.023791 -362.025619) (xy 90.011732 -361.950774)
			(xy 90.007697 -361.87507) (xy 88.891618 -361.87507) (xy 88.891114 -361.912976) (xy 88.883055 -361.988357)
			(xy 88.86703 -362.062455) (xy 88.84322 -362.13443) (xy 88.811894 -362.203466) (xy 88.773407 -362.268781)
			(xy 88.728196 -362.329636) (xy 88.676772 -362.38534) (xy 88.619719 -362.435262) (xy 88.557683 -362.478837)
			(xy 88.491366 -362.515572) (xy 88.42152 -362.545049) (xy 88.348937 -362.566935) (xy 88.274439 -362.580982)
			(xy 88.198869 -362.587031) (xy 88.123085 -362.585012) (xy 88.047945 -362.57495) (xy 87.9743 -362.556958)
			(xy 87.902984 -362.53124) (xy 87.834807 -362.498088) (xy 87.770539 -362.457876) (xy 87.71091 -362.411061)
			(xy 87.656594 -362.358173) (xy 87.608208 -362.299811) (xy 87.5663 -362.236636) (xy 87.531344 -362.169365)
			(xy 87.503737 -362.09876) (xy 87.483791 -362.025619) (xy 87.471732 -361.950774) (xy 87.467697 -361.87507)
			(xy 86.351618 -361.87507) (xy 86.351114 -361.912976) (xy 86.343055 -361.988357) (xy 86.32703 -362.062455)
			(xy 86.30322 -362.13443) (xy 86.271894 -362.203466) (xy 86.233407 -362.268781) (xy 86.188196 -362.329636)
			(xy 86.136772 -362.38534) (xy 86.079719 -362.435262) (xy 86.017683 -362.478837) (xy 85.951366 -362.515572)
			(xy 85.88152 -362.545049) (xy 85.808937 -362.566935) (xy 85.734439 -362.580982) (xy 85.658869 -362.587031)
			(xy 85.583085 -362.585012) (xy 85.507945 -362.57495) (xy 85.4343 -362.556958) (xy 85.362984 -362.53124)
			(xy 85.294807 -362.498088) (xy 85.230539 -362.457876) (xy 85.17091 -362.411061) (xy 85.116594 -362.358173)
			(xy 85.068208 -362.299811) (xy 85.0263 -362.236636) (xy 84.991344 -362.169365) (xy 84.963737 -362.09876)
			(xy 84.943791 -362.025619) (xy 84.931732 -361.950774) (xy 84.927697 -361.87507) (xy 43.056604 -361.87507)
			(xy 43.061704 -361.886669) (xy 43.100992 -361.995913) (xy 43.132649 -362.107606) (xy 43.156525 -362.221218)
			(xy 43.172506 -362.336206) (xy 43.180515 -362.452023) (xy 43.181016 -362.51007) (xy 43.180515 -362.568117)
			(xy 43.172506 -362.683934) (xy 43.156525 -362.798922) (xy 43.132649 -362.912534) (xy 43.100992 -363.024227)
			(xy 43.061704 -363.133471) (xy 43.056604 -363.14507) (xy 86.197697 -363.14507) (xy 86.201732 -363.069366)
			(xy 86.213791 -362.994521) (xy 86.233737 -362.92138) (xy 86.261344 -362.850775) (xy 86.2963 -362.783504)
			(xy 86.338208 -362.720329) (xy 86.386594 -362.661967) (xy 86.44091 -362.609079) (xy 86.500539 -362.562264)
			(xy 86.564807 -362.522052) (xy 86.632984 -362.4889) (xy 86.7043 -362.463182) (xy 86.777945 -362.44519)
			(xy 86.853085 -362.435128) (xy 86.928869 -362.433109) (xy 87.004439 -362.439158) (xy 87.078937 -362.453205)
			(xy 87.15152 -362.475091) (xy 87.221366 -362.504568) (xy 87.287683 -362.541303) (xy 87.349719 -362.584878)
			(xy 87.406772 -362.6348) (xy 87.458196 -362.690504) (xy 87.503407 -362.751359) (xy 87.541894 -362.816674)
			(xy 87.57322 -362.88571) (xy 87.59703 -362.957685) (xy 87.613055 -363.031783) (xy 87.621114 -363.107164)
			(xy 87.621618 -363.14507) (xy 88.737697 -363.14507) (xy 88.741732 -363.069366) (xy 88.753791 -362.994521)
			(xy 88.773737 -362.92138) (xy 88.801344 -362.850775) (xy 88.8363 -362.783504) (xy 88.878208 -362.720329)
			(xy 88.926594 -362.661967) (xy 88.98091 -362.609079) (xy 89.040539 -362.562264) (xy 89.104807 -362.522052)
			(xy 89.172984 -362.4889) (xy 89.2443 -362.463182) (xy 89.317945 -362.44519) (xy 89.393085 -362.435128)
			(xy 89.468869 -362.433109) (xy 89.544439 -362.439158) (xy 89.618937 -362.453205) (xy 89.69152 -362.475091)
			(xy 89.761366 -362.504568) (xy 89.827683 -362.541303) (xy 89.889719 -362.584878) (xy 89.946772 -362.6348)
			(xy 89.998196 -362.690504) (xy 90.043407 -362.751359) (xy 90.081894 -362.816674) (xy 90.11322 -362.88571)
			(xy 90.13703 -362.957685) (xy 90.153055 -363.031783) (xy 90.161114 -363.107164) (xy 90.161618 -363.14507)
			(xy 91.277697 -363.14507) (xy 91.281732 -363.069366) (xy 91.293791 -362.994521) (xy 91.313737 -362.92138)
			(xy 91.341344 -362.850775) (xy 91.3763 -362.783504) (xy 91.418208 -362.720329) (xy 91.466594 -362.661967)
			(xy 91.52091 -362.609079) (xy 91.580539 -362.562264) (xy 91.644807 -362.522052) (xy 91.712984 -362.4889)
			(xy 91.7843 -362.463182) (xy 91.857945 -362.44519) (xy 91.933085 -362.435128) (xy 92.008869 -362.433109)
			(xy 92.084439 -362.439158) (xy 92.158937 -362.453205) (xy 92.23152 -362.475091) (xy 92.301366 -362.504568)
			(xy 92.367683 -362.541303) (xy 92.429719 -362.584878) (xy 92.486772 -362.6348) (xy 92.538196 -362.690504)
			(xy 92.583407 -362.751359) (xy 92.621894 -362.816674) (xy 92.65322 -362.88571) (xy 92.67703 -362.957685)
			(xy 92.693055 -363.031783) (xy 92.701114 -363.107164) (xy 92.701618 -363.14507) (xy 92.701114 -363.182976)
			(xy 92.693055 -363.258357) (xy 92.67703 -363.332455) (xy 92.65322 -363.40443) (xy 92.621894 -363.473466)
			(xy 92.583407 -363.538781) (xy 92.538196 -363.599636) (xy 92.486772 -363.65534) (xy 92.429719 -363.705262)
			(xy 92.367683 -363.748837) (xy 92.301366 -363.785572) (xy 92.23152 -363.815049) (xy 92.158937 -363.836935)
			(xy 92.084439 -363.850982) (xy 92.008869 -363.857031) (xy 91.933085 -363.855012) (xy 91.857945 -363.84495)
			(xy 91.7843 -363.826958) (xy 91.712984 -363.80124) (xy 91.644807 -363.768088) (xy 91.580539 -363.727876)
			(xy 91.52091 -363.681061) (xy 91.466594 -363.628173) (xy 91.418208 -363.569811) (xy 91.3763 -363.506636)
			(xy 91.341344 -363.439365) (xy 91.313737 -363.36876) (xy 91.293791 -363.295619) (xy 91.281732 -363.220774)
			(xy 91.277697 -363.14507) (xy 90.161618 -363.14507) (xy 90.161114 -363.182976) (xy 90.153055 -363.258357)
			(xy 90.13703 -363.332455) (xy 90.11322 -363.40443) (xy 90.081894 -363.473466) (xy 90.043407 -363.538781)
			(xy 89.998196 -363.599636) (xy 89.946772 -363.65534) (xy 89.889719 -363.705262) (xy 89.827683 -363.748837)
			(xy 89.761366 -363.785572) (xy 89.69152 -363.815049) (xy 89.618937 -363.836935) (xy 89.544439 -363.850982)
			(xy 89.468869 -363.857031) (xy 89.393085 -363.855012) (xy 89.317945 -363.84495) (xy 89.2443 -363.826958)
			(xy 89.172984 -363.80124) (xy 89.104807 -363.768088) (xy 89.040539 -363.727876) (xy 88.98091 -363.681061)
			(xy 88.926594 -363.628173) (xy 88.878208 -363.569811) (xy 88.8363 -363.506636) (xy 88.801344 -363.439365)
			(xy 88.773737 -363.36876) (xy 88.753791 -363.295619) (xy 88.741732 -363.220774) (xy 88.737697 -363.14507)
			(xy 87.621618 -363.14507) (xy 87.621114 -363.182976) (xy 87.613055 -363.258357) (xy 87.59703 -363.332455)
			(xy 87.57322 -363.40443) (xy 87.541894 -363.473466) (xy 87.503407 -363.538781) (xy 87.458196 -363.599636)
			(xy 87.406772 -363.65534) (xy 87.349719 -363.705262) (xy 87.287683 -363.748837) (xy 87.221366 -363.785572)
			(xy 87.15152 -363.815049) (xy 87.078937 -363.836935) (xy 87.004439 -363.850982) (xy 86.928869 -363.857031)
			(xy 86.853085 -363.855012) (xy 86.777945 -363.84495) (xy 86.7043 -363.826958) (xy 86.632984 -363.80124)
			(xy 86.564807 -363.768088) (xy 86.500539 -363.727876) (xy 86.44091 -363.681061) (xy 86.386594 -363.628173)
			(xy 86.338208 -363.569811) (xy 86.2963 -363.506636) (xy 86.261344 -363.439365) (xy 86.233737 -363.36876)
			(xy 86.213791 -363.295619) (xy 86.201732 -363.220774) (xy 86.197697 -363.14507) (xy 43.056604 -363.14507)
			(xy 43.055152 -363.148372) (xy 43.328336 -363.148372) (xy 44.751244 -363.148372) (xy 44.751244 -363.86008)
			(xy 45.867577 -363.86008) (xy 45.871612 -363.784376) (xy 45.883671 -363.709531) (xy 45.903617 -363.63639)
			(xy 45.931224 -363.565785) (xy 45.96618 -363.498514) (xy 46.008088 -363.435339) (xy 46.056474 -363.376977)
			(xy 46.11079 -363.324089) (xy 46.170419 -363.277274) (xy 46.234687 -363.237062) (xy 46.302864 -363.20391)
			(xy 46.37418 -363.178192) (xy 46.447825 -363.1602) (xy 46.522965 -363.150138) (xy 46.598749 -363.148119)
			(xy 46.674319 -363.154168) (xy 46.748817 -363.168215) (xy 46.8214 -363.190101) (xy 46.891246 -363.219578)
			(xy 46.957563 -363.256313) (xy 47.019599 -363.299888) (xy 47.076652 -363.34981) (xy 47.128076 -363.405514)
			(xy 47.173287 -363.466369) (xy 47.211774 -363.531684) (xy 47.2431 -363.60072) (xy 47.26691 -363.672695)
			(xy 47.282935 -363.746793) (xy 47.290994 -363.822174) (xy 47.291498 -363.86008) (xy 48.407577 -363.86008)
			(xy 48.411612 -363.784376) (xy 48.423671 -363.709531) (xy 48.443617 -363.63639) (xy 48.471224 -363.565785)
			(xy 48.50618 -363.498514) (xy 48.548088 -363.435339) (xy 48.596474 -363.376977) (xy 48.65079 -363.324089)
			(xy 48.710419 -363.277274) (xy 48.774687 -363.237062) (xy 48.842864 -363.20391) (xy 48.91418 -363.178192)
			(xy 48.987825 -363.1602) (xy 49.062965 -363.150138) (xy 49.138749 -363.148119) (xy 49.214319 -363.154168)
			(xy 49.288817 -363.168215) (xy 49.3614 -363.190101) (xy 49.431246 -363.219578) (xy 49.497563 -363.256313)
			(xy 49.559599 -363.299888) (xy 49.616652 -363.34981) (xy 49.668076 -363.405514) (xy 49.713287 -363.466369)
			(xy 49.751774 -363.531684) (xy 49.7831 -363.60072) (xy 49.80691 -363.672695) (xy 49.822935 -363.746793)
			(xy 49.830994 -363.822174) (xy 49.831498 -363.86008) (xy 50.947577 -363.86008) (xy 50.951612 -363.784376)
			(xy 50.963671 -363.709531) (xy 50.983617 -363.63639) (xy 51.011224 -363.565785) (xy 51.04618 -363.498514)
			(xy 51.088088 -363.435339) (xy 51.136474 -363.376977) (xy 51.19079 -363.324089) (xy 51.250419 -363.277274)
			(xy 51.314687 -363.237062) (xy 51.382864 -363.20391) (xy 51.45418 -363.178192) (xy 51.527825 -363.1602)
			(xy 51.602965 -363.150138) (xy 51.678749 -363.148119) (xy 51.754319 -363.154168) (xy 51.828817 -363.168215)
			(xy 51.9014 -363.190101) (xy 51.971246 -363.219578) (xy 52.037563 -363.256313) (xy 52.099599 -363.299888)
			(xy 52.156652 -363.34981) (xy 52.208076 -363.405514) (xy 52.253287 -363.466369) (xy 52.291774 -363.531684)
			(xy 52.3231 -363.60072) (xy 52.34691 -363.672695) (xy 52.362935 -363.746793) (xy 52.370994 -363.822174)
			(xy 52.371498 -363.86008) (xy 53.487577 -363.86008) (xy 53.491612 -363.784376) (xy 53.503671 -363.709531)
			(xy 53.523617 -363.63639) (xy 53.551224 -363.565785) (xy 53.58618 -363.498514) (xy 53.628088 -363.435339)
			(xy 53.676474 -363.376977) (xy 53.73079 -363.324089) (xy 53.790419 -363.277274) (xy 53.854687 -363.237062)
			(xy 53.922864 -363.20391) (xy 53.99418 -363.178192) (xy 54.067825 -363.1602) (xy 54.142965 -363.150138)
			(xy 54.218749 -363.148119) (xy 54.294319 -363.154168) (xy 54.368817 -363.168215) (xy 54.4414 -363.190101)
			(xy 54.511246 -363.219578) (xy 54.577563 -363.256313) (xy 54.639599 -363.299888) (xy 54.696652 -363.34981)
			(xy 54.748076 -363.405514) (xy 54.793287 -363.466369) (xy 54.831774 -363.531684) (xy 54.8631 -363.60072)
			(xy 54.88691 -363.672695) (xy 54.902935 -363.746793) (xy 54.910994 -363.822174) (xy 54.911498 -363.86008)
			(xy 56.027577 -363.86008) (xy 56.031612 -363.784376) (xy 56.043671 -363.709531) (xy 56.063617 -363.63639)
			(xy 56.091224 -363.565785) (xy 56.12618 -363.498514) (xy 56.168088 -363.435339) (xy 56.216474 -363.376977)
			(xy 56.27079 -363.324089) (xy 56.330419 -363.277274) (xy 56.394687 -363.237062) (xy 56.462864 -363.20391)
			(xy 56.53418 -363.178192) (xy 56.607825 -363.1602) (xy 56.682965 -363.150138) (xy 56.758749 -363.148119)
			(xy 56.834319 -363.154168) (xy 56.908817 -363.168215) (xy 56.9814 -363.190101) (xy 57.051246 -363.219578)
			(xy 57.117563 -363.256313) (xy 57.179599 -363.299888) (xy 57.236652 -363.34981) (xy 57.288076 -363.405514)
			(xy 57.333287 -363.466369) (xy 57.371774 -363.531684) (xy 57.4031 -363.60072) (xy 57.42691 -363.672695)
			(xy 57.442935 -363.746793) (xy 57.450994 -363.822174) (xy 57.451498 -363.86008) (xy 58.567577 -363.86008)
			(xy 58.571612 -363.784376) (xy 58.583671 -363.709531) (xy 58.603617 -363.63639) (xy 58.631224 -363.565785)
			(xy 58.66618 -363.498514) (xy 58.708088 -363.435339) (xy 58.756474 -363.376977) (xy 58.81079 -363.324089)
			(xy 58.870419 -363.277274) (xy 58.934687 -363.237062) (xy 59.002864 -363.20391) (xy 59.07418 -363.178192)
			(xy 59.147825 -363.1602) (xy 59.222965 -363.150138) (xy 59.298749 -363.148119) (xy 59.374319 -363.154168)
			(xy 59.448817 -363.168215) (xy 59.5214 -363.190101) (xy 59.591246 -363.219578) (xy 59.657563 -363.256313)
			(xy 59.719599 -363.299888) (xy 59.776652 -363.34981) (xy 59.828076 -363.405514) (xy 59.873287 -363.466369)
			(xy 59.911774 -363.531684) (xy 59.9431 -363.60072) (xy 59.96691 -363.672695) (xy 59.982935 -363.746793)
			(xy 59.990994 -363.822174) (xy 59.991498 -363.86008) (xy 61.107577 -363.86008) (xy 61.111612 -363.784376)
			(xy 61.123671 -363.709531) (xy 61.143617 -363.63639) (xy 61.171224 -363.565785) (xy 61.20618 -363.498514)
			(xy 61.248088 -363.435339) (xy 61.296474 -363.376977) (xy 61.35079 -363.324089) (xy 61.410419 -363.277274)
			(xy 61.474687 -363.237062) (xy 61.542864 -363.20391) (xy 61.61418 -363.178192) (xy 61.687825 -363.1602)
			(xy 61.762965 -363.150138) (xy 61.838749 -363.148119) (xy 61.914319 -363.154168) (xy 61.988817 -363.168215)
			(xy 62.0614 -363.190101) (xy 62.131246 -363.219578) (xy 62.197563 -363.256313) (xy 62.259599 -363.299888)
			(xy 62.316652 -363.34981) (xy 62.368076 -363.405514) (xy 62.413287 -363.466369) (xy 62.451774 -363.531684)
			(xy 62.4831 -363.60072) (xy 62.50691 -363.672695) (xy 62.522935 -363.746793) (xy 62.530994 -363.822174)
			(xy 62.531498 -363.86008) (xy 62.530994 -363.897986) (xy 62.522935 -363.973367) (xy 62.50691 -364.047465)
			(xy 62.4831 -364.11944) (xy 62.451774 -364.188476) (xy 62.413287 -364.253791) (xy 62.368076 -364.314646)
			(xy 62.316652 -364.37035) (xy 62.265544 -364.41507) (xy 84.927697 -364.41507) (xy 84.931732 -364.339366)
			(xy 84.943791 -364.264521) (xy 84.963737 -364.19138) (xy 84.991344 -364.120775) (xy 85.0263 -364.053504)
			(xy 85.068208 -363.990329) (xy 85.116594 -363.931967) (xy 85.17091 -363.879079) (xy 85.230539 -363.832264)
			(xy 85.294807 -363.792052) (xy 85.362984 -363.7589) (xy 85.4343 -363.733182) (xy 85.507945 -363.71519)
			(xy 85.583085 -363.705128) (xy 85.658869 -363.703109) (xy 85.734439 -363.709158) (xy 85.808937 -363.723205)
			(xy 85.88152 -363.745091) (xy 85.951366 -363.774568) (xy 86.017683 -363.811303) (xy 86.079719 -363.854878)
			(xy 86.136772 -363.9048) (xy 86.188196 -363.960504) (xy 86.233407 -364.021359) (xy 86.271894 -364.086674)
			(xy 86.30322 -364.15571) (xy 86.32703 -364.227685) (xy 86.343055 -364.301783) (xy 86.351114 -364.377164)
			(xy 86.351618 -364.41507) (xy 87.467697 -364.41507) (xy 87.471732 -364.339366) (xy 87.483791 -364.264521)
			(xy 87.503737 -364.19138) (xy 87.531344 -364.120775) (xy 87.5663 -364.053504) (xy 87.608208 -363.990329)
			(xy 87.656594 -363.931967) (xy 87.71091 -363.879079) (xy 87.770539 -363.832264) (xy 87.834807 -363.792052)
			(xy 87.902984 -363.7589) (xy 87.9743 -363.733182) (xy 88.047945 -363.71519) (xy 88.123085 -363.705128)
			(xy 88.198869 -363.703109) (xy 88.274439 -363.709158) (xy 88.348937 -363.723205) (xy 88.42152 -363.745091)
			(xy 88.491366 -363.774568) (xy 88.557683 -363.811303) (xy 88.619719 -363.854878) (xy 88.676772 -363.9048)
			(xy 88.728196 -363.960504) (xy 88.773407 -364.021359) (xy 88.811894 -364.086674) (xy 88.84322 -364.15571)
			(xy 88.86703 -364.227685) (xy 88.883055 -364.301783) (xy 88.891114 -364.377164) (xy 88.891618 -364.41507)
			(xy 90.007697 -364.41507) (xy 90.011732 -364.339366) (xy 90.023791 -364.264521) (xy 90.043737 -364.19138)
			(xy 90.071344 -364.120775) (xy 90.1063 -364.053504) (xy 90.148208 -363.990329) (xy 90.196594 -363.931967)
			(xy 90.25091 -363.879079) (xy 90.310539 -363.832264) (xy 90.374807 -363.792052) (xy 90.442984 -363.7589)
			(xy 90.5143 -363.733182) (xy 90.587945 -363.71519) (xy 90.663085 -363.705128) (xy 90.738869 -363.703109)
			(xy 90.814439 -363.709158) (xy 90.888937 -363.723205) (xy 90.96152 -363.745091) (xy 91.031366 -363.774568)
			(xy 91.097683 -363.811303) (xy 91.159719 -363.854878) (xy 91.165664 -363.86008) (xy 93.154506 -363.86008)
			(xy 93.158522 -363.74381) (xy 93.170549 -363.628095) (xy 93.190531 -363.513485) (xy 93.218373 -363.400526)
			(xy 93.253942 -363.289758) (xy 93.297068 -363.181707) (xy 93.347545 -363.076889) (xy 93.405134 -362.975804)
			(xy 93.46956 -362.878932) (xy 93.540515 -362.786736) (xy 93.617662 -362.699655) (xy 93.700633 -362.618104)
			(xy 93.789033 -362.542472) (xy 93.88244 -362.473118) (xy 93.980409 -362.410375) (xy 94.082473 -362.354539)
			(xy 94.188147 -362.305878) (xy 94.296926 -362.264624) (xy 94.408291 -362.230973) (xy 94.521714 -362.205085)
			(xy 94.636651 -362.187084) (xy 94.752557 -362.177055) (xy 94.868879 -362.175047) (xy 94.985062 -362.181069)
			(xy 95.100553 -362.195092) (xy 95.214801 -362.21705) (xy 95.327262 -362.246837) (xy 95.4374 -362.284312)
			(xy 95.54469 -362.329297) (xy 95.648621 -362.381576) (xy 95.748697 -362.440901) (xy 95.844443 -362.506989)
			(xy 95.9354 -362.579525) (xy 96.021136 -362.658164) (xy 96.101243 -362.74253) (xy 96.175339 -362.832222)
			(xy 96.243069 -362.926812) (xy 96.304113 -363.02585) (xy 96.358178 -363.128863) (xy 96.405008 -363.23536)
			(xy 96.444379 -363.344835) (xy 96.476103 -363.456765) (xy 96.500029 -363.570617) (xy 96.516043 -363.685849)
			(xy 96.52407 -363.801911) (xy 96.524572 -363.86008) (xy 96.52407 -363.918249) (xy 96.516043 -364.034311)
			(xy 96.500029 -364.149543) (xy 96.476103 -364.263395) (xy 96.444379 -364.375325) (xy 96.405008 -364.4848)
			(xy 96.358178 -364.591297) (xy 96.304113 -364.69431) (xy 96.243069 -364.793348) (xy 96.175339 -364.887938)
			(xy 96.101243 -364.97763) (xy 96.021136 -365.061996) (xy 95.9354 -365.140635) (xy 95.844443 -365.213171)
			(xy 95.748697 -365.279259) (xy 95.648621 -365.338584) (xy 95.54469 -365.390863) (xy 95.4374 -365.435848)
			(xy 95.327262 -365.473323) (xy 95.214801 -365.50311) (xy 95.100553 -365.525068) (xy 94.985062 -365.539091)
			(xy 94.868879 -365.545113) (xy 94.752557 -365.543105) (xy 94.636651 -365.533076) (xy 94.521714 -365.515075)
			(xy 94.408291 -365.489187) (xy 94.296926 -365.455536) (xy 94.188147 -365.414282) (xy 94.082473 -365.365621)
			(xy 93.980409 -365.309785) (xy 93.88244 -365.247042) (xy 93.789033 -365.177688) (xy 93.700633 -365.102056)
			(xy 93.617662 -365.020505) (xy 93.540515 -364.933424) (xy 93.46956 -364.841228) (xy 93.405134 -364.744356)
			(xy 93.347545 -364.643271) (xy 93.297068 -364.538453) (xy 93.253942 -364.430402) (xy 93.218373 -364.319634)
			(xy 93.190531 -364.206675) (xy 93.170549 -364.092065) (xy 93.158522 -363.97635) (xy 93.154506 -363.86008)
			(xy 91.165664 -363.86008) (xy 91.216772 -363.9048) (xy 91.268196 -363.960504) (xy 91.313407 -364.021359)
			(xy 91.351894 -364.086674) (xy 91.38322 -364.15571) (xy 91.40703 -364.227685) (xy 91.423055 -364.301783)
			(xy 91.431114 -364.377164) (xy 91.431618 -364.41507) (xy 91.431114 -364.452976) (xy 91.423055 -364.528357)
			(xy 91.40703 -364.602455) (xy 91.38322 -364.67443) (xy 91.351894 -364.743466) (xy 91.313407 -364.808781)
			(xy 91.268196 -364.869636) (xy 91.216772 -364.92534) (xy 91.159719 -364.975262) (xy 91.097683 -365.018837)
			(xy 91.031366 -365.055572) (xy 90.96152 -365.085049) (xy 90.888937 -365.106935) (xy 90.814439 -365.120982)
			(xy 90.738869 -365.127031) (xy 90.663085 -365.125012) (xy 90.587945 -365.11495) (xy 90.5143 -365.096958)
			(xy 90.442984 -365.07124) (xy 90.374807 -365.038088) (xy 90.310539 -364.997876) (xy 90.25091 -364.951061)
			(xy 90.196594 -364.898173) (xy 90.148208 -364.839811) (xy 90.1063 -364.776636) (xy 90.071344 -364.709365)
			(xy 90.043737 -364.63876) (xy 90.023791 -364.565619) (xy 90.011732 -364.490774) (xy 90.007697 -364.41507)
			(xy 88.891618 -364.41507) (xy 88.891114 -364.452976) (xy 88.883055 -364.528357) (xy 88.86703 -364.602455)
			(xy 88.84322 -364.67443) (xy 88.811894 -364.743466) (xy 88.773407 -364.808781) (xy 88.728196 -364.869636)
			(xy 88.676772 -364.92534) (xy 88.619719 -364.975262) (xy 88.557683 -365.018837) (xy 88.491366 -365.055572)
			(xy 88.42152 -365.085049) (xy 88.348937 -365.106935) (xy 88.274439 -365.120982) (xy 88.198869 -365.127031)
			(xy 88.123085 -365.125012) (xy 88.047945 -365.11495) (xy 87.9743 -365.096958) (xy 87.902984 -365.07124)
			(xy 87.834807 -365.038088) (xy 87.770539 -364.997876) (xy 87.71091 -364.951061) (xy 87.656594 -364.898173)
			(xy 87.608208 -364.839811) (xy 87.5663 -364.776636) (xy 87.531344 -364.709365) (xy 87.503737 -364.63876)
			(xy 87.483791 -364.565619) (xy 87.471732 -364.490774) (xy 87.467697 -364.41507) (xy 86.351618 -364.41507)
			(xy 86.351114 -364.452976) (xy 86.343055 -364.528357) (xy 86.32703 -364.602455) (xy 86.30322 -364.67443)
			(xy 86.271894 -364.743466) (xy 86.233407 -364.808781) (xy 86.188196 -364.869636) (xy 86.136772 -364.92534)
			(xy 86.079719 -364.975262) (xy 86.017683 -365.018837) (xy 85.951366 -365.055572) (xy 85.88152 -365.085049)
			(xy 85.808937 -365.106935) (xy 85.734439 -365.120982) (xy 85.658869 -365.127031) (xy 85.583085 -365.125012)
			(xy 85.507945 -365.11495) (xy 85.4343 -365.096958) (xy 85.362984 -365.07124) (xy 85.294807 -365.038088)
			(xy 85.230539 -364.997876) (xy 85.17091 -364.951061) (xy 85.116594 -364.898173) (xy 85.068208 -364.839811)
			(xy 85.0263 -364.776636) (xy 84.991344 -364.709365) (xy 84.963737 -364.63876) (xy 84.943791 -364.565619)
			(xy 84.931732 -364.490774) (xy 84.927697 -364.41507) (xy 62.265544 -364.41507) (xy 62.259599 -364.420272)
			(xy 62.197563 -364.463847) (xy 62.131246 -364.500582) (xy 62.0614 -364.530059) (xy 61.988817 -364.551945)
			(xy 61.914319 -364.565992) (xy 61.838749 -364.572041) (xy 61.762965 -364.570022) (xy 61.687825 -364.55996)
			(xy 61.61418 -364.541968) (xy 61.542864 -364.51625) (xy 61.474687 -364.483098) (xy 61.410419 -364.442886)
			(xy 61.35079 -364.396071) (xy 61.296474 -364.343183) (xy 61.248088 -364.284821) (xy 61.20618 -364.221646)
			(xy 61.171224 -364.154375) (xy 61.143617 -364.08377) (xy 61.123671 -364.010629) (xy 61.111612 -363.935784)
			(xy 61.107577 -363.86008) (xy 59.991498 -363.86008) (xy 59.990994 -363.897986) (xy 59.982935 -363.973367)
			(xy 59.96691 -364.047465) (xy 59.9431 -364.11944) (xy 59.911774 -364.188476) (xy 59.873287 -364.253791)
			(xy 59.828076 -364.314646) (xy 59.776652 -364.37035) (xy 59.719599 -364.420272) (xy 59.657563 -364.463847)
			(xy 59.591246 -364.500582) (xy 59.5214 -364.530059) (xy 59.448817 -364.551945) (xy 59.374319 -364.565992)
			(xy 59.298749 -364.572041) (xy 59.222965 -364.570022) (xy 59.147825 -364.55996) (xy 59.07418 -364.541968)
			(xy 59.002864 -364.51625) (xy 58.934687 -364.483098) (xy 58.870419 -364.442886) (xy 58.81079 -364.396071)
			(xy 58.756474 -364.343183) (xy 58.708088 -364.284821) (xy 58.66618 -364.221646) (xy 58.631224 -364.154375)
			(xy 58.603617 -364.08377) (xy 58.583671 -364.010629) (xy 58.571612 -363.935784) (xy 58.567577 -363.86008)
			(xy 57.451498 -363.86008) (xy 57.450994 -363.897986) (xy 57.442935 -363.973367) (xy 57.42691 -364.047465)
			(xy 57.4031 -364.11944) (xy 57.371774 -364.188476) (xy 57.333287 -364.253791) (xy 57.288076 -364.314646)
			(xy 57.236652 -364.37035) (xy 57.179599 -364.420272) (xy 57.117563 -364.463847) (xy 57.051246 -364.500582)
			(xy 56.9814 -364.530059) (xy 56.908817 -364.551945) (xy 56.834319 -364.565992) (xy 56.758749 -364.572041)
			(xy 56.682965 -364.570022) (xy 56.607825 -364.55996) (xy 56.53418 -364.541968) (xy 56.462864 -364.51625)
			(xy 56.394687 -364.483098) (xy 56.330419 -364.442886) (xy 56.27079 -364.396071) (xy 56.216474 -364.343183)
			(xy 56.168088 -364.284821) (xy 56.12618 -364.221646) (xy 56.091224 -364.154375) (xy 56.063617 -364.08377)
			(xy 56.043671 -364.010629) (xy 56.031612 -363.935784) (xy 56.027577 -363.86008) (xy 54.911498 -363.86008)
			(xy 54.910994 -363.897986) (xy 54.902935 -363.973367) (xy 54.88691 -364.047465) (xy 54.8631 -364.11944)
			(xy 54.831774 -364.188476) (xy 54.793287 -364.253791) (xy 54.748076 -364.314646) (xy 54.696652 -364.37035)
			(xy 54.639599 -364.420272) (xy 54.577563 -364.463847) (xy 54.511246 -364.500582) (xy 54.4414 -364.530059)
			(xy 54.368817 -364.551945) (xy 54.294319 -364.565992) (xy 54.218749 -364.572041) (xy 54.142965 -364.570022)
			(xy 54.067825 -364.55996) (xy 53.99418 -364.541968) (xy 53.922864 -364.51625) (xy 53.854687 -364.483098)
			(xy 53.790419 -364.442886) (xy 53.73079 -364.396071) (xy 53.676474 -364.343183) (xy 53.628088 -364.284821)
			(xy 53.58618 -364.221646) (xy 53.551224 -364.154375) (xy 53.523617 -364.08377) (xy 53.503671 -364.010629)
			(xy 53.491612 -363.935784) (xy 53.487577 -363.86008) (xy 52.371498 -363.86008) (xy 52.370994 -363.897986)
			(xy 52.362935 -363.973367) (xy 52.34691 -364.047465) (xy 52.3231 -364.11944) (xy 52.291774 -364.188476)
			(xy 52.253287 -364.253791) (xy 52.208076 -364.314646) (xy 52.156652 -364.37035) (xy 52.099599 -364.420272)
			(xy 52.037563 -364.463847) (xy 51.971246 -364.500582) (xy 51.9014 -364.530059) (xy 51.828817 -364.551945)
			(xy 51.754319 -364.565992) (xy 51.678749 -364.572041) (xy 51.602965 -364.570022) (xy 51.527825 -364.55996)
			(xy 51.45418 -364.541968) (xy 51.382864 -364.51625) (xy 51.314687 -364.483098) (xy 51.250419 -364.442886)
			(xy 51.19079 -364.396071) (xy 51.136474 -364.343183) (xy 51.088088 -364.284821) (xy 51.04618 -364.221646)
			(xy 51.011224 -364.154375) (xy 50.983617 -364.08377) (xy 50.963671 -364.010629) (xy 50.951612 -363.935784)
			(xy 50.947577 -363.86008) (xy 49.831498 -363.86008) (xy 49.830994 -363.897986) (xy 49.822935 -363.973367)
			(xy 49.80691 -364.047465) (xy 49.7831 -364.11944) (xy 49.751774 -364.188476) (xy 49.713287 -364.253791)
			(xy 49.668076 -364.314646) (xy 49.616652 -364.37035) (xy 49.559599 -364.420272) (xy 49.497563 -364.463847)
			(xy 49.431246 -364.500582) (xy 49.3614 -364.530059) (xy 49.288817 -364.551945) (xy 49.214319 -364.565992)
			(xy 49.138749 -364.572041) (xy 49.062965 -364.570022) (xy 48.987825 -364.55996) (xy 48.91418 -364.541968)
			(xy 48.842864 -364.51625) (xy 48.774687 -364.483098) (xy 48.710419 -364.442886) (xy 48.65079 -364.396071)
			(xy 48.596474 -364.343183) (xy 48.548088 -364.284821) (xy 48.50618 -364.221646) (xy 48.471224 -364.154375)
			(xy 48.443617 -364.08377) (xy 48.423671 -364.010629) (xy 48.411612 -363.935784) (xy 48.407577 -363.86008)
			(xy 47.291498 -363.86008) (xy 47.290994 -363.897986) (xy 47.282935 -363.973367) (xy 47.26691 -364.047465)
			(xy 47.2431 -364.11944) (xy 47.211774 -364.188476) (xy 47.173287 -364.253791) (xy 47.128076 -364.314646)
			(xy 47.076652 -364.37035) (xy 47.019599 -364.420272) (xy 46.957563 -364.463847) (xy 46.891246 -364.500582)
			(xy 46.8214 -364.530059) (xy 46.748817 -364.551945) (xy 46.674319 -364.565992) (xy 46.598749 -364.572041)
			(xy 46.522965 -364.570022) (xy 46.447825 -364.55996) (xy 46.37418 -364.541968) (xy 46.302864 -364.51625)
			(xy 46.234687 -364.483098) (xy 46.170419 -364.442886) (xy 46.11079 -364.396071) (xy 46.056474 -364.343183)
			(xy 46.008088 -364.284821) (xy 45.96618 -364.221646) (xy 45.931224 -364.154375) (xy 45.903617 -364.08377)
			(xy 45.883671 -364.010629) (xy 45.871612 -363.935784) (xy 45.867577 -363.86008) (xy 44.751244 -363.86008)
			(xy 44.751244 -364.571788) (xy 43.328336 -364.571788) (xy 43.328336 -363.148372) (xy 43.055152 -363.148372)
			(xy 43.014974 -363.239744) (xy 42.961022 -363.34254) (xy 42.900108 -363.441368) (xy 42.83252 -363.535759)
			(xy 42.758581 -363.625261) (xy 42.678643 -363.709449) (xy 42.593088 -363.787922) (xy 42.502322 -363.860305)
			(xy 42.406779 -363.926254) (xy 42.306914 -363.985454) (xy 42.203202 -364.037623) (xy 42.096139 -364.082512)
			(xy 41.986233 -364.119908) (xy 41.874009 -364.149633) (xy 41.760003 -364.171544) (xy 41.644756 -364.185537)
			(xy 41.528818 -364.191546) (xy 41.412742 -364.189543) (xy 41.29708 -364.179535) (xy 41.182385 -364.161572)
			(xy 41.069202 -364.135739) (xy 40.958071 -364.102159) (xy 40.849522 -364.060991) (xy 40.744072 -364.012433)
			(xy 40.642223 -363.956716) (xy 40.54446 -363.894104) (xy 40.45125 -363.824897) (xy 40.363037 -363.749424)
			(xy 40.280241 -363.668045) (xy 40.203257 -363.581148) (xy 40.132452 -363.489147) (xy 40.068162 -363.39248)
			(xy 40.010695 -363.291608) (xy 39.960324 -363.187011) (xy 39.917289 -363.079188) (xy 39.881795 -362.968654)
			(xy 39.854012 -362.855934) (xy 39.834072 -362.741566) (xy 39.82207 -362.626094) (xy 39.818063 -362.51007)
			(xy 36.092815 -362.51007) (xy 36.140713 -362.546241) (xy 36.204933 -362.604785) (xy 36.263477 -362.669005)
			(xy 36.315846 -362.738352) (xy 36.361593 -362.812236) (xy 36.400327 -362.890025) (xy 36.431719 -362.971057)
			(xy 36.4555 -363.054639) (xy 36.471468 -363.140059) (xy 36.479486 -363.226588) (xy 36.479988 -363.270038)
			(xy 36.479486 -363.313488) (xy 36.471468 -363.400017) (xy 36.4555 -363.485437) (xy 36.431719 -363.569019)
			(xy 36.400327 -363.650051) (xy 36.361593 -363.72784) (xy 36.315846 -363.801724) (xy 36.263477 -363.871071)
			(xy 36.204933 -363.935291) (xy 36.140713 -363.993835) (xy 36.071366 -364.046204) (xy 35.997482 -364.091951)
			(xy 35.919693 -364.130685) (xy 35.838661 -364.162077) (xy 35.755079 -364.185858) (xy 35.669659 -364.201826)
			(xy 35.58313 -364.209844) (xy 35.49623 -364.209844) (xy 35.409701 -364.201826) (xy 35.324281 -364.185858)
			(xy 35.240699 -364.162077) (xy 35.159667 -364.130685) (xy 35.081878 -364.091951) (xy 35.007994 -364.046204)
			(xy 34.938647 -363.993835) (xy 34.874427 -363.935291) (xy 34.815883 -363.871071) (xy 34.763514 -363.801724)
			(xy 34.717767 -363.72784) (xy 34.679033 -363.650051) (xy 34.647641 -363.569019) (xy 34.62386 -363.485437)
			(xy 34.607892 -363.400017) (xy 34.599874 -363.313488) (xy 34.1757 -363.313488) (xy 34.1757 -363.845856)
			(xy 35.2171 -364.887256) (xy 35.281616 -364.90529) (xy 35.313874 -364.897162) (xy 35.3554 -364.887381)
			(xy 35.439739 -364.874476) (xy 35.524899 -364.869266) (xy 35.610182 -364.871794) (xy 35.694884 -364.882039)
			(xy 35.77831 -364.899917) (xy 35.859773 -364.92528) (xy 35.938603 -364.95792) (xy 36.01415 -364.997569)
			(xy 36.05022 -365.020352) (xy 38.33876 -365.020352) (xy 42.127932 -368.809524) (xy 42.127932 -372.81104)
			(xy 68.130928 -372.81104) (xy 68.130928 -371.846348) (xy 68.131622 -371.810282) (xy 68.141943 -371.738891)
			(xy 68.151502 -371.704108) (xy 68.156328 -371.686582) (xy 68.156328 -371.31244) (xy 69.122544 -371.31244)
			(xy 69.122544 -371.686582) (xy 69.12737 -371.704108) (xy 69.136908 -371.738896) (xy 69.147238 -371.810284)
			(xy 69.147944 -371.846348) (xy 69.147944 -371.96649) (xy 69.47408 -371.96649) (xy 69.47408 -371.001798)
			(xy 69.474577 -370.969072) (xy 69.482972 -370.904159) (xy 69.499623 -370.84086) (xy 69.524255 -370.780219)
			(xy 69.556461 -370.723238) (xy 69.57568 -370.696744) (xy 69.60108 -370.662962) (xy 69.60108 -370.645944)
			(xy 69.61632 -370.645944) (xy 69.652134 -370.615464) (xy 69.677311 -370.594611) (xy 69.732043 -370.55886)
			(xy 69.790908 -370.530421) (xy 69.852933 -370.509766) (xy 69.917095 -370.497235) (xy 69.982334 -370.493035)
			(xy 70.047573 -370.497235) (xy 70.111735 -370.509766) (xy 70.17376 -370.530421) (xy 70.232625 -370.55886)
			(xy 70.287357 -370.594611) (xy 70.312534 -370.615464) (xy 70.348348 -370.645944) (xy 70.363588 -370.645944)
			(xy 70.363588 -370.662962) (xy 70.388988 -370.696744) (xy 70.402323 -370.714911) (xy 70.426107 -370.753194)
			(xy 70.436486 -370.773198) (xy 70.443926 -370.786908) (xy 70.464329 -370.810491) (xy 70.489844 -370.828421)
			(xy 70.518946 -370.839625) (xy 70.549897 -370.843436) (xy 70.580848 -370.839625) (xy 70.60995 -370.828421)
			(xy 70.635465 -370.810491) (xy 70.655868 -370.786908) (xy 70.663308 -370.773198) (xy 70.673667 -370.753183)
			(xy 70.697455 -370.714901) (xy 70.710806 -370.696744) (xy 70.735952 -370.662962) (xy 70.735952 -370.645944)
			(xy 70.751446 -370.645944) (xy 70.78726 -370.615464) (xy 70.812437 -370.594611) (xy 70.867169 -370.55886)
			(xy 70.926034 -370.530421) (xy 70.988059 -370.509766) (xy 71.052221 -370.497235) (xy 71.11746 -370.493035)
			(xy 71.182699 -370.497235) (xy 71.246861 -370.509766) (xy 71.308886 -370.530421) (xy 71.367751 -370.55886)
			(xy 71.422483 -370.594611) (xy 71.44766 -370.615464) (xy 71.483474 -370.645944) (xy 71.498968 -370.645944)
			(xy 71.498968 -370.662962) (xy 71.524114 -370.696744) (xy 71.543335 -370.723246) (xy 71.575604 -370.780209)
			(xy 71.600295 -370.840842) (xy 71.616999 -370.904143) (xy 71.62544 -370.969064) (xy 71.625968 -371.001798)
			(xy 71.625968 -371.96649) (xy 71.625462 -371.99875) (xy 71.617276 -372.062748) (xy 71.60106 -372.125197)
			(xy 71.577074 -372.185093) (xy 71.545703 -372.241473) (xy 71.507453 -372.293432) (xy 71.462936 -372.340134)
			(xy 71.412869 -372.38083) (xy 71.358057 -372.414865) (xy 71.299379 -372.441693) (xy 71.237778 -372.460882)
			(xy 71.174245 -372.472124) (xy 71.109801 -372.475239) (xy 71.04548 -372.470176) (xy 70.982316 -372.457017)
			(xy 70.921324 -372.435974) (xy 70.863485 -372.407383) (xy 70.809727 -372.371706) (xy 70.760914 -372.329514)
			(xy 70.739 -372.305834) (xy 70.722776 -372.288517) (xy 70.685107 -372.259666) (xy 70.642737 -372.238311)
			(xy 70.597138 -372.225193) (xy 70.549897 -372.220769) (xy 70.502656 -372.225193) (xy 70.457057 -372.238311)
			(xy 70.414687 -372.259666) (xy 70.377018 -372.288517) (xy 70.360794 -372.305834) (xy 70.338929 -372.329555)
			(xy 70.290125 -372.371749) (xy 70.236375 -372.407429) (xy 70.178541 -372.436021) (xy 70.117555 -372.457066)
			(xy 70.054396 -372.470224) (xy 69.99008 -372.475286) (xy 69.92564 -372.472168) (xy 69.862113 -372.460922)
			(xy 69.800519 -372.441727) (xy 69.741849 -372.414894) (xy 69.687046 -372.380852) (xy 69.636991 -372.34015)
			(xy 69.592488 -372.293441) (xy 69.554254 -372.241477) (xy 69.522901 -372.185092) (xy 69.498935 -372.125194)
			(xy 69.482741 -372.062744) (xy 69.474579 -371.998748) (xy 69.47408 -371.96649) (xy 69.147944 -371.96649)
			(xy 69.147944 -372.81104) (xy 69.147442 -372.843001) (xy 69.139431 -372.906419) (xy 69.123534 -372.968333)
			(xy 69.100002 -373.027766) (xy 69.069208 -373.083781) (xy 69.031635 -373.135496) (xy 68.987878 -373.182093)
			(xy 68.938625 -373.222838) (xy 68.884654 -373.257089) (xy 68.826815 -373.284306) (xy 68.766022 -373.304059)
			(xy 68.703232 -373.316037) (xy 68.639436 -373.320051) (xy 68.57564 -373.316037) (xy 68.51285 -373.304059)
			(xy 68.452057 -373.284306) (xy 68.394218 -373.257089) (xy 68.340247 -373.222838) (xy 68.290994 -373.182093)
			(xy 68.247237 -373.135496) (xy 68.209664 -373.083781) (xy 68.17887 -373.027766) (xy 68.155338 -372.968333)
			(xy 68.139441 -372.906419) (xy 68.13143 -372.843001) (xy 68.130928 -372.81104) (xy 42.127932 -372.81104)
			(xy 42.127932 -374.477703) (xy 47.298092 -374.477703) (xy 47.298092 -374.396593) (xy 47.306042 -374.315874)
			(xy 47.321865 -374.236323) (xy 47.34541 -374.158707) (xy 47.376449 -374.083771) (xy 47.414684 -374.012239)
			(xy 47.459746 -373.944799) (xy 47.511201 -373.8821) (xy 47.568554 -373.824747) (xy 47.631253 -373.773292)
			(xy 47.698693 -373.72823) (xy 47.770225 -373.689995) (xy 47.845161 -373.658956) (xy 47.922777 -373.635411)
			(xy 48.002328 -373.619588) (xy 48.083047 -373.611638) (xy 48.164157 -373.611638) (xy 48.244876 -373.619588)
			(xy 48.324427 -373.635411) (xy 48.402043 -373.658956) (xy 48.476979 -373.689995) (xy 48.548511 -373.72823)
			(xy 48.615951 -373.773292) (xy 48.67865 -373.824747) (xy 48.736003 -373.8821) (xy 48.787458 -373.944799)
			(xy 48.83252 -374.012239) (xy 48.870755 -374.083771) (xy 48.901794 -374.158707) (xy 48.925339 -374.236323)
			(xy 48.941162 -374.315874) (xy 48.949112 -374.396593) (xy 48.94961 -374.437148) (xy 48.949112 -374.477703)
			(xy 48.941162 -374.558422) (xy 48.925339 -374.637973) (xy 48.901794 -374.715589) (xy 48.870755 -374.790525)
			(xy 48.83252 -374.862057) (xy 48.787458 -374.929497) (xy 48.736003 -374.992196) (xy 48.67865 -375.049549)
			(xy 48.615951 -375.101004) (xy 48.548511 -375.146066) (xy 48.476979 -375.184301) (xy 48.402043 -375.21534)
			(xy 48.324427 -375.238885) (xy 48.244876 -375.254708) (xy 48.164157 -375.262658) (xy 48.083047 -375.262658)
			(xy 48.002328 -375.254708) (xy 47.922777 -375.238885) (xy 47.845161 -375.21534) (xy 47.770225 -375.184301)
			(xy 47.698693 -375.146066) (xy 47.631253 -375.101004) (xy 47.568554 -375.049549) (xy 47.511201 -374.992196)
			(xy 47.459746 -374.929497) (xy 47.414684 -374.862057) (xy 47.376449 -374.790525) (xy 47.34541 -374.715589)
			(xy 47.321865 -374.637973) (xy 47.306042 -374.558422) (xy 47.298092 -374.477703) (xy 42.127932 -374.477703)
			(xy 42.127932 -374.804178) (xy 41.32199 -375.61012) (xy 86.39887 -375.61012) (xy 86.402874 -375.410022)
			(xy 86.414881 -375.210244) (xy 86.434872 -375.011107) (xy 86.462814 -374.812929) (xy 86.498662 -374.616027)
			(xy 86.54236 -374.420718) (xy 86.593837 -374.227313) (xy 86.653011 -374.036123) (xy 86.719787 -373.847453)
			(xy 86.794059 -373.661606) (xy 86.875706 -373.478879) (xy 86.964599 -373.299566) (xy 87.060595 -373.123952)
			(xy 87.16354 -372.95232) (xy 87.27327 -372.784944) (xy 87.389608 -372.622093) (xy 87.512369 -372.464026)
			(xy 87.641356 -372.310998) (xy 87.776363 -372.163253) (xy 87.917172 -372.021027) (xy 88.063559 -371.88455)
			(xy 88.215289 -371.754038) (xy 88.37212 -371.629702) (xy 88.533799 -371.51174) (xy 88.700069 -371.400341)
			(xy 88.870662 -371.295684) (xy 89.045306 -371.197936) (xy 89.223722 -371.107253) (xy 89.405622 -371.023782)
			(xy 89.590717 -370.947655) (xy 89.778709 -370.878995) (xy 89.969298 -370.817911) (xy 90.162178 -370.764501)
			(xy 90.35704 -370.718852) (xy 90.553573 -370.681035) (xy 90.751462 -370.651111) (xy 90.950389 -370.629129)
			(xy 91.150037 -370.615124) (xy 91.350085 -370.609118) (xy 91.550213 -370.61112) (xy 91.750101 -370.621128)
			(xy 91.949428 -370.639125) (xy 92.147876 -370.665083) (xy 92.345126 -370.69896) (xy 92.540863 -370.740702)
			(xy 92.734773 -370.790241) (xy 92.926546 -370.847499) (xy 93.115875 -370.912384) (xy 93.302455 -370.984792)
			(xy 93.48599 -371.064608) (xy 93.666184 -371.151702) (xy 93.842749 -371.245936) (xy 94.015402 -371.347159)
			(xy 94.183867 -371.455209) (xy 94.347875 -371.569912) (xy 94.507162 -371.691086) (xy 94.661473 -371.818535)
			(xy 94.810561 -371.952056) (xy 94.954188 -372.091436) (xy 95.092124 -372.23645) (xy 95.224147 -372.386867)
			(xy 95.350046 -372.542445) (xy 95.46962 -372.702937) (xy 95.582676 -372.868083) (xy 95.689035 -373.037621)
			(xy 95.788526 -373.211279) (xy 95.880989 -373.388778) (xy 95.966276 -373.569834) (xy 96.044251 -373.754158)
			(xy 96.114788 -373.941454) (xy 96.177776 -374.131422) (xy 96.233113 -374.323758) (xy 96.28071 -374.518154)
			(xy 96.320491 -374.714299) (xy 96.352393 -374.911878) (xy 96.376364 -375.110575) (xy 96.392366 -375.310073)
			(xy 96.400373 -375.510051) (xy 96.400874 -375.61012) (xy 96.400373 -375.710189) (xy 96.392366 -375.910167)
			(xy 96.376364 -376.109665) (xy 96.352393 -376.308362) (xy 96.320491 -376.505941) (xy 96.28071 -376.702086)
			(xy 96.233113 -376.896482) (xy 96.177776 -377.088818) (xy 96.114788 -377.278786) (xy 96.044251 -377.466082)
			(xy 95.966276 -377.650406) (xy 95.880989 -377.831462) (xy 95.788526 -378.008961) (xy 95.689035 -378.182619)
			(xy 95.582676 -378.352157) (xy 95.46962 -378.517303) (xy 95.350046 -378.677795) (xy 95.224147 -378.833373)
			(xy 95.092124 -378.98379) (xy 94.954188 -379.128804) (xy 94.810561 -379.268184) (xy 94.661473 -379.401705)
			(xy 94.507162 -379.529154) (xy 94.347875 -379.650328) (xy 94.183867 -379.765031) (xy 94.015402 -379.873081)
			(xy 93.842749 -379.974304) (xy 93.666184 -380.068538) (xy 93.48599 -380.155632) (xy 93.302455 -380.235448)
			(xy 93.115875 -380.307856) (xy 92.926546 -380.372741) (xy 92.734773 -380.429999) (xy 92.540863 -380.479538)
			(xy 92.345126 -380.52128) (xy 92.147876 -380.555157) (xy 91.949428 -380.581115) (xy 91.750101 -380.599112)
			(xy 91.550213 -380.60912) (xy 91.350085 -380.611122) (xy 91.150037 -380.605116) (xy 90.950389 -380.591111)
			(xy 90.751462 -380.569129) (xy 90.553573 -380.539205) (xy 90.35704 -380.501388) (xy 90.162178 -380.455739)
			(xy 89.969298 -380.402329) (xy 89.778709 -380.341245) (xy 89.590717 -380.272585) (xy 89.405622 -380.196458)
			(xy 89.223722 -380.112987) (xy 89.045306 -380.022304) (xy 88.870662 -379.924556) (xy 88.700069 -379.819899)
			(xy 88.533799 -379.7085) (xy 88.37212 -379.590538) (xy 88.215289 -379.466202) (xy 88.063559 -379.33569)
			(xy 87.917172 -379.199213) (xy 87.776363 -379.056987) (xy 87.641356 -378.909242) (xy 87.512369 -378.756214)
			(xy 87.389608 -378.598147) (xy 87.27327 -378.435296) (xy 87.16354 -378.26792) (xy 87.060595 -378.096288)
			(xy 86.964599 -377.920674) (xy 86.875706 -377.741361) (xy 86.794059 -377.558634) (xy 86.719787 -377.372787)
			(xy 86.653011 -377.184117) (xy 86.593837 -376.992927) (xy 86.54236 -376.799522) (xy 86.498662 -376.604213)
			(xy 86.462814 -376.407311) (xy 86.434872 -376.209133) (xy 86.414881 -376.009996) (xy 86.402874 -375.810218)
			(xy 86.39887 -375.61012) (xy 41.32199 -375.61012) (xy 41.27373 -375.65838) (xy 40.556942 -375.65838)
			(xy 40.528383 -375.665021) (xy 40.470182 -375.672153) (xy 40.440864 -375.672604) (xy 40.179244 -375.672604)
			(xy 40.108886 -375.742962) (xy 40.108886 -376.210068) (xy 40.202358 -376.30354) (xy 40.789606 -376.30354)
			(xy 41.020746 -376.53468) (xy 41.020746 -377.077224) (xy 40.785034 -377.312936) (xy 35.293046 -377.312936)
			(xy 35.230308 -377.375674) (xy 35.218848 -377.387807) (xy 35.20214 -377.416687) (xy 35.19349 -377.448911)
			(xy 35.193488 -377.482275) (xy 35.202135 -377.5145) (xy 35.21884 -377.543381) (xy 35.230308 -377.555506)
			(xy 35.252914 -377.578112) (xy 35.314636 -377.5964) (xy 35.346132 -377.589796) (xy 35.388995 -377.581291)
			(xy 35.475815 -377.571318) (xy 35.563186 -377.569443) (xy 35.650354 -377.575683) (xy 35.736567 -377.589984)
			(xy 35.821082 -377.612222) (xy 35.903168 -377.642204) (xy 35.982119 -377.679674) (xy 36.057253 -377.724307)
			(xy 36.127922 -377.775719) (xy 36.193516 -377.833465) (xy 36.253469 -377.897048) (xy 36.307264 -377.96592)
			(xy 36.354438 -378.039485) (xy 36.394582 -378.11711) (xy 36.427352 -378.198125) (xy 36.452463 -378.28183)
			(xy 36.4697 -378.367504) (xy 36.478914 -378.454408) (xy 36.480025 -378.541793) (xy 36.473024 -378.628903)
			(xy 36.457971 -378.714988) (xy 36.434996 -378.799305) (xy 36.404297 -378.881126) (xy 36.366139 -378.959747)
			(xy 36.320851 -379.034488) (xy 36.268824 -379.104705) (xy 36.210507 -379.169791) (xy 36.146402 -379.229187)
			(xy 36.077064 -379.282379) (xy 36.003089 -379.328908) (xy 35.925116 -379.368373) (xy 35.843818 -379.400433)
			(xy 35.759897 -379.424812) (xy 35.674075 -379.4413) (xy 35.587094 -379.449754) (xy 35.499703 -379.450102)
			(xy 35.412658 -379.44234) (xy 35.326707 -379.426535) (xy 35.242594 -379.402824) (xy 35.161044 -379.371412)
			(xy 35.08276 -379.332568) (xy 35.008417 -379.286629) (xy 34.938658 -379.233991) (xy 34.874083 -379.175107)
			(xy 34.81525 -379.110486) (xy 34.762666 -379.040686) (xy 34.716785 -378.966307) (xy 34.678003 -378.887993)
			(xy 34.646654 -378.806418) (xy 34.623009 -378.722286) (xy 34.607271 -378.636324) (xy 34.602928 -378.592842)
			(xy 34.600496 -378.570806) (xy 34.588986 -378.527996) (xy 34.57022 -378.487834) (xy 34.544767 -378.45154)
			(xy 34.5134 -378.420215) (xy 34.477072 -378.39481) (xy 34.436885 -378.376098) (xy 34.39406 -378.364645)
			(xy 34.349897 -378.360801) (xy 34.305738 -378.364681) (xy 34.262922 -378.376168) (xy 34.22275 -378.394913)
			(xy 34.186442 -378.420346) (xy 34.170366 -378.435616) (xy 31.512494 -381.093488) (xy 34.599874 -381.093488)
			(xy 34.599874 -381.006588) (xy 34.607892 -380.920059) (xy 34.62386 -380.834639) (xy 34.647641 -380.751057)
			(xy 34.679033 -380.670025) (xy 34.717767 -380.592236) (xy 34.763514 -380.518352) (xy 34.815883 -380.449005)
			(xy 34.874427 -380.384785) (xy 34.938647 -380.326241) (xy 35.007994 -380.273872) (xy 35.081878 -380.228125)
			(xy 35.159667 -380.189391) (xy 35.240699 -380.157999) (xy 35.324281 -380.134218) (xy 35.409701 -380.11825)
			(xy 35.49623 -380.110232) (xy 35.58313 -380.110232) (xy 35.669659 -380.11825) (xy 35.755079 -380.134218)
			(xy 35.838661 -380.157999) (xy 35.919693 -380.189391) (xy 35.997482 -380.228125) (xy 36.071366 -380.273872)
			(xy 36.140713 -380.326241) (xy 36.204933 -380.384785) (xy 36.263477 -380.449005) (xy 36.315846 -380.518352)
			(xy 36.361593 -380.592236) (xy 36.400327 -380.670025) (xy 36.431719 -380.751057) (xy 36.4555 -380.834639)
			(xy 36.45609 -380.837795) (xy 38.508678 -380.837795) (xy 38.508678 -380.766473) (xy 38.516664 -380.695599)
			(xy 38.532534 -380.626064) (xy 38.556091 -380.558744) (xy 38.587036 -380.494485) (xy 38.624982 -380.434094)
			(xy 38.669451 -380.378332) (xy 38.719884 -380.327899) (xy 38.775646 -380.28343) (xy 38.836037 -380.245484)
			(xy 38.900296 -380.214539) (xy 38.967616 -380.190982) (xy 39.037151 -380.175112) (xy 39.108025 -380.167126)
			(xy 39.179347 -380.167126) (xy 39.250221 -380.175112) (xy 39.319756 -380.190982) (xy 39.387076 -380.214539)
			(xy 39.451335 -380.245484) (xy 39.511726 -380.28343) (xy 39.567488 -380.327899) (xy 39.617921 -380.378332)
			(xy 39.66239 -380.434094) (xy 39.700336 -380.494485) (xy 39.731281 -380.558744) (xy 39.754838 -380.626064)
			(xy 39.770708 -380.695599) (xy 39.778694 -380.766473) (xy 39.779194 -380.802134) (xy 39.778694 -380.837795)
			(xy 40.39539 -380.837795) (xy 40.39539 -380.766473) (xy 40.403376 -380.695599) (xy 40.419246 -380.626064)
			(xy 40.442803 -380.558744) (xy 40.473748 -380.494485) (xy 40.511694 -380.434094) (xy 40.556163 -380.378332)
			(xy 40.606596 -380.327899) (xy 40.662358 -380.28343) (xy 40.722749 -380.245484) (xy 40.787008 -380.214539)
			(xy 40.854328 -380.190982) (xy 40.923863 -380.175112) (xy 40.994737 -380.167126) (xy 41.066059 -380.167126)
			(xy 41.136933 -380.175112) (xy 41.206468 -380.190982) (xy 41.273788 -380.214539) (xy 41.338047 -380.245484)
			(xy 41.398438 -380.28343) (xy 41.4542 -380.327899) (xy 41.504633 -380.378332) (xy 41.549102 -380.434094)
			(xy 41.587048 -380.494485) (xy 41.617993 -380.558744) (xy 41.64155 -380.626064) (xy 41.65742 -380.695599)
			(xy 41.665406 -380.766473) (xy 41.665906 -380.802134) (xy 41.665406 -380.837795) (xy 41.65742 -380.908669)
			(xy 41.64155 -380.978204) (xy 41.617993 -381.045524) (xy 41.587048 -381.109783) (xy 41.549102 -381.170174)
			(xy 41.504633 -381.225936) (xy 41.4542 -381.276369) (xy 41.398438 -381.320838) (xy 41.338047 -381.358784)
			(xy 41.273788 -381.389729) (xy 41.206468 -381.413286) (xy 41.136933 -381.429156) (xy 41.066059 -381.437142)
			(xy 40.994737 -381.437142) (xy 40.923863 -381.429156) (xy 40.854328 -381.413286) (xy 40.787008 -381.389729)
			(xy 40.722749 -381.358784) (xy 40.662358 -381.320838) (xy 40.606596 -381.276369) (xy 40.556163 -381.225936)
			(xy 40.511694 -381.170174) (xy 40.473748 -381.109783) (xy 40.442803 -381.045524) (xy 40.419246 -380.978204)
			(xy 40.403376 -380.908669) (xy 40.39539 -380.837795) (xy 39.778694 -380.837795) (xy 39.770708 -380.908669)
			(xy 39.754838 -380.978204) (xy 39.731281 -381.045524) (xy 39.700336 -381.109783) (xy 39.66239 -381.170174)
			(xy 39.617921 -381.225936) (xy 39.567488 -381.276369) (xy 39.511726 -381.320838) (xy 39.451335 -381.358784)
			(xy 39.387076 -381.389729) (xy 39.319756 -381.413286) (xy 39.250221 -381.429156) (xy 39.179347 -381.437142)
			(xy 39.108025 -381.437142) (xy 39.037151 -381.429156) (xy 38.967616 -381.413286) (xy 38.900296 -381.389729)
			(xy 38.836037 -381.358784) (xy 38.775646 -381.320838) (xy 38.719884 -381.276369) (xy 38.669451 -381.225936)
			(xy 38.624982 -381.170174) (xy 38.587036 -381.109783) (xy 38.556091 -381.045524) (xy 38.532534 -380.978204)
			(xy 38.516664 -380.908669) (xy 38.508678 -380.837795) (xy 36.45609 -380.837795) (xy 36.471468 -380.920059)
			(xy 36.479486 -381.006588) (xy 36.479988 -381.050038) (xy 36.479486 -381.093488) (xy 36.471468 -381.180017)
			(xy 36.4555 -381.265437) (xy 36.431719 -381.349019) (xy 36.400327 -381.430051) (xy 36.361593 -381.50784)
			(xy 36.315846 -381.581724) (xy 36.263477 -381.651071) (xy 36.204933 -381.715291) (xy 36.140713 -381.773835)
			(xy 36.071366 -381.826204) (xy 35.997482 -381.871951) (xy 35.919693 -381.910685) (xy 35.838661 -381.942077)
			(xy 35.755079 -381.965858) (xy 35.669659 -381.981826) (xy 35.58313 -381.989844) (xy 35.49623 -381.989844)
			(xy 35.409701 -381.981826) (xy 35.324281 -381.965858) (xy 35.240699 -381.942077) (xy 35.159667 -381.910685)
			(xy 35.081878 -381.871951) (xy 35.007994 -381.826204) (xy 34.938647 -381.773835) (xy 34.874427 -381.715291)
			(xy 34.815883 -381.651071) (xy 34.763514 -381.581724) (xy 34.717767 -381.50784) (xy 34.679033 -381.430051)
			(xy 34.647641 -381.349019) (xy 34.62386 -381.265437) (xy 34.607892 -381.180017) (xy 34.599874 -381.093488)
			(xy 31.512494 -381.093488) (xy 31.385002 -381.22098) (xy 31.376874 -381.256794) (xy 31.366666 -381.299774)
			(xy 31.339236 -381.383753) (xy 31.304049 -381.464788) (xy 31.261415 -381.542166) (xy 31.211711 -381.615202)
			(xy 31.155375 -381.683254) (xy 31.092903 -381.745721) (xy 31.024847 -381.802053) (xy 30.951806 -381.851752)
			(xy 30.874426 -381.89438) (xy 30.793388 -381.929561) (xy 30.709407 -381.956984) (xy 30.666436 -381.967232)
			(xy 30.630622 -381.97536) (xy 30.385258 -382.220724) (xy 30.369923 -382.236739) (xy 30.344487 -382.273053)
			(xy 30.325742 -382.313232) (xy 30.314257 -382.356055) (xy 30.31038 -382.400221) (xy 30.31423 -382.44439)
			(xy 30.325688 -382.48722) (xy 30.344408 -382.52741) (xy 30.369821 -382.56374) (xy 30.401155 -382.595107)
			(xy 30.437459 -382.620558) (xy 30.477629 -382.63932) (xy 30.520447 -382.650824) (xy 30.542484 -382.653286)
			(xy 30.586009 -382.65763) (xy 30.672057 -382.673383) (xy 30.75627 -382.697061) (xy 30.837919 -382.728458)
			(xy 30.916299 -382.767304) (xy 30.990731 -382.813261) (xy 31.060574 -382.865934) (xy 31.125222 -382.924866)
			(xy 31.184116 -382.989548) (xy 31.236748 -383.059421) (xy 31.282662 -383.133881) (xy 31.321462 -383.212284)
			(xy 31.352812 -383.293951) (xy 31.37644 -383.378177) (xy 31.392143 -383.464234) (xy 31.399785 -383.551377)
			(xy 31.399988 -383.595118) (xy 31.399336 -383.633488) (xy 34.599874 -383.633488) (xy 34.599874 -383.546588)
			(xy 34.607892 -383.460059) (xy 34.62386 -383.374639) (xy 34.647641 -383.291057) (xy 34.679033 -383.210025)
			(xy 34.717767 -383.132236) (xy 34.763514 -383.058352) (xy 34.815883 -382.989005) (xy 34.874427 -382.924785)
			(xy 34.938647 -382.866241) (xy 35.007994 -382.813872) (xy 35.081878 -382.768125) (xy 35.159667 -382.729391)
			(xy 35.240699 -382.697999) (xy 35.324281 -382.674218) (xy 35.409701 -382.65825) (xy 35.49623 -382.650232)
			(xy 35.58313 -382.650232) (xy 35.669659 -382.65825) (xy 35.740117 -382.671421) (xy 38.508678 -382.671421)
			(xy 38.508678 -382.600099) (xy 38.516664 -382.529225) (xy 38.532534 -382.45969) (xy 38.556091 -382.39237)
			(xy 38.587036 -382.328111) (xy 38.624982 -382.26772) (xy 38.669451 -382.211958) (xy 38.719884 -382.161525)
			(xy 38.775646 -382.117056) (xy 38.836037 -382.07911) (xy 38.900296 -382.048165) (xy 38.967616 -382.024608)
			(xy 39.037151 -382.008738) (xy 39.108025 -382.000752) (xy 39.179347 -382.000752) (xy 39.250221 -382.008738)
			(xy 39.319756 -382.024608) (xy 39.387076 -382.048165) (xy 39.451335 -382.07911) (xy 39.511726 -382.117056)
			(xy 39.567488 -382.161525) (xy 39.617921 -382.211958) (xy 39.66239 -382.26772) (xy 39.700336 -382.328111)
			(xy 39.731281 -382.39237) (xy 39.754838 -382.45969) (xy 39.770708 -382.529225) (xy 39.778694 -382.600099)
			(xy 39.779194 -382.63576) (xy 39.778694 -382.671421) (xy 40.39539 -382.671421) (xy 40.39539 -382.600099)
			(xy 40.403376 -382.529225) (xy 40.419246 -382.45969) (xy 40.442803 -382.39237) (xy 40.473748 -382.328111)
			(xy 40.511694 -382.26772) (xy 40.556163 -382.211958) (xy 40.606596 -382.161525) (xy 40.662358 -382.117056)
			(xy 40.722749 -382.07911) (xy 40.787008 -382.048165) (xy 40.854328 -382.024608) (xy 40.923863 -382.008738)
			(xy 40.994737 -382.000752) (xy 41.066059 -382.000752) (xy 41.136933 -382.008738) (xy 41.206468 -382.024608)
			(xy 41.273788 -382.048165) (xy 41.338047 -382.07911) (xy 41.398438 -382.117056) (xy 41.4542 -382.161525)
			(xy 41.504633 -382.211958) (xy 41.549102 -382.26772) (xy 41.587048 -382.328111) (xy 41.617993 -382.39237)
			(xy 41.64155 -382.45969) (xy 41.65742 -382.529225) (xy 41.665406 -382.600099) (xy 41.665906 -382.63576)
			(xy 41.665406 -382.671421) (xy 42.636432 -382.671421) (xy 42.636432 -382.600099) (xy 42.644418 -382.529225)
			(xy 42.660288 -382.45969) (xy 42.683845 -382.39237) (xy 42.71479 -382.328111) (xy 42.752736 -382.26772)
			(xy 42.797205 -382.211958) (xy 42.847638 -382.161525) (xy 42.9034 -382.117056) (xy 42.963791 -382.07911)
			(xy 43.02805 -382.048165) (xy 43.09537 -382.024608) (xy 43.164905 -382.008738) (xy 43.235779 -382.000752)
			(xy 43.307101 -382.000752) (xy 43.377975 -382.008738) (xy 43.44751 -382.024608) (xy 43.51483 -382.048165)
			(xy 43.579089 -382.07911) (xy 43.63948 -382.117056) (xy 43.695242 -382.161525) (xy 43.745675 -382.211958)
			(xy 43.790144 -382.26772) (xy 43.82809 -382.328111) (xy 43.859035 -382.39237) (xy 43.882592 -382.45969)
			(xy 43.898462 -382.529225) (xy 43.906448 -382.600099) (xy 43.906948 -382.63576) (xy 43.906448 -382.671421)
			(xy 44.540416 -382.671421) (xy 44.540416 -382.600099) (xy 44.548402 -382.529225) (xy 44.564272 -382.45969)
			(xy 44.587829 -382.39237) (xy 44.618774 -382.328111) (xy 44.65672 -382.26772) (xy 44.701189 -382.211958)
			(xy 44.751622 -382.161525) (xy 44.807384 -382.117056) (xy 44.867775 -382.07911) (xy 44.932034 -382.048165)
			(xy 44.999354 -382.024608) (xy 45.068889 -382.008738) (xy 45.139763 -382.000752) (xy 45.211085 -382.000752)
			(xy 45.281959 -382.008738) (xy 45.351494 -382.024608) (xy 45.418814 -382.048165) (xy 45.483073 -382.07911)
			(xy 45.543464 -382.117056) (xy 45.599226 -382.161525) (xy 45.649659 -382.211958) (xy 45.694128 -382.26772)
			(xy 45.732074 -382.328111) (xy 45.763019 -382.39237) (xy 45.786576 -382.45969) (xy 45.802446 -382.529225)
			(xy 45.810432 -382.600099) (xy 45.810932 -382.63576) (xy 45.810432 -382.671421) (xy 45.802446 -382.742295)
			(xy 45.786576 -382.81183) (xy 45.763019 -382.87915) (xy 45.732074 -382.943409) (xy 45.694128 -383.0038)
			(xy 45.649659 -383.059562) (xy 45.599226 -383.109995) (xy 45.543464 -383.154464) (xy 45.483073 -383.19241)
			(xy 45.418814 -383.223355) (xy 45.351494 -383.246912) (xy 45.281959 -383.262782) (xy 45.211085 -383.270768)
			(xy 45.139763 -383.270768) (xy 45.068889 -383.262782) (xy 44.999354 -383.246912) (xy 44.932034 -383.223355)
			(xy 44.867775 -383.19241) (xy 44.807384 -383.154464) (xy 44.751622 -383.109995) (xy 44.701189 -383.059562)
			(xy 44.65672 -383.0038) (xy 44.618774 -382.943409) (xy 44.587829 -382.87915) (xy 44.564272 -382.81183)
			(xy 44.548402 -382.742295) (xy 44.540416 -382.671421) (xy 43.906448 -382.671421) (xy 43.898462 -382.742295)
			(xy 43.882592 -382.81183) (xy 43.859035 -382.87915) (xy 43.82809 -382.943409) (xy 43.790144 -383.0038)
			(xy 43.745675 -383.059562) (xy 43.695242 -383.109995) (xy 43.63948 -383.154464) (xy 43.579089 -383.19241)
			(xy 43.51483 -383.223355) (xy 43.44751 -383.246912) (xy 43.377975 -383.262782) (xy 43.307101 -383.270768)
			(xy 43.235779 -383.270768) (xy 43.164905 -383.262782) (xy 43.09537 -383.246912) (xy 43.02805 -383.223355)
			(xy 42.963791 -383.19241) (xy 42.9034 -383.154464) (xy 42.847638 -383.109995) (xy 42.797205 -383.059562)
			(xy 42.752736 -383.0038) (xy 42.71479 -382.943409) (xy 42.683845 -382.87915) (xy 42.660288 -382.81183)
			(xy 42.644418 -382.742295) (xy 42.636432 -382.671421) (xy 41.665406 -382.671421) (xy 41.65742 -382.742295)
			(xy 41.64155 -382.81183) (xy 41.617993 -382.87915) (xy 41.587048 -382.943409) (xy 41.549102 -383.0038)
			(xy 41.504633 -383.059562) (xy 41.4542 -383.109995) (xy 41.398438 -383.154464) (xy 41.338047 -383.19241)
			(xy 41.273788 -383.223355) (xy 41.206468 -383.246912) (xy 41.136933 -383.262782) (xy 41.066059 -383.270768)
			(xy 40.994737 -383.270768) (xy 40.923863 -383.262782) (xy 40.854328 -383.246912) (xy 40.787008 -383.223355)
			(xy 40.722749 -383.19241) (xy 40.662358 -383.154464) (xy 40.606596 -383.109995) (xy 40.556163 -383.059562)
			(xy 40.511694 -383.0038) (xy 40.473748 -382.943409) (xy 40.442803 -382.87915) (xy 40.419246 -382.81183)
			(xy 40.403376 -382.742295) (xy 40.39539 -382.671421) (xy 39.778694 -382.671421) (xy 39.770708 -382.742295)
			(xy 39.754838 -382.81183) (xy 39.731281 -382.87915) (xy 39.700336 -382.943409) (xy 39.66239 -383.0038)
			(xy 39.617921 -383.059562) (xy 39.567488 -383.109995) (xy 39.511726 -383.154464) (xy 39.451335 -383.19241)
			(xy 39.387076 -383.223355) (xy 39.319756 -383.246912) (xy 39.250221 -383.262782) (xy 39.179347 -383.270768)
			(xy 39.108025 -383.270768) (xy 39.037151 -383.262782) (xy 38.967616 -383.246912) (xy 38.900296 -383.223355)
			(xy 38.836037 -383.19241) (xy 38.775646 -383.154464) (xy 38.719884 -383.109995) (xy 38.669451 -383.059562)
			(xy 38.624982 -383.0038) (xy 38.587036 -382.943409) (xy 38.556091 -382.87915) (xy 38.532534 -382.81183)
			(xy 38.516664 -382.742295) (xy 38.508678 -382.671421) (xy 35.740117 -382.671421) (xy 35.755079 -382.674218)
			(xy 35.838661 -382.697999) (xy 35.919693 -382.729391) (xy 35.997482 -382.768125) (xy 36.071366 -382.813872)
			(xy 36.140713 -382.866241) (xy 36.204933 -382.924785) (xy 36.263477 -382.989005) (xy 36.315846 -383.058352)
			(xy 36.361593 -383.132236) (xy 36.400327 -383.210025) (xy 36.431719 -383.291057) (xy 36.4555 -383.374639)
			(xy 36.471468 -383.460059) (xy 36.479486 -383.546588) (xy 36.479988 -383.590038) (xy 36.479486 -383.633488)
			(xy 36.471468 -383.720017) (xy 36.4555 -383.805437) (xy 36.431719 -383.889019) (xy 36.400327 -383.970051)
			(xy 36.361593 -384.04784) (xy 36.315846 -384.121724) (xy 36.263477 -384.191071) (xy 36.204933 -384.255291)
			(xy 36.140713 -384.313835) (xy 36.071366 -384.366204) (xy 35.997482 -384.411951) (xy 35.919693 -384.450685)
			(xy 35.838661 -384.482077) (xy 35.755079 -384.505858) (xy 35.669659 -384.521826) (xy 35.58313 -384.529844)
			(xy 35.49623 -384.529844) (xy 35.409701 -384.521826) (xy 35.324281 -384.505858) (xy 35.240699 -384.482077)
			(xy 35.159667 -384.450685) (xy 35.081878 -384.411951) (xy 35.007994 -384.366204) (xy 34.938647 -384.313835)
			(xy 34.874427 -384.255291) (xy 34.815883 -384.191071) (xy 34.763514 -384.121724) (xy 34.717767 -384.04784)
			(xy 34.679033 -383.970051) (xy 34.647641 -383.889019) (xy 34.62386 -383.805437) (xy 34.607892 -383.720017)
			(xy 34.599874 -383.633488) (xy 31.399336 -383.633488) (xy 31.399242 -383.639021) (xy 31.39058 -383.726404)
			(xy 31.373809 -383.8126) (xy 31.349076 -383.896857) (xy 31.316596 -383.978442) (xy 31.276652 -384.056643)
			(xy 31.229591 -384.13078) (xy 31.175824 -384.200206) (xy 31.115819 -384.264319) (xy 31.050099 -384.322557)
			(xy 30.979235 -384.374416) (xy 30.903846 -384.419443) (xy 30.824587 -384.457245) (xy 30.742149 -384.487494)
			(xy 30.657251 -384.509926) (xy 30.570631 -384.524346) (xy 30.483044 -384.530627) (xy 30.395252 -384.528717)
			(xy 30.308021 -384.51863) (xy 30.222111 -384.500455) (xy 30.138269 -384.47435) (xy 30.057225 -384.440543)
			(xy 30.018228 -384.420364) (xy 29.98425 -384.401842) (xy 29.919144 -384.359998) (xy 29.857699 -384.312942)
			(xy 29.828744 -384.287268) (xy 29.811703 -384.272502) (xy 29.773459 -384.248621) (xy 29.731602 -384.231862)
			(xy 29.687444 -384.222753) (xy 29.642372 -384.221577) (xy 29.5978 -384.228373) (xy 29.555126 -384.242928)
			(xy 29.51569 -384.264783) (xy 29.48073 -384.293254) (xy 29.451341 -384.327447) (xy 29.428447 -384.36629)
			(xy 29.412766 -384.408562) (xy 29.404789 -384.452939) (xy 29.40431 -384.475482) (xy 29.40431 -384.572357)
			(xy 38.508678 -384.572357) (xy 38.508678 -384.501035) (xy 38.516664 -384.430161) (xy 38.532534 -384.360626)
			(xy 38.556091 -384.293306) (xy 38.587036 -384.229047) (xy 38.624982 -384.168656) (xy 38.669451 -384.112894)
			(xy 38.719884 -384.062461) (xy 38.775646 -384.017992) (xy 38.836037 -383.980046) (xy 38.900296 -383.949101)
			(xy 38.967616 -383.925544) (xy 39.037151 -383.909674) (xy 39.108025 -383.901688) (xy 39.179347 -383.901688)
			(xy 39.250221 -383.909674) (xy 39.319756 -383.925544) (xy 39.387076 -383.949101) (xy 39.451335 -383.980046)
			(xy 39.511726 -384.017992) (xy 39.567488 -384.062461) (xy 39.617921 -384.112894) (xy 39.66239 -384.168656)
			(xy 39.700336 -384.229047) (xy 39.731281 -384.293306) (xy 39.754838 -384.360626) (xy 39.770708 -384.430161)
			(xy 39.778694 -384.501035) (xy 39.779194 -384.536696) (xy 39.778694 -384.572357) (xy 40.39539 -384.572357)
			(xy 40.39539 -384.501035) (xy 40.403376 -384.430161) (xy 40.419246 -384.360626) (xy 40.442803 -384.293306)
			(xy 40.473748 -384.229047) (xy 40.511694 -384.168656) (xy 40.556163 -384.112894) (xy 40.606596 -384.062461)
			(xy 40.662358 -384.017992) (xy 40.722749 -383.980046) (xy 40.787008 -383.949101) (xy 40.854328 -383.925544)
			(xy 40.923863 -383.909674) (xy 40.994737 -383.901688) (xy 41.066059 -383.901688) (xy 41.136933 -383.909674)
			(xy 41.206468 -383.925544) (xy 41.273788 -383.949101) (xy 41.338047 -383.980046) (xy 41.398438 -384.017992)
			(xy 41.4542 -384.062461) (xy 41.504633 -384.112894) (xy 41.549102 -384.168656) (xy 41.587048 -384.229047)
			(xy 41.617993 -384.293306) (xy 41.64155 -384.360626) (xy 41.65742 -384.430161) (xy 41.665406 -384.501035)
			(xy 41.665906 -384.536696) (xy 41.665406 -384.572357) (xy 42.636432 -384.572357) (xy 42.636432 -384.501035)
			(xy 42.644418 -384.430161) (xy 42.660288 -384.360626) (xy 42.683845 -384.293306) (xy 42.71479 -384.229047)
			(xy 42.752736 -384.168656) (xy 42.797205 -384.112894) (xy 42.847638 -384.062461) (xy 42.9034 -384.017992)
			(xy 42.963791 -383.980046) (xy 43.02805 -383.949101) (xy 43.09537 -383.925544) (xy 43.164905 -383.909674)
			(xy 43.235779 -383.901688) (xy 43.307101 -383.901688) (xy 43.377975 -383.909674) (xy 43.44751 -383.925544)
			(xy 43.51483 -383.949101) (xy 43.579089 -383.980046) (xy 43.63948 -384.017992) (xy 43.695242 -384.062461)
			(xy 43.745675 -384.112894) (xy 43.790144 -384.168656) (xy 43.82809 -384.229047) (xy 43.859035 -384.293306)
			(xy 43.882592 -384.360626) (xy 43.898462 -384.430161) (xy 43.906448 -384.501035) (xy 43.906948 -384.536696)
			(xy 43.906448 -384.572357) (xy 44.540416 -384.572357) (xy 44.540416 -384.501035) (xy 44.548402 -384.430161)
			(xy 44.564272 -384.360626) (xy 44.587829 -384.293306) (xy 44.618774 -384.229047) (xy 44.65672 -384.168656)
			(xy 44.701189 -384.112894) (xy 44.751622 -384.062461) (xy 44.807384 -384.017992) (xy 44.867775 -383.980046)
			(xy 44.932034 -383.949101) (xy 44.999354 -383.925544) (xy 45.068889 -383.909674) (xy 45.139763 -383.901688)
			(xy 45.211085 -383.901688) (xy 45.281959 -383.909674) (xy 45.351494 -383.925544) (xy 45.418814 -383.949101)
			(xy 45.483073 -383.980046) (xy 45.543464 -384.017992) (xy 45.599226 -384.062461) (xy 45.649659 -384.112894)
			(xy 45.694128 -384.168656) (xy 45.732074 -384.229047) (xy 45.763019 -384.293306) (xy 45.786576 -384.360626)
			(xy 45.802446 -384.430161) (xy 45.810432 -384.501035) (xy 45.810932 -384.536696) (xy 45.810634 -384.557918)
			(xy 76.158023 -384.557918) (xy 76.158023 -384.494682) (xy 76.166277 -384.431986) (xy 76.182645 -384.370905)
			(xy 76.206845 -384.312483) (xy 76.238465 -384.257719) (xy 76.276962 -384.207552) (xy 76.321679 -384.162838)
			(xy 76.371849 -384.124345) (xy 76.426615 -384.092729) (xy 76.485039 -384.068533) (xy 76.546122 -384.05217)
			(xy 76.608818 -384.04392) (xy 76.640436 -384.043428) (xy 77.593444 -384.043428) (xy 77.621706 -384.043833)
			(xy 77.677848 -384.050401) (xy 77.732836 -384.063488) (xy 77.785917 -384.082916) (xy 77.836362 -384.108417)
			(xy 77.860144 -384.123692) (xy 77.892148 -384.144774) (xy 78.054962 -384.144774) (xy 78.088744 -384.119374)
			(xy 78.115223 -384.100191) (xy 78.172164 -384.068049) (xy 78.232756 -384.043474) (xy 78.296 -384.026872)
			(xy 78.360851 -384.018518) (xy 78.393544 -384.018028) (xy 79.729076 -384.018028) (xy 79.761022 -384.018543)
			(xy 79.824411 -384.026549) (xy 79.886297 -384.042435) (xy 79.945703 -384.065954) (xy 80.001694 -384.096732)
			(xy 80.053385 -384.134286) (xy 80.099961 -384.178022) (xy 80.140689 -384.227251) (xy 80.174925 -384.281197)
			(xy 80.20213 -384.339008) (xy 80.221874 -384.399773) (xy 80.233847 -384.462534) (xy 80.237859 -384.5263)
			(xy 80.233847 -384.590066) (xy 80.221874 -384.652827) (xy 80.20213 -384.713592) (xy 80.174925 -384.771403)
			(xy 80.140689 -384.825349) (xy 80.099961 -384.874578) (xy 80.053385 -384.918314) (xy 80.001694 -384.955868)
			(xy 79.945703 -384.986646) (xy 79.886297 -385.010165) (xy 79.824411 -385.026051) (xy 79.761022 -385.034057)
			(xy 79.729076 -385.034536) (xy 78.393544 -385.034536) (xy 78.39329 -385.034536) (xy 78.360622 -385.034041)
			(xy 78.295824 -385.025667) (xy 78.232634 -385.009058) (xy 78.172093 -384.984488) (xy 78.1152 -384.952362)
			(xy 78.088744 -384.93319) (xy 78.054962 -384.90779) (xy 77.892148 -384.90779) (xy 77.860144 -384.928872)
			(xy 77.836348 -384.944121) (xy 77.785895 -384.969598) (xy 77.732817 -384.98902) (xy 77.677837 -385.002123)
			(xy 77.621704 -385.008727) (xy 77.593444 -385.009136) (xy 76.640436 -385.009136) (xy 76.608818 -385.00868)
			(xy 76.546122 -385.00043) (xy 76.485039 -384.984067) (xy 76.426615 -384.959871) (xy 76.371849 -384.928255)
			(xy 76.321679 -384.889762) (xy 76.276962 -384.845048) (xy 76.238465 -384.794881) (xy 76.206845 -384.740117)
			(xy 76.182645 -384.681695) (xy 76.166277 -384.620614) (xy 76.158023 -384.557918) (xy 45.810634 -384.557918)
			(xy 45.810432 -384.572357) (xy 45.802446 -384.643231) (xy 45.786576 -384.712766) (xy 45.763019 -384.780086)
			(xy 45.732074 -384.844345) (xy 45.694128 -384.904736) (xy 45.649659 -384.960498) (xy 45.599226 -385.010931)
			(xy 45.543464 -385.0554) (xy 45.483073 -385.093346) (xy 45.418814 -385.124291) (xy 45.351494 -385.147848)
			(xy 45.281959 -385.163718) (xy 45.211085 -385.171704) (xy 45.139763 -385.171704) (xy 45.068889 -385.163718)
			(xy 44.999354 -385.147848) (xy 44.932034 -385.124291) (xy 44.867775 -385.093346) (xy 44.807384 -385.0554)
			(xy 44.751622 -385.010931) (xy 44.701189 -384.960498) (xy 44.65672 -384.904736) (xy 44.618774 -384.844345)
			(xy 44.587829 -384.780086) (xy 44.564272 -384.712766) (xy 44.548402 -384.643231) (xy 44.540416 -384.572357)
			(xy 43.906448 -384.572357) (xy 43.898462 -384.643231) (xy 43.882592 -384.712766) (xy 43.859035 -384.780086)
			(xy 43.82809 -384.844345) (xy 43.790144 -384.904736) (xy 43.745675 -384.960498) (xy 43.695242 -385.010931)
			(xy 43.63948 -385.0554) (xy 43.579089 -385.093346) (xy 43.51483 -385.124291) (xy 43.44751 -385.147848)
			(xy 43.377975 -385.163718) (xy 43.307101 -385.171704) (xy 43.235779 -385.171704) (xy 43.164905 -385.163718)
			(xy 43.09537 -385.147848) (xy 43.02805 -385.124291) (xy 42.963791 -385.093346) (xy 42.9034 -385.0554)
			(xy 42.847638 -385.010931) (xy 42.797205 -384.960498) (xy 42.752736 -384.904736) (xy 42.71479 -384.844345)
			(xy 42.683845 -384.780086) (xy 42.660288 -384.712766) (xy 42.644418 -384.643231) (xy 42.636432 -384.572357)
			(xy 41.665406 -384.572357) (xy 41.65742 -384.643231) (xy 41.64155 -384.712766) (xy 41.617993 -384.780086)
			(xy 41.587048 -384.844345) (xy 41.549102 -384.904736) (xy 41.504633 -384.960498) (xy 41.4542 -385.010931)
			(xy 41.398438 -385.0554) (xy 41.338047 -385.093346) (xy 41.273788 -385.124291) (xy 41.206468 -385.147848)
			(xy 41.136933 -385.163718) (xy 41.066059 -385.171704) (xy 40.994737 -385.171704) (xy 40.923863 -385.163718)
			(xy 40.854328 -385.147848) (xy 40.787008 -385.124291) (xy 40.722749 -385.093346) (xy 40.662358 -385.0554)
			(xy 40.606596 -385.010931) (xy 40.556163 -384.960498) (xy 40.511694 -384.904736) (xy 40.473748 -384.844345)
			(xy 40.442803 -384.780086) (xy 40.419246 -384.712766) (xy 40.403376 -384.643231) (xy 40.39539 -384.572357)
			(xy 39.778694 -384.572357) (xy 39.770708 -384.643231) (xy 39.754838 -384.712766) (xy 39.731281 -384.780086)
			(xy 39.700336 -384.844345) (xy 39.66239 -384.904736) (xy 39.617921 -384.960498) (xy 39.567488 -385.010931)
			(xy 39.511726 -385.0554) (xy 39.451335 -385.093346) (xy 39.387076 -385.124291) (xy 39.319756 -385.147848)
			(xy 39.250221 -385.163718) (xy 39.179347 -385.171704) (xy 39.108025 -385.171704) (xy 39.037151 -385.163718)
			(xy 38.967616 -385.147848) (xy 38.900296 -385.124291) (xy 38.836037 -385.093346) (xy 38.775646 -385.0554)
			(xy 38.719884 -385.010931) (xy 38.669451 -384.960498) (xy 38.624982 -384.904736) (xy 38.587036 -384.844345)
			(xy 38.556091 -384.780086) (xy 38.532534 -384.712766) (xy 38.516664 -384.643231) (xy 38.508678 -384.572357)
			(xy 29.40431 -384.572357) (xy 29.40431 -385.244594) (xy 29.404797 -385.267138) (xy 29.412756 -385.311518)
			(xy 29.428424 -385.353796) (xy 29.451309 -385.392644) (xy 29.480693 -385.426842) (xy 29.515653 -385.455316)
			(xy 29.55509 -385.477171) (xy 29.597766 -385.491721) (xy 29.64234 -385.498508) (xy 29.687412 -385.49732)
			(xy 29.731567 -385.488194) (xy 29.773417 -385.471417) (xy 29.811648 -385.447515) (xy 29.828744 -385.432808)
			(xy 29.861244 -385.404069) (xy 29.930663 -385.352024) (xy 30.004582 -385.306596) (xy 30.082372 -385.268171)
			(xy 30.16337 -385.237075) (xy 30.246889 -385.213573) (xy 30.332218 -385.197866) (xy 30.41863 -385.190085)
			(xy 30.505393 -385.190299) (xy 30.591766 -385.198504) (xy 30.677016 -385.214631) (xy 30.760419 -385.238543)
			(xy 30.841263 -385.270037) (xy 30.918863 -385.308845) (xy 30.992557 -385.354636) (xy 31.06172 -385.407021)
			(xy 31.125763 -385.465555) (xy 31.184141 -385.52974) (xy 31.236358 -385.59903) (xy 31.28197 -385.672836)
			(xy 31.320588 -385.75053) (xy 31.351885 -385.831451) (xy 31.375595 -385.914911) (xy 31.391515 -386.0002)
			(xy 31.39951 -386.086593) (xy 31.399512 -386.173356) (xy 31.3995 -386.173488) (xy 34.599874 -386.173488)
			(xy 34.599874 -386.086588) (xy 34.607892 -386.000059) (xy 34.62386 -385.914639) (xy 34.647641 -385.831057)
			(xy 34.679033 -385.750025) (xy 34.717767 -385.672236) (xy 34.763514 -385.598352) (xy 34.815883 -385.529005)
			(xy 34.874427 -385.464785) (xy 34.938647 -385.406241) (xy 35.007994 -385.353872) (xy 35.081878 -385.308125)
			(xy 35.159667 -385.269391) (xy 35.240699 -385.237999) (xy 35.324281 -385.214218) (xy 35.409701 -385.19825)
			(xy 35.49623 -385.190232) (xy 35.58313 -385.190232) (xy 35.669659 -385.19825) (xy 35.755079 -385.214218)
			(xy 35.838661 -385.237999) (xy 35.919693 -385.269391) (xy 35.997482 -385.308125) (xy 36.071366 -385.353872)
			(xy 36.140713 -385.406241) (xy 36.204933 -385.464785) (xy 36.263477 -385.529005) (xy 36.315846 -385.598352)
			(xy 36.361593 -385.672236) (xy 36.400327 -385.750025) (xy 36.431719 -385.831057) (xy 36.4555 -385.914639)
			(xy 36.471468 -386.000059) (xy 36.479486 -386.086588) (xy 36.479988 -386.130038) (xy 36.479486 -386.173488)
			(xy 36.472629 -386.247487) (xy 38.508678 -386.247487) (xy 38.508678 -386.176165) (xy 38.516664 -386.105291)
			(xy 38.532534 -386.035756) (xy 38.556091 -385.968436) (xy 38.587036 -385.904177) (xy 38.624982 -385.843786)
			(xy 38.669451 -385.788024) (xy 38.719884 -385.737591) (xy 38.775646 -385.693122) (xy 38.836037 -385.655176)
			(xy 38.900296 -385.624231) (xy 38.967616 -385.600674) (xy 39.037151 -385.584804) (xy 39.108025 -385.576818)
			(xy 39.179347 -385.576818) (xy 39.250221 -385.584804) (xy 39.319756 -385.600674) (xy 39.387076 -385.624231)
			(xy 39.451335 -385.655176) (xy 39.511726 -385.693122) (xy 39.567488 -385.737591) (xy 39.617921 -385.788024)
			(xy 39.66239 -385.843786) (xy 39.700336 -385.904177) (xy 39.731281 -385.968436) (xy 39.754838 -386.035756)
			(xy 39.770708 -386.105291) (xy 39.778694 -386.176165) (xy 39.779194 -386.211826) (xy 39.778694 -386.247487)
			(xy 40.39539 -386.247487) (xy 40.39539 -386.176165) (xy 40.403376 -386.105291) (xy 40.419246 -386.035756)
			(xy 40.442803 -385.968436) (xy 40.473748 -385.904177) (xy 40.511694 -385.843786) (xy 40.556163 -385.788024)
			(xy 40.606596 -385.737591) (xy 40.662358 -385.693122) (xy 40.722749 -385.655176) (xy 40.787008 -385.624231)
			(xy 40.854328 -385.600674) (xy 40.923863 -385.584804) (xy 40.994737 -385.576818) (xy 41.066059 -385.576818)
			(xy 41.136933 -385.584804) (xy 41.206468 -385.600674) (xy 41.273788 -385.624231) (xy 41.338047 -385.655176)
			(xy 41.398438 -385.693122) (xy 41.4542 -385.737591) (xy 41.504633 -385.788024) (xy 41.549102 -385.843786)
			(xy 41.587048 -385.904177) (xy 41.617993 -385.968436) (xy 41.64155 -386.035756) (xy 41.65742 -386.105291)
			(xy 41.665406 -386.176165) (xy 41.665906 -386.211826) (xy 41.665406 -386.247487) (xy 42.636432 -386.247487)
			(xy 42.636432 -386.176165) (xy 42.644418 -386.105291) (xy 42.660288 -386.035756) (xy 42.683845 -385.968436)
			(xy 42.71479 -385.904177) (xy 42.752736 -385.843786) (xy 42.797205 -385.788024) (xy 42.847638 -385.737591)
			(xy 42.9034 -385.693122) (xy 42.963791 -385.655176) (xy 43.02805 -385.624231) (xy 43.09537 -385.600674)
			(xy 43.164905 -385.584804) (xy 43.235779 -385.576818) (xy 43.307101 -385.576818) (xy 43.377975 -385.584804)
			(xy 43.44751 -385.600674) (xy 43.51483 -385.624231) (xy 43.579089 -385.655176) (xy 43.63948 -385.693122)
			(xy 43.695242 -385.737591) (xy 43.745675 -385.788024) (xy 43.790144 -385.843786) (xy 43.82809 -385.904177)
			(xy 43.859035 -385.968436) (xy 43.882592 -386.035756) (xy 43.898462 -386.105291) (xy 43.906448 -386.176165)
			(xy 43.906948 -386.211826) (xy 43.906448 -386.247487) (xy 44.540416 -386.247487) (xy 44.540416 -386.176165)
			(xy 44.548402 -386.105291) (xy 44.564272 -386.035756) (xy 44.587829 -385.968436) (xy 44.618774 -385.904177)
			(xy 44.65672 -385.843786) (xy 44.701189 -385.788024) (xy 44.751622 -385.737591) (xy 44.807384 -385.693122)
			(xy 44.867775 -385.655176) (xy 44.932034 -385.624231) (xy 44.999354 -385.600674) (xy 45.068889 -385.584804)
			(xy 45.139763 -385.576818) (xy 45.211085 -385.576818) (xy 45.281959 -385.584804) (xy 45.351494 -385.600674)
			(xy 45.418814 -385.624231) (xy 45.483073 -385.655176) (xy 45.543464 -385.693122) (xy 45.599226 -385.737591)
			(xy 45.649659 -385.788024) (xy 45.694128 -385.843786) (xy 45.732074 -385.904177) (xy 45.763019 -385.968436)
			(xy 45.786576 -386.035756) (xy 45.802446 -386.105291) (xy 45.810432 -386.176165) (xy 45.810932 -386.211826)
			(xy 45.810432 -386.247487) (xy 45.802446 -386.318361) (xy 45.786576 -386.387896) (xy 45.763019 -386.455216)
			(xy 45.732074 -386.519475) (xy 45.694128 -386.579866) (xy 45.649659 -386.635628) (xy 45.599226 -386.686061)
			(xy 45.543464 -386.73053) (xy 45.483073 -386.768476) (xy 45.418814 -386.799421) (xy 45.351494 -386.822978)
			(xy 45.281959 -386.838848) (xy 45.211085 -386.846834) (xy 45.139763 -386.846834) (xy 45.068889 -386.838848)
			(xy 44.999354 -386.822978) (xy 44.932034 -386.799421) (xy 44.867775 -386.768476) (xy 44.807384 -386.73053)
			(xy 44.751622 -386.686061) (xy 44.701189 -386.635628) (xy 44.65672 -386.579866) (xy 44.618774 -386.519475)
			(xy 44.587829 -386.455216) (xy 44.564272 -386.387896) (xy 44.548402 -386.318361) (xy 44.540416 -386.247487)
			(xy 43.906448 -386.247487) (xy 43.898462 -386.318361) (xy 43.882592 -386.387896) (xy 43.859035 -386.455216)
			(xy 43.82809 -386.519475) (xy 43.790144 -386.579866) (xy 43.745675 -386.635628) (xy 43.695242 -386.686061)
			(xy 43.63948 -386.73053) (xy 43.579089 -386.768476) (xy 43.51483 -386.799421) (xy 43.44751 -386.822978)
			(xy 43.377975 -386.838848) (xy 43.307101 -386.846834) (xy 43.235779 -386.846834) (xy 43.164905 -386.838848)
			(xy 43.09537 -386.822978) (xy 43.02805 -386.799421) (xy 42.963791 -386.768476) (xy 42.9034 -386.73053)
			(xy 42.847638 -386.686061) (xy 42.797205 -386.635628) (xy 42.752736 -386.579866) (xy 42.71479 -386.519475)
			(xy 42.683845 -386.455216) (xy 42.660288 -386.387896) (xy 42.644418 -386.318361) (xy 42.636432 -386.247487)
			(xy 41.665406 -386.247487) (xy 41.65742 -386.318361) (xy 41.64155 -386.387896) (xy 41.617993 -386.455216)
			(xy 41.587048 -386.519475) (xy 41.549102 -386.579866) (xy 41.504633 -386.635628) (xy 41.4542 -386.686061)
			(xy 41.398438 -386.73053) (xy 41.338047 -386.768476) (xy 41.273788 -386.799421) (xy 41.206468 -386.822978)
			(xy 41.136933 -386.838848) (xy 41.066059 -386.846834) (xy 40.994737 -386.846834) (xy 40.923863 -386.838848)
			(xy 40.854328 -386.822978) (xy 40.787008 -386.799421) (xy 40.722749 -386.768476) (xy 40.662358 -386.73053)
			(xy 40.606596 -386.686061) (xy 40.556163 -386.635628) (xy 40.511694 -386.579866) (xy 40.473748 -386.519475)
			(xy 40.442803 -386.455216) (xy 40.419246 -386.387896) (xy 40.403376 -386.318361) (xy 40.39539 -386.247487)
			(xy 39.778694 -386.247487) (xy 39.770708 -386.318361) (xy 39.754838 -386.387896) (xy 39.731281 -386.455216)
			(xy 39.700336 -386.519475) (xy 39.66239 -386.579866) (xy 39.617921 -386.635628) (xy 39.567488 -386.686061)
			(xy 39.511726 -386.73053) (xy 39.451335 -386.768476) (xy 39.387076 -386.799421) (xy 39.319756 -386.822978)
			(xy 39.250221 -386.838848) (xy 39.179347 -386.846834) (xy 39.108025 -386.846834) (xy 39.037151 -386.838848)
			(xy 38.967616 -386.822978) (xy 38.900296 -386.799421) (xy 38.836037 -386.768476) (xy 38.775646 -386.73053)
			(xy 38.719884 -386.686061) (xy 38.669451 -386.635628) (xy 38.624982 -386.579866) (xy 38.587036 -386.519475)
			(xy 38.556091 -386.455216) (xy 38.532534 -386.387896) (xy 38.516664 -386.318361) (xy 38.508678 -386.247487)
			(xy 36.472629 -386.247487) (xy 36.471468 -386.260017) (xy 36.4555 -386.345437) (xy 36.431719 -386.429019)
			(xy 36.400327 -386.510051) (xy 36.361593 -386.58784) (xy 36.315846 -386.661724) (xy 36.263477 -386.731071)
			(xy 36.204933 -386.795291) (xy 36.140713 -386.853835) (xy 36.071366 -386.906204) (xy 35.997482 -386.951951)
			(xy 35.919693 -386.990685) (xy 35.838661 -387.022077) (xy 35.755079 -387.045858) (xy 35.669659 -387.061826)
			(xy 35.58313 -387.069844) (xy 35.49623 -387.069844) (xy 35.409701 -387.061826) (xy 35.324281 -387.045858)
			(xy 35.240699 -387.022077) (xy 35.159667 -386.990685) (xy 35.081878 -386.951951) (xy 35.007994 -386.906204)
			(xy 34.938647 -386.853835) (xy 34.874427 -386.795291) (xy 34.815883 -386.731071) (xy 34.763514 -386.661724)
			(xy 34.717767 -386.58784) (xy 34.679033 -386.510051) (xy 34.647641 -386.429019) (xy 34.62386 -386.345437)
			(xy 34.607892 -386.260017) (xy 34.599874 -386.173488) (xy 31.3995 -386.173488) (xy 31.391522 -386.259749)
			(xy 31.375606 -386.34504) (xy 31.351902 -386.428501) (xy 31.320609 -386.509424) (xy 31.281995 -386.587119)
			(xy 31.236387 -386.660928) (xy 31.184174 -386.73022) (xy 31.125799 -386.794409) (xy 31.061759 -386.852946)
			(xy 30.992599 -386.905335) (xy 30.918907 -386.95113) (xy 30.84131 -386.989942) (xy 30.760467 -387.02144)
			(xy 30.677066 -387.045357) (xy 30.591817 -387.061489) (xy 30.505444 -387.069699) (xy 30.418681 -387.069917)
			(xy 30.332268 -387.062141) (xy 30.246939 -387.046438) (xy 30.163419 -387.022941) (xy 30.082418 -386.99185)
			(xy 30.004627 -386.953429) (xy 29.930705 -386.908005) (xy 29.861283 -386.855964) (xy 29.828744 -386.827268)
			(xy 29.811703 -386.812502) (xy 29.773459 -386.788621) (xy 29.731602 -386.771862) (xy 29.687444 -386.762753)
			(xy 29.642372 -386.761577) (xy 29.5978 -386.768373) (xy 29.555126 -386.782928) (xy 29.51569 -386.804783)
			(xy 29.48073 -386.833254) (xy 29.451341 -386.867447) (xy 29.428447 -386.90629) (xy 29.412766 -386.948562)
			(xy 29.404789 -386.992939) (xy 29.40431 -387.015482) (xy 29.40431 -387.229519) (xy 76.293395 -387.229519)
			(xy 76.293395 -387.166281) (xy 76.301649 -387.103583) (xy 76.318017 -387.0425) (xy 76.342218 -386.984075)
			(xy 76.373838 -386.929309) (xy 76.412336 -386.879139) (xy 76.457053 -386.834424) (xy 76.507224 -386.795928)
			(xy 76.561991 -386.76431) (xy 76.620417 -386.740111) (xy 76.681501 -386.723746) (xy 76.744199 -386.715493)
			(xy 76.775818 -386.715) (xy 77.662024 -386.715) (xy 77.690312 -386.71538) (xy 77.746507 -386.721933)
			(xy 77.801549 -386.735018) (xy 77.854681 -386.754455) (xy 77.905174 -386.779975) (xy 77.928978 -386.795264)
			(xy 77.960728 -386.8166) (xy 78.018132 -386.8166) (xy 78.018132 -386.871464) (xy 78.037942 -386.893829)
			(xy 78.072573 -386.942514) (xy 78.100934 -386.995098) (xy 78.122594 -387.050778) (xy 78.137222 -387.108705)
			(xy 78.144595 -387.167994) (xy 78.144599 -387.227739) (xy 78.137235 -387.287028) (xy 78.122615 -387.344957)
			(xy 78.100963 -387.400641) (xy 78.072608 -387.453229) (xy 78.037985 -387.501918) (xy 78.018132 -387.524244)
			(xy 78.018132 -387.579108) (xy 77.960728 -387.579108) (xy 77.928978 -387.600444) (xy 77.905175 -387.615731)
			(xy 77.85467 -387.641221) (xy 77.801537 -387.660645) (xy 77.746499 -387.673736) (xy 77.690311 -387.680317)
			(xy 77.662024 -387.680708) (xy 76.775818 -387.680708) (xy 76.744199 -387.680307) (xy 76.681501 -387.672054)
			(xy 76.620417 -387.655689) (xy 76.561991 -387.63149) (xy 76.507224 -387.599872) (xy 76.457053 -387.561376)
			(xy 76.412336 -387.516661) (xy 76.373838 -387.466491) (xy 76.342218 -387.411725) (xy 76.318017 -387.3533)
			(xy 76.301649 -387.292217) (xy 76.293395 -387.229519) (xy 29.40431 -387.229519) (xy 29.40431 -387.784594)
			(xy 29.404797 -387.807138) (xy 29.412756 -387.851518) (xy 29.428424 -387.893796) (xy 29.451309 -387.932644)
			(xy 29.480693 -387.966842) (xy 29.515653 -387.995316) (xy 29.55509 -388.017171) (xy 29.597766 -388.031721)
			(xy 29.64234 -388.038508) (xy 29.687412 -388.03732) (xy 29.731567 -388.028194) (xy 29.773417 -388.011417)
			(xy 29.811648 -387.987515) (xy 29.828744 -387.972808) (xy 29.861244 -387.944069) (xy 29.930663 -387.892024)
			(xy 30.004582 -387.846596) (xy 30.082372 -387.808171) (xy 30.16337 -387.777075) (xy 30.246889 -387.753573)
			(xy 30.332218 -387.737866) (xy 30.41863 -387.730085) (xy 30.505393 -387.730299) (xy 30.591766 -387.738504)
			(xy 30.677016 -387.754631) (xy 30.760419 -387.778543) (xy 30.841263 -387.810037) (xy 30.918863 -387.848845)
			(xy 30.992557 -387.894636) (xy 31.06172 -387.947021) (xy 31.125763 -388.005555) (xy 31.184141 -388.06974)
			(xy 31.236358 -388.13903) (xy 31.28197 -388.212836) (xy 31.320588 -388.29053) (xy 31.351885 -388.371451)
			(xy 31.375595 -388.454911) (xy 31.391515 -388.5402) (xy 31.39951 -388.626593) (xy 31.399512 -388.713356)
			(xy 31.3995 -388.713488) (xy 34.599874 -388.713488) (xy 34.599874 -388.626588) (xy 34.607892 -388.540059)
			(xy 34.62386 -388.454639) (xy 34.647641 -388.371057) (xy 34.679033 -388.290025) (xy 34.717767 -388.212236)
			(xy 34.763514 -388.138352) (xy 34.815883 -388.069005) (xy 34.874427 -388.004785) (xy 34.938647 -387.946241)
			(xy 35.007994 -387.893872) (xy 35.081878 -387.848125) (xy 35.159667 -387.809391) (xy 35.240699 -387.777999)
			(xy 35.324281 -387.754218) (xy 35.409701 -387.73825) (xy 35.49623 -387.730232) (xy 35.58313 -387.730232)
			(xy 35.669659 -387.73825) (xy 35.755079 -387.754218) (xy 35.838661 -387.777999) (xy 35.919693 -387.809391)
			(xy 35.997482 -387.848125) (xy 36.071366 -387.893872) (xy 36.140713 -387.946241) (xy 36.204933 -388.004785)
			(xy 36.263477 -388.069005) (xy 36.315846 -388.138352) (xy 36.361593 -388.212236) (xy 36.384709 -388.258659)
			(xy 38.465244 -388.258659) (xy 38.465244 -388.187337) (xy 38.47323 -388.116463) (xy 38.4891 -388.046928)
			(xy 38.512657 -387.979608) (xy 38.543602 -387.915349) (xy 38.581548 -387.854958) (xy 38.626017 -387.799196)
			(xy 38.67645 -387.748763) (xy 38.732212 -387.704294) (xy 38.792603 -387.666348) (xy 38.856862 -387.635403)
			(xy 38.924182 -387.611846) (xy 38.993717 -387.595976) (xy 39.064591 -387.58799) (xy 39.135913 -387.58799)
			(xy 39.206787 -387.595976) (xy 39.276322 -387.611846) (xy 39.343642 -387.635403) (xy 39.407901 -387.666348)
			(xy 39.468292 -387.704294) (xy 39.524054 -387.748763) (xy 39.574487 -387.799196) (xy 39.618956 -387.854958)
			(xy 39.656902 -387.915349) (xy 39.687847 -387.979608) (xy 39.711404 -388.046928) (xy 39.727274 -388.116463)
			(xy 39.73526 -388.187337) (xy 39.73576 -388.222998) (xy 39.73526 -388.258659) (xy 40.351956 -388.258659)
			(xy 40.351956 -388.187337) (xy 40.359942 -388.116463) (xy 40.375812 -388.046928) (xy 40.399369 -387.979608)
			(xy 40.430314 -387.915349) (xy 40.46826 -387.854958) (xy 40.512729 -387.799196) (xy 40.563162 -387.748763)
			(xy 40.618924 -387.704294) (xy 40.679315 -387.666348) (xy 40.743574 -387.635403) (xy 40.810894 -387.611846)
			(xy 40.880429 -387.595976) (xy 40.951303 -387.58799) (xy 41.022625 -387.58799) (xy 41.093499 -387.595976)
			(xy 41.163034 -387.611846) (xy 41.230354 -387.635403) (xy 41.294613 -387.666348) (xy 41.355004 -387.704294)
			(xy 41.410766 -387.748763) (xy 41.461199 -387.799196) (xy 41.505668 -387.854958) (xy 41.543614 -387.915349)
			(xy 41.574559 -387.979608) (xy 41.598116 -388.046928) (xy 41.613986 -388.116463) (xy 41.621972 -388.187337)
			(xy 41.622472 -388.222998) (xy 41.621972 -388.258659) (xy 42.592998 -388.258659) (xy 42.592998 -388.187337)
			(xy 42.600984 -388.116463) (xy 42.616854 -388.046928) (xy 42.640411 -387.979608) (xy 42.671356 -387.915349)
			(xy 42.709302 -387.854958) (xy 42.753771 -387.799196) (xy 42.804204 -387.748763) (xy 42.859966 -387.704294)
			(xy 42.920357 -387.666348) (xy 42.984616 -387.635403) (xy 43.051936 -387.611846) (xy 43.121471 -387.595976)
			(xy 43.192345 -387.58799) (xy 43.263667 -387.58799) (xy 43.334541 -387.595976) (xy 43.404076 -387.611846)
			(xy 43.471396 -387.635403) (xy 43.535655 -387.666348) (xy 43.596046 -387.704294) (xy 43.651808 -387.748763)
			(xy 43.702241 -387.799196) (xy 43.74671 -387.854958) (xy 43.784656 -387.915349) (xy 43.815601 -387.979608)
			(xy 43.839158 -388.046928) (xy 43.855028 -388.116463) (xy 43.863014 -388.187337) (xy 43.863514 -388.222998)
			(xy 43.863014 -388.258659) (xy 44.496982 -388.258659) (xy 44.496982 -388.187337) (xy 44.504968 -388.116463)
			(xy 44.520838 -388.046928) (xy 44.544395 -387.979608) (xy 44.57534 -387.915349) (xy 44.613286 -387.854958)
			(xy 44.657755 -387.799196) (xy 44.708188 -387.748763) (xy 44.76395 -387.704294) (xy 44.824341 -387.666348)
			(xy 44.8886 -387.635403) (xy 44.95592 -387.611846) (xy 45.025455 -387.595976) (xy 45.096329 -387.58799)
			(xy 45.167651 -387.58799) (xy 45.238525 -387.595976) (xy 45.30806 -387.611846) (xy 45.37538 -387.635403)
			(xy 45.439639 -387.666348) (xy 45.50003 -387.704294) (xy 45.555792 -387.748763) (xy 45.606225 -387.799196)
			(xy 45.650694 -387.854958) (xy 45.68864 -387.915349) (xy 45.719585 -387.979608) (xy 45.743142 -388.046928)
			(xy 45.759012 -388.116463) (xy 45.766998 -388.187337) (xy 45.767498 -388.222998) (xy 45.766998 -388.258659)
			(xy 45.759012 -388.329533) (xy 45.743142 -388.399068) (xy 45.719585 -388.466388) (xy 45.68864 -388.530647)
			(xy 45.650694 -388.591038) (xy 45.606225 -388.6468) (xy 45.555792 -388.697233) (xy 45.50003 -388.741702)
			(xy 45.439639 -388.779648) (xy 45.37538 -388.810593) (xy 45.30806 -388.83415) (xy 45.238525 -388.85002)
			(xy 45.167651 -388.858006) (xy 45.096329 -388.858006) (xy 45.025455 -388.85002) (xy 44.95592 -388.83415)
			(xy 44.8886 -388.810593) (xy 44.824341 -388.779648) (xy 44.76395 -388.741702) (xy 44.708188 -388.697233)
			(xy 44.657755 -388.6468) (xy 44.613286 -388.591038) (xy 44.57534 -388.530647) (xy 44.544395 -388.466388)
			(xy 44.520838 -388.399068) (xy 44.504968 -388.329533) (xy 44.496982 -388.258659) (xy 43.863014 -388.258659)
			(xy 43.855028 -388.329533) (xy 43.839158 -388.399068) (xy 43.815601 -388.466388) (xy 43.784656 -388.530647)
			(xy 43.74671 -388.591038) (xy 43.702241 -388.6468) (xy 43.651808 -388.697233) (xy 43.596046 -388.741702)
			(xy 43.535655 -388.779648) (xy 43.471396 -388.810593) (xy 43.404076 -388.83415) (xy 43.334541 -388.85002)
			(xy 43.263667 -388.858006) (xy 43.192345 -388.858006) (xy 43.121471 -388.85002) (xy 43.051936 -388.83415)
			(xy 42.984616 -388.810593) (xy 42.920357 -388.779648) (xy 42.859966 -388.741702) (xy 42.804204 -388.697233)
			(xy 42.753771 -388.6468) (xy 42.709302 -388.591038) (xy 42.671356 -388.530647) (xy 42.640411 -388.466388)
			(xy 42.616854 -388.399068) (xy 42.600984 -388.329533) (xy 42.592998 -388.258659) (xy 41.621972 -388.258659)
			(xy 41.613986 -388.329533) (xy 41.598116 -388.399068) (xy 41.574559 -388.466388) (xy 41.543614 -388.530647)
			(xy 41.505668 -388.591038) (xy 41.461199 -388.6468) (xy 41.410766 -388.697233) (xy 41.355004 -388.741702)
			(xy 41.294613 -388.779648) (xy 41.230354 -388.810593) (xy 41.163034 -388.83415) (xy 41.093499 -388.85002)
			(xy 41.022625 -388.858006) (xy 40.951303 -388.858006) (xy 40.880429 -388.85002) (xy 40.810894 -388.83415)
			(xy 40.743574 -388.810593) (xy 40.679315 -388.779648) (xy 40.618924 -388.741702) (xy 40.563162 -388.697233)
			(xy 40.512729 -388.6468) (xy 40.46826 -388.591038) (xy 40.430314 -388.530647) (xy 40.399369 -388.466388)
			(xy 40.375812 -388.399068) (xy 40.359942 -388.329533) (xy 40.351956 -388.258659) (xy 39.73526 -388.258659)
			(xy 39.727274 -388.329533) (xy 39.711404 -388.399068) (xy 39.687847 -388.466388) (xy 39.656902 -388.530647)
			(xy 39.618956 -388.591038) (xy 39.574487 -388.6468) (xy 39.524054 -388.697233) (xy 39.468292 -388.741702)
			(xy 39.407901 -388.779648) (xy 39.343642 -388.810593) (xy 39.276322 -388.83415) (xy 39.206787 -388.85002)
			(xy 39.135913 -388.858006) (xy 39.064591 -388.858006) (xy 38.993717 -388.85002) (xy 38.924182 -388.83415)
			(xy 38.856862 -388.810593) (xy 38.792603 -388.779648) (xy 38.732212 -388.741702) (xy 38.67645 -388.697233)
			(xy 38.626017 -388.6468) (xy 38.581548 -388.591038) (xy 38.543602 -388.530647) (xy 38.512657 -388.466388)
			(xy 38.4891 -388.399068) (xy 38.47323 -388.329533) (xy 38.465244 -388.258659) (xy 36.384709 -388.258659)
			(xy 36.400327 -388.290025) (xy 36.431719 -388.371057) (xy 36.4555 -388.454639) (xy 36.471468 -388.540059)
			(xy 36.479486 -388.626588) (xy 36.479988 -388.670038) (xy 36.479486 -388.713488) (xy 36.471468 -388.800017)
			(xy 36.4555 -388.885437) (xy 36.431719 -388.969019) (xy 36.400327 -389.050051) (xy 36.361593 -389.12784)
			(xy 36.315846 -389.201724) (xy 36.263477 -389.271071) (xy 36.204933 -389.335291) (xy 36.140713 -389.393835)
			(xy 36.071366 -389.446204) (xy 35.997482 -389.491951) (xy 35.919693 -389.530685) (xy 35.838661 -389.562077)
			(xy 35.755079 -389.585858) (xy 35.669659 -389.601826) (xy 35.58313 -389.609844) (xy 35.49623 -389.609844)
			(xy 35.409701 -389.601826) (xy 35.324281 -389.585858) (xy 35.240699 -389.562077) (xy 35.159667 -389.530685)
			(xy 35.081878 -389.491951) (xy 35.007994 -389.446204) (xy 34.938647 -389.393835) (xy 34.874427 -389.335291)
			(xy 34.815883 -389.271071) (xy 34.763514 -389.201724) (xy 34.717767 -389.12784) (xy 34.679033 -389.050051)
			(xy 34.647641 -388.969019) (xy 34.62386 -388.885437) (xy 34.607892 -388.800017) (xy 34.599874 -388.713488)
			(xy 31.3995 -388.713488) (xy 31.391522 -388.799749) (xy 31.375606 -388.88504) (xy 31.351902 -388.968501)
			(xy 31.320609 -389.049424) (xy 31.281995 -389.127119) (xy 31.236387 -389.200928) (xy 31.184174 -389.27022)
			(xy 31.125799 -389.334409) (xy 31.061759 -389.392946) (xy 30.992599 -389.445335) (xy 30.918907 -389.49113)
			(xy 30.84131 -389.529942) (xy 30.760467 -389.56144) (xy 30.677066 -389.585357) (xy 30.591817 -389.601489)
			(xy 30.505444 -389.609699) (xy 30.418681 -389.609917) (xy 30.332268 -389.602141) (xy 30.246939 -389.586438)
			(xy 30.163419 -389.562941) (xy 30.082418 -389.53185) (xy 30.004627 -389.493429) (xy 29.930705 -389.448005)
			(xy 29.861283 -389.395964) (xy 29.828744 -389.367268) (xy 29.811703 -389.352502) (xy 29.773459 -389.328621)
			(xy 29.731602 -389.311862) (xy 29.687444 -389.302753) (xy 29.642372 -389.301577) (xy 29.5978 -389.308373)
			(xy 29.555126 -389.322928) (xy 29.51569 -389.344783) (xy 29.48073 -389.373254) (xy 29.451341 -389.407447)
			(xy 29.428447 -389.44629) (xy 29.412766 -389.488562) (xy 29.404789 -389.532939) (xy 29.40431 -389.555482)
			(xy 29.40431 -390.149181) (xy 38.465244 -390.149181) (xy 38.465244 -390.077859) (xy 38.47323 -390.006985)
			(xy 38.4891 -389.93745) (xy 38.512657 -389.87013) (xy 38.543602 -389.805871) (xy 38.581548 -389.74548)
			(xy 38.626017 -389.689718) (xy 38.67645 -389.639285) (xy 38.732212 -389.594816) (xy 38.792603 -389.55687)
			(xy 38.856862 -389.525925) (xy 38.924182 -389.502368) (xy 38.993717 -389.486498) (xy 39.064591 -389.478512)
			(xy 39.135913 -389.478512) (xy 39.206787 -389.486498) (xy 39.276322 -389.502368) (xy 39.343642 -389.525925)
			(xy 39.407901 -389.55687) (xy 39.468292 -389.594816) (xy 39.524054 -389.639285) (xy 39.574487 -389.689718)
			(xy 39.618956 -389.74548) (xy 39.656902 -389.805871) (xy 39.687847 -389.87013) (xy 39.711404 -389.93745)
			(xy 39.727274 -390.006985) (xy 39.73526 -390.077859) (xy 39.73576 -390.11352) (xy 39.73526 -390.149181)
			(xy 40.351956 -390.149181) (xy 40.351956 -390.077859) (xy 40.359942 -390.006985) (xy 40.375812 -389.93745)
			(xy 40.399369 -389.87013) (xy 40.430314 -389.805871) (xy 40.46826 -389.74548) (xy 40.512729 -389.689718)
			(xy 40.563162 -389.639285) (xy 40.618924 -389.594816) (xy 40.679315 -389.55687) (xy 40.743574 -389.525925)
			(xy 40.810894 -389.502368) (xy 40.880429 -389.486498) (xy 40.951303 -389.478512) (xy 41.022625 -389.478512)
			(xy 41.093499 -389.486498) (xy 41.163034 -389.502368) (xy 41.230354 -389.525925) (xy 41.294613 -389.55687)
			(xy 41.355004 -389.594816) (xy 41.410766 -389.639285) (xy 41.461199 -389.689718) (xy 41.505668 -389.74548)
			(xy 41.543614 -389.805871) (xy 41.574559 -389.87013) (xy 41.598116 -389.93745) (xy 41.613986 -390.006985)
			(xy 41.621972 -390.077859) (xy 41.622472 -390.11352) (xy 41.621972 -390.149181) (xy 42.592998 -390.149181)
			(xy 42.592998 -390.077859) (xy 42.600984 -390.006985) (xy 42.616854 -389.93745) (xy 42.640411 -389.87013)
			(xy 42.671356 -389.805871) (xy 42.709302 -389.74548) (xy 42.753771 -389.689718) (xy 42.804204 -389.639285)
			(xy 42.859966 -389.594816) (xy 42.920357 -389.55687) (xy 42.984616 -389.525925) (xy 43.051936 -389.502368)
			(xy 43.121471 -389.486498) (xy 43.192345 -389.478512) (xy 43.263667 -389.478512) (xy 43.334541 -389.486498)
			(xy 43.404076 -389.502368) (xy 43.471396 -389.525925) (xy 43.535655 -389.55687) (xy 43.596046 -389.594816)
			(xy 43.651808 -389.639285) (xy 43.702241 -389.689718) (xy 43.74671 -389.74548) (xy 43.784656 -389.805871)
			(xy 43.815601 -389.87013) (xy 43.839158 -389.93745) (xy 43.855028 -390.006985) (xy 43.863014 -390.077859)
			(xy 43.863514 -390.11352) (xy 43.863014 -390.149181) (xy 44.496982 -390.149181) (xy 44.496982 -390.077859)
			(xy 44.504968 -390.006985) (xy 44.520838 -389.93745) (xy 44.544395 -389.87013) (xy 44.57534 -389.805871)
			(xy 44.613286 -389.74548) (xy 44.657755 -389.689718) (xy 44.708188 -389.639285) (xy 44.76395 -389.594816)
			(xy 44.824341 -389.55687) (xy 44.8886 -389.525925) (xy 44.95592 -389.502368) (xy 45.025455 -389.486498)
			(xy 45.096329 -389.478512) (xy 45.167651 -389.478512) (xy 45.238525 -389.486498) (xy 45.30806 -389.502368)
			(xy 45.37538 -389.525925) (xy 45.439639 -389.55687) (xy 45.50003 -389.594816) (xy 45.555792 -389.639285)
			(xy 45.606225 -389.689718) (xy 45.650694 -389.74548) (xy 45.68864 -389.805871) (xy 45.719585 -389.87013)
			(xy 45.743142 -389.93745) (xy 45.759012 -390.006985) (xy 45.766998 -390.077859) (xy 45.767498 -390.11352)
			(xy 45.766998 -390.149181) (xy 45.759012 -390.220055) (xy 45.743142 -390.28959) (xy 45.719585 -390.35691)
			(xy 45.68864 -390.421169) (xy 45.650694 -390.48156) (xy 45.606225 -390.537322) (xy 45.555792 -390.587755)
			(xy 45.50003 -390.632224) (xy 45.439639 -390.67017) (xy 45.37538 -390.701115) (xy 45.30806 -390.724672)
			(xy 45.238525 -390.740542) (xy 45.167651 -390.748528) (xy 45.096329 -390.748528) (xy 45.025455 -390.740542)
			(xy 44.95592 -390.724672) (xy 44.8886 -390.701115) (xy 44.824341 -390.67017) (xy 44.76395 -390.632224)
			(xy 44.708188 -390.587755) (xy 44.657755 -390.537322) (xy 44.613286 -390.48156) (xy 44.57534 -390.421169)
			(xy 44.544395 -390.35691) (xy 44.520838 -390.28959) (xy 44.504968 -390.220055) (xy 44.496982 -390.149181)
			(xy 43.863014 -390.149181) (xy 43.855028 -390.220055) (xy 43.839158 -390.28959) (xy 43.815601 -390.35691)
			(xy 43.784656 -390.421169) (xy 43.74671 -390.48156) (xy 43.702241 -390.537322) (xy 43.651808 -390.587755)
			(xy 43.596046 -390.632224) (xy 43.535655 -390.67017) (xy 43.471396 -390.701115) (xy 43.404076 -390.724672)
			(xy 43.334541 -390.740542) (xy 43.263667 -390.748528) (xy 43.192345 -390.748528) (xy 43.121471 -390.740542)
			(xy 43.051936 -390.724672) (xy 42.984616 -390.701115) (xy 42.920357 -390.67017) (xy 42.859966 -390.632224)
			(xy 42.804204 -390.587755) (xy 42.753771 -390.537322) (xy 42.709302 -390.48156) (xy 42.671356 -390.421169)
			(xy 42.640411 -390.35691) (xy 42.616854 -390.28959) (xy 42.600984 -390.220055) (xy 42.592998 -390.149181)
			(xy 41.621972 -390.149181) (xy 41.613986 -390.220055) (xy 41.598116 -390.28959) (xy 41.574559 -390.35691)
			(xy 41.543614 -390.421169) (xy 41.505668 -390.48156) (xy 41.461199 -390.537322) (xy 41.410766 -390.587755)
			(xy 41.355004 -390.632224) (xy 41.294613 -390.67017) (xy 41.230354 -390.701115) (xy 41.163034 -390.724672)
			(xy 41.093499 -390.740542) (xy 41.022625 -390.748528) (xy 40.951303 -390.748528) (xy 40.880429 -390.740542)
			(xy 40.810894 -390.724672) (xy 40.743574 -390.701115) (xy 40.679315 -390.67017) (xy 40.618924 -390.632224)
			(xy 40.563162 -390.587755) (xy 40.512729 -390.537322) (xy 40.46826 -390.48156) (xy 40.430314 -390.421169)
			(xy 40.399369 -390.35691) (xy 40.375812 -390.28959) (xy 40.359942 -390.220055) (xy 40.351956 -390.149181)
			(xy 39.73526 -390.149181) (xy 39.727274 -390.220055) (xy 39.711404 -390.28959) (xy 39.687847 -390.35691)
			(xy 39.656902 -390.421169) (xy 39.618956 -390.48156) (xy 39.574487 -390.537322) (xy 39.524054 -390.587755)
			(xy 39.468292 -390.632224) (xy 39.407901 -390.67017) (xy 39.343642 -390.701115) (xy 39.276322 -390.724672)
			(xy 39.206787 -390.740542) (xy 39.135913 -390.748528) (xy 39.064591 -390.748528) (xy 38.993717 -390.740542)
			(xy 38.924182 -390.724672) (xy 38.856862 -390.701115) (xy 38.792603 -390.67017) (xy 38.732212 -390.632224)
			(xy 38.67645 -390.587755) (xy 38.626017 -390.537322) (xy 38.581548 -390.48156) (xy 38.543602 -390.421169)
			(xy 38.512657 -390.35691) (xy 38.4891 -390.28959) (xy 38.47323 -390.220055) (xy 38.465244 -390.149181)
			(xy 29.40431 -390.149181) (xy 29.40431 -390.324594) (xy 29.404797 -390.347138) (xy 29.412756 -390.391518)
			(xy 29.428424 -390.433796) (xy 29.451309 -390.472644) (xy 29.480693 -390.506842) (xy 29.515653 -390.535316)
			(xy 29.55509 -390.557171) (xy 29.597766 -390.571721) (xy 29.64234 -390.578508) (xy 29.687412 -390.57732)
			(xy 29.731567 -390.568194) (xy 29.773417 -390.551417) (xy 29.811648 -390.527515) (xy 29.828744 -390.512808)
			(xy 29.861244 -390.484069) (xy 29.930663 -390.432024) (xy 30.004582 -390.386596) (xy 30.082372 -390.348171)
			(xy 30.16337 -390.317075) (xy 30.246889 -390.293573) (xy 30.332218 -390.277866) (xy 30.41863 -390.270085)
			(xy 30.505393 -390.270299) (xy 30.591766 -390.278504) (xy 30.677016 -390.294631) (xy 30.760419 -390.318543)
			(xy 30.841263 -390.350037) (xy 30.918863 -390.388845) (xy 30.992557 -390.434636) (xy 31.06172 -390.487021)
			(xy 31.125763 -390.545555) (xy 31.184141 -390.60974) (xy 31.236358 -390.67903) (xy 31.28197 -390.752836)
			(xy 31.320588 -390.83053) (xy 31.351885 -390.911451) (xy 31.375595 -390.994911) (xy 31.391515 -391.0802)
			(xy 31.39951 -391.166593) (xy 31.399512 -391.253356) (xy 31.3995 -391.253488) (xy 34.599874 -391.253488)
			(xy 34.599874 -391.166588) (xy 34.607892 -391.080059) (xy 34.62386 -390.994639) (xy 34.647641 -390.911057)
			(xy 34.679033 -390.830025) (xy 34.717767 -390.752236) (xy 34.763514 -390.678352) (xy 34.815883 -390.609005)
			(xy 34.874427 -390.544785) (xy 34.938647 -390.486241) (xy 35.007994 -390.433872) (xy 35.081878 -390.388125)
			(xy 35.159667 -390.349391) (xy 35.240699 -390.317999) (xy 35.324281 -390.294218) (xy 35.409701 -390.27825)
			(xy 35.49623 -390.270232) (xy 35.58313 -390.270232) (xy 35.669659 -390.27825) (xy 35.755079 -390.294218)
			(xy 35.838661 -390.317999) (xy 35.919693 -390.349391) (xy 35.997482 -390.388125) (xy 36.071366 -390.433872)
			(xy 36.140713 -390.486241) (xy 36.204933 -390.544785) (xy 36.263477 -390.609005) (xy 36.315846 -390.678352)
			(xy 36.361593 -390.752236) (xy 36.400327 -390.830025) (xy 36.431719 -390.911057) (xy 36.4555 -390.994639)
			(xy 36.471468 -391.080059) (xy 36.479486 -391.166588) (xy 36.479988 -391.210038) (xy 36.479486 -391.253488)
			(xy 36.471468 -391.340017) (xy 36.4555 -391.425437) (xy 36.431719 -391.509019) (xy 36.400327 -391.590051)
			(xy 36.361593 -391.66784) (xy 36.315846 -391.741724) (xy 36.263477 -391.811071) (xy 36.204933 -391.875291)
			(xy 36.140713 -391.933835) (xy 36.071366 -391.986204) (xy 35.997482 -392.031951) (xy 35.919693 -392.070685)
			(xy 35.838661 -392.102077) (xy 35.755079 -392.125858) (xy 35.669659 -392.141826) (xy 35.58313 -392.149844)
			(xy 35.49623 -392.149844) (xy 35.409701 -392.141826) (xy 35.324281 -392.125858) (xy 35.240699 -392.102077)
			(xy 35.159667 -392.070685) (xy 35.081878 -392.031951) (xy 35.007994 -391.986204) (xy 34.938647 -391.933835)
			(xy 34.874427 -391.875291) (xy 34.815883 -391.811071) (xy 34.763514 -391.741724) (xy 34.717767 -391.66784)
			(xy 34.679033 -391.590051) (xy 34.647641 -391.509019) (xy 34.62386 -391.425437) (xy 34.607892 -391.340017)
			(xy 34.599874 -391.253488) (xy 31.3995 -391.253488) (xy 31.391522 -391.339749) (xy 31.375606 -391.42504)
			(xy 31.351902 -391.508501) (xy 31.320609 -391.589424) (xy 31.281995 -391.667119) (xy 31.236387 -391.740928)
			(xy 31.184174 -391.81022) (xy 31.125799 -391.874409) (xy 31.061759 -391.932946) (xy 30.992599 -391.985335)
			(xy 30.918907 -392.03113) (xy 30.84131 -392.069942) (xy 30.760467 -392.10144) (xy 30.677066 -392.125357)
			(xy 30.591817 -392.141489) (xy 30.505444 -392.149699) (xy 30.418681 -392.149917) (xy 30.332268 -392.142141)
			(xy 30.246939 -392.126438) (xy 30.163419 -392.102941) (xy 30.082418 -392.07185) (xy 30.004627 -392.033429)
			(xy 29.930705 -391.988005) (xy 29.861283 -391.935964) (xy 29.828744 -391.907268) (xy 29.811703 -391.892502)
			(xy 29.773459 -391.868621) (xy 29.731602 -391.851862) (xy 29.687444 -391.842753) (xy 29.642372 -391.841577)
			(xy 29.5978 -391.848373) (xy 29.555126 -391.862928) (xy 29.51569 -391.884783) (xy 29.48073 -391.913254)
			(xy 29.451341 -391.947447) (xy 29.428447 -391.98629) (xy 29.412766 -392.028562) (xy 29.404789 -392.072939)
			(xy 29.40431 -392.095482) (xy 29.40431 -392.190325) (xy 38.465244 -392.190325) (xy 38.465244 -392.119003)
			(xy 38.47323 -392.048129) (xy 38.4891 -391.978594) (xy 38.512657 -391.911274) (xy 38.543602 -391.847015)
			(xy 38.581548 -391.786624) (xy 38.626017 -391.730862) (xy 38.67645 -391.680429) (xy 38.732212 -391.63596)
			(xy 38.792603 -391.598014) (xy 38.856862 -391.567069) (xy 38.924182 -391.543512) (xy 38.993717 -391.527642)
			(xy 39.064591 -391.519656) (xy 39.135913 -391.519656) (xy 39.206787 -391.527642) (xy 39.276322 -391.543512)
			(xy 39.343642 -391.567069) (xy 39.407901 -391.598014) (xy 39.468292 -391.63596) (xy 39.524054 -391.680429)
			(xy 39.574487 -391.730862) (xy 39.618956 -391.786624) (xy 39.656902 -391.847015) (xy 39.687847 -391.911274)
			(xy 39.711404 -391.978594) (xy 39.727274 -392.048129) (xy 39.73526 -392.119003) (xy 39.73576 -392.154664)
			(xy 39.73526 -392.190325) (xy 40.351956 -392.190325) (xy 40.351956 -392.119003) (xy 40.359942 -392.048129)
			(xy 40.375812 -391.978594) (xy 40.399369 -391.911274) (xy 40.430314 -391.847015) (xy 40.46826 -391.786624)
			(xy 40.512729 -391.730862) (xy 40.563162 -391.680429) (xy 40.618924 -391.63596) (xy 40.679315 -391.598014)
			(xy 40.743574 -391.567069) (xy 40.810894 -391.543512) (xy 40.880429 -391.527642) (xy 40.951303 -391.519656)
			(xy 41.022625 -391.519656) (xy 41.093499 -391.527642) (xy 41.163034 -391.543512) (xy 41.230354 -391.567069)
			(xy 41.294613 -391.598014) (xy 41.355004 -391.63596) (xy 41.410766 -391.680429) (xy 41.461199 -391.730862)
			(xy 41.505668 -391.786624) (xy 41.543614 -391.847015) (xy 41.574559 -391.911274) (xy 41.598116 -391.978594)
			(xy 41.613986 -392.048129) (xy 41.621972 -392.119003) (xy 41.622472 -392.154664) (xy 41.621972 -392.190325)
			(xy 42.592998 -392.190325) (xy 42.592998 -392.119003) (xy 42.600984 -392.048129) (xy 42.616854 -391.978594)
			(xy 42.640411 -391.911274) (xy 42.671356 -391.847015) (xy 42.709302 -391.786624) (xy 42.753771 -391.730862)
			(xy 42.804204 -391.680429) (xy 42.859966 -391.63596) (xy 42.920357 -391.598014) (xy 42.984616 -391.567069)
			(xy 43.051936 -391.543512) (xy 43.121471 -391.527642) (xy 43.192345 -391.519656) (xy 43.263667 -391.519656)
			(xy 43.334541 -391.527642) (xy 43.404076 -391.543512) (xy 43.471396 -391.567069) (xy 43.535655 -391.598014)
			(xy 43.596046 -391.63596) (xy 43.651808 -391.680429) (xy 43.702241 -391.730862) (xy 43.74671 -391.786624)
			(xy 43.784656 -391.847015) (xy 43.815601 -391.911274) (xy 43.839158 -391.978594) (xy 43.855028 -392.048129)
			(xy 43.863014 -392.119003) (xy 43.863514 -392.154664) (xy 43.863014 -392.190325) (xy 44.496982 -392.190325)
			(xy 44.496982 -392.119003) (xy 44.504968 -392.048129) (xy 44.520838 -391.978594) (xy 44.544395 -391.911274)
			(xy 44.57534 -391.847015) (xy 44.613286 -391.786624) (xy 44.657755 -391.730862) (xy 44.708188 -391.680429)
			(xy 44.76395 -391.63596) (xy 44.824341 -391.598014) (xy 44.8886 -391.567069) (xy 44.95592 -391.543512)
			(xy 45.025455 -391.527642) (xy 45.096329 -391.519656) (xy 45.167651 -391.519656) (xy 45.238525 -391.527642)
			(xy 45.30806 -391.543512) (xy 45.37538 -391.567069) (xy 45.439639 -391.598014) (xy 45.50003 -391.63596)
			(xy 45.555792 -391.680429) (xy 45.606225 -391.730862) (xy 45.650694 -391.786624) (xy 45.68864 -391.847015)
			(xy 45.719585 -391.911274) (xy 45.743142 -391.978594) (xy 45.759012 -392.048129) (xy 45.766998 -392.119003)
			(xy 45.767498 -392.154664) (xy 45.766998 -392.190325) (xy 45.759012 -392.261199) (xy 45.743142 -392.330734)
			(xy 45.719585 -392.398054) (xy 45.68864 -392.462313) (xy 45.650694 -392.522704) (xy 45.606225 -392.578466)
			(xy 45.555792 -392.628899) (xy 45.50003 -392.673368) (xy 45.439639 -392.711314) (xy 45.37538 -392.742259)
			(xy 45.30806 -392.765816) (xy 45.238525 -392.781686) (xy 45.167651 -392.789672) (xy 45.096329 -392.789672)
			(xy 45.025455 -392.781686) (xy 44.95592 -392.765816) (xy 44.8886 -392.742259) (xy 44.824341 -392.711314)
			(xy 44.76395 -392.673368) (xy 44.708188 -392.628899) (xy 44.657755 -392.578466) (xy 44.613286 -392.522704)
			(xy 44.57534 -392.462313) (xy 44.544395 -392.398054) (xy 44.520838 -392.330734) (xy 44.504968 -392.261199)
			(xy 44.496982 -392.190325) (xy 43.863014 -392.190325) (xy 43.855028 -392.261199) (xy 43.839158 -392.330734)
			(xy 43.815601 -392.398054) (xy 43.784656 -392.462313) (xy 43.74671 -392.522704) (xy 43.702241 -392.578466)
			(xy 43.651808 -392.628899) (xy 43.596046 -392.673368) (xy 43.535655 -392.711314) (xy 43.471396 -392.742259)
			(xy 43.404076 -392.765816) (xy 43.334541 -392.781686) (xy 43.263667 -392.789672) (xy 43.192345 -392.789672)
			(xy 43.121471 -392.781686) (xy 43.051936 -392.765816) (xy 42.984616 -392.742259) (xy 42.920357 -392.711314)
			(xy 42.859966 -392.673368) (xy 42.804204 -392.628899) (xy 42.753771 -392.578466) (xy 42.709302 -392.522704)
			(xy 42.671356 -392.462313) (xy 42.640411 -392.398054) (xy 42.616854 -392.330734) (xy 42.600984 -392.261199)
			(xy 42.592998 -392.190325) (xy 41.621972 -392.190325) (xy 41.613986 -392.261199) (xy 41.598116 -392.330734)
			(xy 41.574559 -392.398054) (xy 41.543614 -392.462313) (xy 41.505668 -392.522704) (xy 41.461199 -392.578466)
			(xy 41.410766 -392.628899) (xy 41.355004 -392.673368) (xy 41.294613 -392.711314) (xy 41.230354 -392.742259)
			(xy 41.163034 -392.765816) (xy 41.093499 -392.781686) (xy 41.022625 -392.789672) (xy 40.951303 -392.789672)
			(xy 40.880429 -392.781686) (xy 40.810894 -392.765816) (xy 40.743574 -392.742259) (xy 40.679315 -392.711314)
			(xy 40.618924 -392.673368) (xy 40.563162 -392.628899) (xy 40.512729 -392.578466) (xy 40.46826 -392.522704)
			(xy 40.430314 -392.462313) (xy 40.399369 -392.398054) (xy 40.375812 -392.330734) (xy 40.359942 -392.261199)
			(xy 40.351956 -392.190325) (xy 39.73526 -392.190325) (xy 39.727274 -392.261199) (xy 39.711404 -392.330734)
			(xy 39.687847 -392.398054) (xy 39.656902 -392.462313) (xy 39.618956 -392.522704) (xy 39.574487 -392.578466)
			(xy 39.524054 -392.628899) (xy 39.468292 -392.673368) (xy 39.407901 -392.711314) (xy 39.343642 -392.742259)
			(xy 39.276322 -392.765816) (xy 39.206787 -392.781686) (xy 39.135913 -392.789672) (xy 39.064591 -392.789672)
			(xy 38.993717 -392.781686) (xy 38.924182 -392.765816) (xy 38.856862 -392.742259) (xy 38.792603 -392.711314)
			(xy 38.732212 -392.673368) (xy 38.67645 -392.628899) (xy 38.626017 -392.578466) (xy 38.581548 -392.522704)
			(xy 38.543602 -392.462313) (xy 38.512657 -392.398054) (xy 38.4891 -392.330734) (xy 38.47323 -392.261199)
			(xy 38.465244 -392.190325) (xy 29.40431 -392.190325) (xy 29.40431 -392.864594) (xy 29.404797 -392.887138)
			(xy 29.412756 -392.931518) (xy 29.428424 -392.973796) (xy 29.451309 -393.012644) (xy 29.480693 -393.046842)
			(xy 29.515653 -393.075316) (xy 29.55509 -393.097171) (xy 29.597766 -393.111721) (xy 29.64234 -393.118508)
			(xy 29.687412 -393.11732) (xy 29.731567 -393.108194) (xy 29.773417 -393.091417) (xy 29.811648 -393.067515)
			(xy 29.828744 -393.052808) (xy 29.861244 -393.024069) (xy 29.930663 -392.972024) (xy 30.004582 -392.926596)
			(xy 30.082372 -392.888171) (xy 30.16337 -392.857075) (xy 30.246889 -392.833573) (xy 30.332218 -392.817866)
			(xy 30.41863 -392.810085) (xy 30.505393 -392.810299) (xy 30.591766 -392.818504) (xy 30.677016 -392.834631)
			(xy 30.760419 -392.858543) (xy 30.841263 -392.890037) (xy 30.918863 -392.928845) (xy 30.992557 -392.974636)
			(xy 31.06172 -393.027021) (xy 31.125763 -393.085555) (xy 31.184141 -393.14974) (xy 31.236358 -393.21903)
			(xy 31.28197 -393.292836) (xy 31.320588 -393.37053) (xy 31.351885 -393.451451) (xy 31.375595 -393.534911)
			(xy 31.391515 -393.6202) (xy 31.39951 -393.706593) (xy 31.399512 -393.793356) (xy 31.3995 -393.793488)
			(xy 34.599874 -393.793488) (xy 34.599874 -393.706588) (xy 34.607892 -393.620059) (xy 34.62386 -393.534639)
			(xy 34.647641 -393.451057) (xy 34.679033 -393.370025) (xy 34.717767 -393.292236) (xy 34.763514 -393.218352)
			(xy 34.815883 -393.149005) (xy 34.874427 -393.084785) (xy 34.938647 -393.026241) (xy 35.007994 -392.973872)
			(xy 35.081878 -392.928125) (xy 35.159667 -392.889391) (xy 35.240699 -392.857999) (xy 35.324281 -392.834218)
			(xy 35.409701 -392.81825) (xy 35.49623 -392.810232) (xy 35.58313 -392.810232) (xy 35.669659 -392.81825)
			(xy 35.755079 -392.834218) (xy 35.838661 -392.857999) (xy 35.919693 -392.889391) (xy 35.997482 -392.928125)
			(xy 36.071366 -392.973872) (xy 36.140713 -393.026241) (xy 36.204933 -393.084785) (xy 36.263477 -393.149005)
			(xy 36.315846 -393.218352) (xy 36.361593 -393.292236) (xy 36.400327 -393.370025) (xy 36.431719 -393.451057)
			(xy 36.4555 -393.534639) (xy 36.471468 -393.620059) (xy 36.479486 -393.706588) (xy 36.479988 -393.750038)
			(xy 36.479486 -393.793488) (xy 36.471468 -393.880017) (xy 36.4555 -393.965437) (xy 36.431719 -394.049019)
			(xy 36.41191 -394.100151) (xy 38.465244 -394.100151) (xy 38.465244 -394.028829) (xy 38.47323 -393.957955)
			(xy 38.4891 -393.88842) (xy 38.512657 -393.8211) (xy 38.543602 -393.756841) (xy 38.581548 -393.69645)
			(xy 38.626017 -393.640688) (xy 38.67645 -393.590255) (xy 38.732212 -393.545786) (xy 38.792603 -393.50784)
			(xy 38.856862 -393.476895) (xy 38.924182 -393.453338) (xy 38.993717 -393.437468) (xy 39.064591 -393.429482)
			(xy 39.135913 -393.429482) (xy 39.206787 -393.437468) (xy 39.276322 -393.453338) (xy 39.343642 -393.476895)
			(xy 39.407901 -393.50784) (xy 39.468292 -393.545786) (xy 39.524054 -393.590255) (xy 39.574487 -393.640688)
			(xy 39.618956 -393.69645) (xy 39.656902 -393.756841) (xy 39.687847 -393.8211) (xy 39.711404 -393.88842)
			(xy 39.727274 -393.957955) (xy 39.73526 -394.028829) (xy 39.73576 -394.06449) (xy 39.73526 -394.100151)
			(xy 40.351956 -394.100151) (xy 40.351956 -394.028829) (xy 40.359942 -393.957955) (xy 40.375812 -393.88842)
			(xy 40.399369 -393.8211) (xy 40.430314 -393.756841) (xy 40.46826 -393.69645) (xy 40.512729 -393.640688)
			(xy 40.563162 -393.590255) (xy 40.618924 -393.545786) (xy 40.679315 -393.50784) (xy 40.743574 -393.476895)
			(xy 40.810894 -393.453338) (xy 40.880429 -393.437468) (xy 40.951303 -393.429482) (xy 41.022625 -393.429482)
			(xy 41.093499 -393.437468) (xy 41.163034 -393.453338) (xy 41.230354 -393.476895) (xy 41.294613 -393.50784)
			(xy 41.355004 -393.545786) (xy 41.410766 -393.590255) (xy 41.461199 -393.640688) (xy 41.505668 -393.69645)
			(xy 41.543614 -393.756841) (xy 41.574559 -393.8211) (xy 41.598116 -393.88842) (xy 41.613986 -393.957955)
			(xy 41.621972 -394.028829) (xy 41.622472 -394.06449) (xy 41.621972 -394.100151) (xy 42.592998 -394.100151)
			(xy 42.592998 -394.028829) (xy 42.600984 -393.957955) (xy 42.616854 -393.88842) (xy 42.640411 -393.8211)
			(xy 42.671356 -393.756841) (xy 42.709302 -393.69645) (xy 42.753771 -393.640688) (xy 42.804204 -393.590255)
			(xy 42.859966 -393.545786) (xy 42.920357 -393.50784) (xy 42.984616 -393.476895) (xy 43.051936 -393.453338)
			(xy 43.121471 -393.437468) (xy 43.192345 -393.429482) (xy 43.263667 -393.429482) (xy 43.334541 -393.437468)
			(xy 43.404076 -393.453338) (xy 43.471396 -393.476895) (xy 43.535655 -393.50784) (xy 43.596046 -393.545786)
			(xy 43.651808 -393.590255) (xy 43.702241 -393.640688) (xy 43.74671 -393.69645) (xy 43.784656 -393.756841)
			(xy 43.815601 -393.8211) (xy 43.839158 -393.88842) (xy 43.855028 -393.957955) (xy 43.863014 -394.028829)
			(xy 43.863514 -394.06449) (xy 43.863014 -394.100151) (xy 44.496982 -394.100151) (xy 44.496982 -394.028829)
			(xy 44.504968 -393.957955) (xy 44.520838 -393.88842) (xy 44.544395 -393.8211) (xy 44.57534 -393.756841)
			(xy 44.613286 -393.69645) (xy 44.657755 -393.640688) (xy 44.708188 -393.590255) (xy 44.76395 -393.545786)
			(xy 44.824341 -393.50784) (xy 44.8886 -393.476895) (xy 44.95592 -393.453338) (xy 45.025455 -393.437468)
			(xy 45.096329 -393.429482) (xy 45.167651 -393.429482) (xy 45.238525 -393.437468) (xy 45.30806 -393.453338)
			(xy 45.37538 -393.476895) (xy 45.439639 -393.50784) (xy 45.50003 -393.545786) (xy 45.555792 -393.590255)
			(xy 45.606225 -393.640688) (xy 45.650694 -393.69645) (xy 45.68864 -393.756841) (xy 45.719585 -393.8211)
			(xy 45.743142 -393.88842) (xy 45.759012 -393.957955) (xy 45.766998 -394.028829) (xy 45.767498 -394.06449)
			(xy 45.766998 -394.100151) (xy 45.759012 -394.171025) (xy 45.743142 -394.24056) (xy 45.719585 -394.30788)
			(xy 45.68864 -394.372139) (xy 45.650694 -394.43253) (xy 45.606225 -394.488292) (xy 45.555792 -394.538725)
			(xy 45.50003 -394.583194) (xy 45.439639 -394.62114) (xy 45.37538 -394.652085) (xy 45.30806 -394.675642)
			(xy 45.238525 -394.691512) (xy 45.167651 -394.699498) (xy 45.096329 -394.699498) (xy 45.025455 -394.691512)
			(xy 44.95592 -394.675642) (xy 44.8886 -394.652085) (xy 44.824341 -394.62114) (xy 44.76395 -394.583194)
			(xy 44.708188 -394.538725) (xy 44.657755 -394.488292) (xy 44.613286 -394.43253) (xy 44.57534 -394.372139)
			(xy 44.544395 -394.30788) (xy 44.520838 -394.24056) (xy 44.504968 -394.171025) (xy 44.496982 -394.100151)
			(xy 43.863014 -394.100151) (xy 43.855028 -394.171025) (xy 43.839158 -394.24056) (xy 43.815601 -394.30788)
			(xy 43.784656 -394.372139) (xy 43.74671 -394.43253) (xy 43.702241 -394.488292) (xy 43.651808 -394.538725)
			(xy 43.596046 -394.583194) (xy 43.535655 -394.62114) (xy 43.471396 -394.652085) (xy 43.404076 -394.675642)
			(xy 43.334541 -394.691512) (xy 43.263667 -394.699498) (xy 43.192345 -394.699498) (xy 43.121471 -394.691512)
			(xy 43.051936 -394.675642) (xy 42.984616 -394.652085) (xy 42.920357 -394.62114) (xy 42.859966 -394.583194)
			(xy 42.804204 -394.538725) (xy 42.753771 -394.488292) (xy 42.709302 -394.43253) (xy 42.671356 -394.372139)
			(xy 42.640411 -394.30788) (xy 42.616854 -394.24056) (xy 42.600984 -394.171025) (xy 42.592998 -394.100151)
			(xy 41.621972 -394.100151) (xy 41.613986 -394.171025) (xy 41.598116 -394.24056) (xy 41.574559 -394.30788)
			(xy 41.543614 -394.372139) (xy 41.505668 -394.43253) (xy 41.461199 -394.488292) (xy 41.410766 -394.538725)
			(xy 41.355004 -394.583194) (xy 41.294613 -394.62114) (xy 41.230354 -394.652085) (xy 41.163034 -394.675642)
			(xy 41.093499 -394.691512) (xy 41.022625 -394.699498) (xy 40.951303 -394.699498) (xy 40.880429 -394.691512)
			(xy 40.810894 -394.675642) (xy 40.743574 -394.652085) (xy 40.679315 -394.62114) (xy 40.618924 -394.583194)
			(xy 40.563162 -394.538725) (xy 40.512729 -394.488292) (xy 40.46826 -394.43253) (xy 40.430314 -394.372139)
			(xy 40.399369 -394.30788) (xy 40.375812 -394.24056) (xy 40.359942 -394.171025) (xy 40.351956 -394.100151)
			(xy 39.73526 -394.100151) (xy 39.727274 -394.171025) (xy 39.711404 -394.24056) (xy 39.687847 -394.30788)
			(xy 39.656902 -394.372139) (xy 39.618956 -394.43253) (xy 39.574487 -394.488292) (xy 39.524054 -394.538725)
			(xy 39.468292 -394.583194) (xy 39.407901 -394.62114) (xy 39.343642 -394.652085) (xy 39.276322 -394.675642)
			(xy 39.206787 -394.691512) (xy 39.135913 -394.699498) (xy 39.064591 -394.699498) (xy 38.993717 -394.691512)
			(xy 38.924182 -394.675642) (xy 38.856862 -394.652085) (xy 38.792603 -394.62114) (xy 38.732212 -394.583194)
			(xy 38.67645 -394.538725) (xy 38.626017 -394.488292) (xy 38.581548 -394.43253) (xy 38.543602 -394.372139)
			(xy 38.512657 -394.30788) (xy 38.4891 -394.24056) (xy 38.47323 -394.171025) (xy 38.465244 -394.100151)
			(xy 36.41191 -394.100151) (xy 36.400327 -394.130051) (xy 36.361593 -394.20784) (xy 36.315846 -394.281724)
			(xy 36.263477 -394.351071) (xy 36.204933 -394.415291) (xy 36.140713 -394.473835) (xy 36.071366 -394.526204)
			(xy 35.997482 -394.571951) (xy 35.919693 -394.610685) (xy 35.838661 -394.642077) (xy 35.755079 -394.665858)
			(xy 35.669659 -394.681826) (xy 35.58313 -394.689844) (xy 35.49623 -394.689844) (xy 35.409701 -394.681826)
			(xy 35.324281 -394.665858) (xy 35.240699 -394.642077) (xy 35.159667 -394.610685) (xy 35.081878 -394.571951)
			(xy 35.007994 -394.526204) (xy 34.938647 -394.473835) (xy 34.874427 -394.415291) (xy 34.815883 -394.351071)
			(xy 34.763514 -394.281724) (xy 34.717767 -394.20784) (xy 34.679033 -394.130051) (xy 34.647641 -394.049019)
			(xy 34.62386 -393.965437) (xy 34.607892 -393.880017) (xy 34.599874 -393.793488) (xy 31.3995 -393.793488)
			(xy 31.391522 -393.879749) (xy 31.375606 -393.96504) (xy 31.351902 -394.048501) (xy 31.320609 -394.129424)
			(xy 31.281995 -394.207119) (xy 31.236387 -394.280928) (xy 31.184174 -394.35022) (xy 31.125799 -394.414409)
			(xy 31.061759 -394.472946) (xy 30.992599 -394.525335) (xy 30.918907 -394.57113) (xy 30.84131 -394.609942)
			(xy 30.760467 -394.64144) (xy 30.677066 -394.665357) (xy 30.591817 -394.681489) (xy 30.505444 -394.689699)
			(xy 30.418681 -394.689917) (xy 30.332268 -394.682141) (xy 30.246939 -394.666438) (xy 30.163419 -394.642941)
			(xy 30.082418 -394.61185) (xy 30.004627 -394.573429) (xy 29.930705 -394.528005) (xy 29.861283 -394.475964)
			(xy 29.828744 -394.447268) (xy 29.811703 -394.432502) (xy 29.773459 -394.408621) (xy 29.731602 -394.391862)
			(xy 29.687444 -394.382753) (xy 29.642372 -394.381577) (xy 29.5978 -394.388373) (xy 29.555126 -394.402928)
			(xy 29.51569 -394.424783) (xy 29.48073 -394.453254) (xy 29.451341 -394.487447) (xy 29.428447 -394.52629)
			(xy 29.412766 -394.568562) (xy 29.404789 -394.612939) (xy 29.40431 -394.635482) (xy 29.40431 -395.404594)
			(xy 29.404797 -395.427138) (xy 29.412756 -395.471518) (xy 29.428424 -395.513796) (xy 29.451309 -395.552644)
			(xy 29.480693 -395.586842) (xy 29.515653 -395.615316) (xy 29.55509 -395.637171) (xy 29.597766 -395.651721)
			(xy 29.64234 -395.658508) (xy 29.687412 -395.65732) (xy 29.731567 -395.648194) (xy 29.773417 -395.631417)
			(xy 29.811648 -395.607515) (xy 29.828744 -395.592808) (xy 29.861244 -395.564069) (xy 29.930663 -395.512024)
			(xy 30.004582 -395.466596) (xy 30.082372 -395.428171) (xy 30.16337 -395.397075) (xy 30.246889 -395.373573)
			(xy 30.332218 -395.357866) (xy 30.41863 -395.350085) (xy 30.505393 -395.350299) (xy 30.591766 -395.358504)
			(xy 30.677016 -395.374631) (xy 30.760419 -395.398543) (xy 30.841263 -395.430037) (xy 30.918863 -395.468845)
			(xy 30.992557 -395.514636) (xy 31.06172 -395.567021) (xy 31.125763 -395.625555) (xy 31.184141 -395.68974)
			(xy 31.236358 -395.75903) (xy 31.28197 -395.832836) (xy 31.320588 -395.91053) (xy 31.351885 -395.991451)
			(xy 31.375595 -396.074911) (xy 31.391515 -396.1602) (xy 31.39951 -396.246593) (xy 31.399512 -396.333356)
			(xy 31.3995 -396.333488) (xy 34.599874 -396.333488) (xy 34.599874 -396.246588) (xy 34.607892 -396.160059)
			(xy 34.62386 -396.074639) (xy 34.647641 -395.991057) (xy 34.679033 -395.910025) (xy 34.717767 -395.832236)
			(xy 34.763514 -395.758352) (xy 34.815883 -395.689005) (xy 34.874427 -395.624785) (xy 34.938647 -395.566241)
			(xy 35.007994 -395.513872) (xy 35.081878 -395.468125) (xy 35.159667 -395.429391) (xy 35.240699 -395.397999)
			(xy 35.324281 -395.374218) (xy 35.409701 -395.35825) (xy 35.49623 -395.350232) (xy 35.58313 -395.350232)
			(xy 35.669659 -395.35825) (xy 35.755079 -395.374218) (xy 35.838661 -395.397999) (xy 35.919693 -395.429391)
			(xy 35.997482 -395.468125) (xy 36.071366 -395.513872) (xy 36.140713 -395.566241) (xy 36.165583 -395.588913)
			(xy 47.708556 -395.588913) (xy 47.708556 -395.507803) (xy 47.716506 -395.427084) (xy 47.732329 -395.347533)
			(xy 47.755874 -395.269917) (xy 47.786913 -395.194981) (xy 47.825148 -395.123449) (xy 47.87021 -395.056009)
			(xy 47.921665 -394.99331) (xy 47.979018 -394.935957) (xy 48.041717 -394.884502) (xy 48.109157 -394.83944)
			(xy 48.180689 -394.801205) (xy 48.255625 -394.770166) (xy 48.333241 -394.746621) (xy 48.412792 -394.730798)
			(xy 48.493511 -394.722848) (xy 48.574621 -394.722848) (xy 48.65534 -394.730798) (xy 48.734891 -394.746621)
			(xy 48.812507 -394.770166) (xy 48.887443 -394.801205) (xy 48.958975 -394.83944) (xy 49.026415 -394.884502)
			(xy 49.089114 -394.935957) (xy 49.146467 -394.99331) (xy 49.197922 -395.056009) (xy 49.242984 -395.123449)
			(xy 49.281219 -395.194981) (xy 49.312258 -395.269917) (xy 49.335803 -395.347533) (xy 49.351626 -395.427084)
			(xy 49.359576 -395.507803) (xy 49.360074 -395.548358) (xy 49.359576 -395.588913) (xy 49.351626 -395.669632)
			(xy 49.335803 -395.749183) (xy 49.312258 -395.826799) (xy 49.281219 -395.901735) (xy 49.242984 -395.973267)
			(xy 49.197922 -396.040707) (xy 49.146467 -396.103406) (xy 49.089114 -396.160759) (xy 49.026415 -396.212214)
			(xy 48.958975 -396.257276) (xy 48.887443 -396.295511) (xy 48.812507 -396.32655) (xy 48.734891 -396.350095)
			(xy 48.65534 -396.365918) (xy 48.574621 -396.373868) (xy 48.493511 -396.373868) (xy 48.412792 -396.365918)
			(xy 48.333241 -396.350095) (xy 48.255625 -396.32655) (xy 48.180689 -396.295511) (xy 48.109157 -396.257276)
			(xy 48.041717 -396.212214) (xy 47.979018 -396.160759) (xy 47.921665 -396.103406) (xy 47.87021 -396.040707)
			(xy 47.825148 -395.973267) (xy 47.786913 -395.901735) (xy 47.755874 -395.826799) (xy 47.732329 -395.749183)
			(xy 47.716506 -395.669632) (xy 47.708556 -395.588913) (xy 36.165583 -395.588913) (xy 36.204933 -395.624785)
			(xy 36.263477 -395.689005) (xy 36.315846 -395.758352) (xy 36.361593 -395.832236) (xy 36.400327 -395.910025)
			(xy 36.431719 -395.991057) (xy 36.4555 -396.074639) (xy 36.471468 -396.160059) (xy 36.479486 -396.246588)
			(xy 36.479988 -396.290038) (xy 36.479486 -396.333488) (xy 36.471468 -396.420017) (xy 36.4555 -396.505437)
			(xy 36.431719 -396.589019) (xy 36.400327 -396.670051) (xy 36.361593 -396.74784) (xy 36.315846 -396.821724)
			(xy 36.285012 -396.862554) (xy 71.895208 -396.862554) (xy 71.895208 -395.785594) (xy 71.89565 -395.754447)
			(xy 71.90326 -395.692619) (xy 71.918366 -395.632184) (xy 71.940741 -395.574047) (xy 71.97005 -395.519079)
			(xy 72.005855 -395.468102) (xy 72.047618 -395.421881) (xy 72.094715 -395.381108) (xy 72.14644 -395.346393)
			(xy 72.202018 -395.318256) (xy 72.260617 -395.29712) (xy 72.321359 -395.2833) (xy 72.383334 -395.277003)
			(xy 72.445614 -395.278324) (xy 72.507267 -395.287243) (xy 72.567368 -395.303626) (xy 72.625018 -395.327229)
			(xy 72.679353 -395.357697) (xy 72.729559 -395.394574) (xy 72.774885 -395.437307) (xy 72.79513 -395.460982)
			(xy 72.809747 -395.477852) (xy 72.843822 -395.506681) (xy 72.882408 -395.529115) (xy 72.924318 -395.544465)
			(xy 72.968266 -395.552261) (xy 73.0129 -395.552261) (xy 73.056848 -395.544465) (xy 73.098758 -395.529115)
			(xy 73.137344 -395.506681) (xy 73.171419 -395.477852) (xy 73.186036 -395.460982) (xy 73.207092 -395.436379)
			(xy 73.254434 -395.392195) (xy 73.307003 -395.354378) (xy 73.363947 -395.323541) (xy 73.424345 -395.300182)
			(xy 73.48722 -395.28468) (xy 73.551554 -395.277286) (xy 73.616307 -395.278118) (xy 73.68043 -395.287164)
			(xy 73.742885 -395.304277) (xy 73.802663 -395.329181) (xy 73.858796 -395.361472) (xy 73.910375 -395.400627)
			(xy 73.956566 -395.446014) (xy 73.976992 -395.471142) (xy 73.991595 -395.488874) (xy 74.026045 -395.519254)
			(xy 74.065393 -395.542949) (xy 74.108359 -395.559187) (xy 74.153543 -395.567441) (xy 74.199475 -395.567441)
			(xy 74.244659 -395.559187) (xy 74.287625 -395.542949) (xy 74.326973 -395.519254) (xy 74.361423 -395.488874)
			(xy 74.376026 -395.471142) (xy 74.395993 -395.4465) (xy 74.441125 -395.401936) (xy 74.491448 -395.36333)
			(xy 74.546183 -395.331282) (xy 74.604477 -395.306291) (xy 74.665428 -395.288743) (xy 74.728087 -395.278912)
			(xy 74.791483 -395.27695) (xy 74.85463 -395.282888) (xy 74.916549 -395.296633) (xy 74.976278 -395.317971)
			(xy 75.032889 -395.346573) (xy 75.085504 -395.381993) (xy 75.133305 -395.423681) (xy 75.15479 -395.447012)
			(xy 75.171029 -395.464397) (xy 75.208754 -395.493368) (xy 75.251211 -395.514815) (xy 75.296916 -395.527991)
			(xy 75.344274 -395.532435) (xy 75.391632 -395.527991) (xy 75.437337 -395.514815) (xy 75.479794 -395.493368)
			(xy 75.517519 -395.464397) (xy 75.533758 -395.447012) (xy 75.555648 -395.423259) (xy 75.604413 -395.380898)
			(xy 75.65815 -395.345055) (xy 75.715996 -395.316308) (xy 75.777016 -395.29512) (xy 75.840229 -395.281833)
			(xy 75.904616 -395.276659) (xy 75.96914 -395.279683) (xy 76.032761 -395.290857) (xy 76.094454 -395.309999)
			(xy 76.153225 -395.336801) (xy 76.208128 -395.370832) (xy 76.258278 -395.411544) (xy 76.302867 -395.45828)
			(xy 76.341176 -395.510288) (xy 76.37259 -395.56673) (xy 76.3966 -395.626696) (xy 76.412821 -395.689221)
			(xy 76.420992 -395.753297) (xy 76.421488 -395.785594) (xy 76.421488 -396.862554) (xy 76.420967 -396.895289)
			(xy 76.412532 -396.960214) (xy 76.395833 -397.023519) (xy 76.371147 -397.084157) (xy 76.338882 -397.141125)
			(xy 76.319634 -397.167608) (xy 76.294488 -397.20139) (xy 76.294488 -397.218408) (xy 76.278994 -397.218408)
			(xy 76.24318 -397.248888) (xy 76.218003 -397.269741) (xy 76.163271 -397.305492) (xy 76.104406 -397.333931)
			(xy 76.042381 -397.354586) (xy 75.978219 -397.367117) (xy 75.91298 -397.371317) (xy 75.847741 -397.367117)
			(xy 75.783579 -397.354586) (xy 75.721554 -397.333931) (xy 75.662689 -397.305492) (xy 75.607957 -397.269741)
			(xy 75.58278 -397.248888) (xy 75.546966 -397.218408) (xy 75.531472 -397.218408) (xy 75.531472 -397.20139)
			(xy 75.506326 -397.167608) (xy 75.492729 -397.149036) (xy 75.468559 -397.109862) (xy 75.458066 -397.089376)
			(xy 75.450663 -397.075541) (xy 75.430256 -397.051717) (xy 75.404655 -397.033591) (xy 75.375405 -397.022258)
			(xy 75.344274 -397.018403) (xy 75.313143 -397.022258) (xy 75.283893 -397.033591) (xy 75.258292 -397.051717)
			(xy 75.237885 -397.075541) (xy 75.230482 -397.089376) (xy 75.219991 -397.109863) (xy 75.195821 -397.149038)
			(xy 75.182222 -397.167608) (xy 75.157076 -397.20139) (xy 75.157076 -397.218408) (xy 75.141582 -397.218408)
			(xy 75.105768 -397.248888) (xy 75.080591 -397.269741) (xy 75.025859 -397.305492) (xy 74.966994 -397.333931)
			(xy 74.904969 -397.354586) (xy 74.840807 -397.367117) (xy 74.775568 -397.371317) (xy 74.710329 -397.367117)
			(xy 74.646167 -397.354586) (xy 74.584142 -397.333931) (xy 74.525277 -397.305492) (xy 74.470545 -397.269741)
			(xy 74.445368 -397.248888) (xy 74.409554 -397.218408) (xy 74.39406 -397.218408) (xy 74.39406 -397.20139)
			(xy 74.368914 -397.167608) (xy 74.34631 -397.136269) (xy 74.309826 -397.068157) (xy 74.29627 -397.031972)
			(xy 74.290625 -397.017353) (xy 74.273314 -396.991241) (xy 74.250159 -396.970139) (xy 74.222556 -396.95532)
			(xy 74.192173 -396.94768) (xy 74.160845 -396.94768) (xy 74.130462 -396.95532) (xy 74.102859 -396.970139)
			(xy 74.079704 -396.991241) (xy 74.062393 -397.017353) (xy 74.056748 -397.031972) (xy 74.043195 -397.068158)
			(xy 74.006713 -397.136272) (xy 73.984104 -397.167608) (xy 73.958704 -397.20139) (xy 73.958704 -397.218408)
			(xy 73.943464 -397.218408) (xy 73.90765 -397.248888) (xy 73.882473 -397.269741) (xy 73.827741 -397.305492)
			(xy 73.768876 -397.333931) (xy 73.706851 -397.354586) (xy 73.642689 -397.367117) (xy 73.57745 -397.371317)
			(xy 73.512211 -397.367117) (xy 73.448049 -397.354586) (xy 73.386024 -397.333931) (xy 73.327159 -397.305492)
			(xy 73.272427 -397.269741) (xy 73.24725 -397.248888) (xy 73.211436 -397.218408) (xy 73.196196 -397.218408)
			(xy 73.196196 -397.20139) (xy 73.170796 -397.167608) (xy 73.152059 -397.141866) (xy 73.120474 -397.086582)
			(xy 73.107804 -397.057372) (xy 73.100936 -397.042215) (xy 73.080683 -397.015829) (xy 73.054292 -396.995583)
			(xy 73.023561 -396.982855) (xy 72.990583 -396.978514) (xy 72.957605 -396.982855) (xy 72.926874 -396.995583)
			(xy 72.900483 -397.015829) (xy 72.88023 -397.042215) (xy 72.873362 -397.057372) (xy 72.860692 -397.086581)
			(xy 72.829098 -397.14186) (xy 72.81037 -397.167608) (xy 72.785224 -397.20139) (xy 72.785224 -397.218408)
			(xy 72.76973 -397.218408) (xy 72.733916 -397.248888) (xy 72.708739 -397.269741) (xy 72.654007 -397.305492)
			(xy 72.595142 -397.333931) (xy 72.533117 -397.354586) (xy 72.468955 -397.367117) (xy 72.403716 -397.371317)
			(xy 72.338477 -397.367117) (xy 72.274315 -397.354586) (xy 72.21229 -397.333931) (xy 72.153425 -397.305492)
			(xy 72.098693 -397.269741) (xy 72.073516 -397.248888) (xy 72.037702 -397.218408) (xy 72.022208 -397.218408)
			(xy 72.022208 -397.20139) (xy 71.997062 -397.167608) (xy 71.977816 -397.141123) (xy 71.945552 -397.084155)
			(xy 71.920867 -397.023518) (xy 71.904168 -396.960213) (xy 71.895732 -396.895289) (xy 71.895208 -396.862554)
			(xy 36.285012 -396.862554) (xy 36.263477 -396.891071) (xy 36.204933 -396.955291) (xy 36.140713 -397.013835)
			(xy 36.071366 -397.066204) (xy 35.997482 -397.111951) (xy 35.919693 -397.150685) (xy 35.838661 -397.182077)
			(xy 35.755079 -397.205858) (xy 35.669659 -397.221826) (xy 35.58313 -397.229844) (xy 35.49623 -397.229844)
			(xy 35.409701 -397.221826) (xy 35.324281 -397.205858) (xy 35.240699 -397.182077) (xy 35.159667 -397.150685)
			(xy 35.081878 -397.111951) (xy 35.007994 -397.066204) (xy 34.938647 -397.013835) (xy 34.874427 -396.955291)
			(xy 34.815883 -396.891071) (xy 34.763514 -396.821724) (xy 34.717767 -396.74784) (xy 34.679033 -396.670051)
			(xy 34.647641 -396.589019) (xy 34.62386 -396.505437) (xy 34.607892 -396.420017) (xy 34.599874 -396.333488)
			(xy 31.3995 -396.333488) (xy 31.391522 -396.419749) (xy 31.375606 -396.50504) (xy 31.351902 -396.588501)
			(xy 31.320609 -396.669424) (xy 31.281995 -396.747119) (xy 31.236387 -396.820928) (xy 31.184174 -396.89022)
			(xy 31.125799 -396.954409) (xy 31.061759 -397.012946) (xy 30.992599 -397.065335) (xy 30.918907 -397.11113)
			(xy 30.84131 -397.149942) (xy 30.760467 -397.18144) (xy 30.677066 -397.205357) (xy 30.591817 -397.221489)
			(xy 30.505444 -397.229699) (xy 30.418681 -397.229917) (xy 30.332268 -397.222141) (xy 30.246939 -397.206438)
			(xy 30.163419 -397.182941) (xy 30.082418 -397.15185) (xy 30.004627 -397.113429) (xy 29.930705 -397.068005)
			(xy 29.861283 -397.015964) (xy 29.828744 -396.987268) (xy 29.811703 -396.972502) (xy 29.773459 -396.948621)
			(xy 29.731602 -396.931862) (xy 29.687444 -396.922753) (xy 29.642372 -396.921577) (xy 29.5978 -396.928373)
			(xy 29.555126 -396.942928) (xy 29.51569 -396.964783) (xy 29.48073 -396.993254) (xy 29.451341 -397.027447)
			(xy 29.428447 -397.06629) (xy 29.412766 -397.108562) (xy 29.404789 -397.152939) (xy 29.40431 -397.175482)
			(xy 29.40431 -397.944594) (xy 29.404797 -397.967138) (xy 29.412756 -398.011518) (xy 29.428424 -398.053796)
			(xy 29.451309 -398.092644) (xy 29.480693 -398.126842) (xy 29.515653 -398.155316) (xy 29.55509 -398.177171)
			(xy 29.597766 -398.191721) (xy 29.64234 -398.198508) (xy 29.687412 -398.19732) (xy 29.731567 -398.188194)
			(xy 29.773417 -398.171417) (xy 29.811648 -398.147515) (xy 29.828744 -398.132808) (xy 29.861244 -398.104069)
			(xy 29.930663 -398.052024) (xy 30.004582 -398.006596) (xy 30.082372 -397.968171) (xy 30.16337 -397.937075)
			(xy 30.246889 -397.913573) (xy 30.332218 -397.897866) (xy 30.41863 -397.890085) (xy 30.505393 -397.890299)
			(xy 30.591766 -397.898504) (xy 30.677016 -397.914631) (xy 30.760419 -397.938543) (xy 30.841263 -397.970037)
			(xy 30.918863 -398.008845) (xy 30.992557 -398.054636) (xy 31.06172 -398.107021) (xy 31.125763 -398.165555)
			(xy 31.184141 -398.22974) (xy 31.236358 -398.29903) (xy 31.28197 -398.372836) (xy 31.320588 -398.45053)
			(xy 31.351885 -398.531451) (xy 31.375595 -398.614911) (xy 31.391515 -398.7002) (xy 31.39951 -398.786593)
			(xy 31.399512 -398.873356) (xy 31.3995 -398.873488) (xy 34.599874 -398.873488) (xy 34.599874 -398.786588)
			(xy 34.607892 -398.700059) (xy 34.62386 -398.614639) (xy 34.647641 -398.531057) (xy 34.679033 -398.450025)
			(xy 34.717767 -398.372236) (xy 34.763514 -398.298352) (xy 34.815883 -398.229005) (xy 34.874427 -398.164785)
			(xy 34.938647 -398.106241) (xy 35.007994 -398.053872) (xy 35.081878 -398.008125) (xy 35.159667 -397.969391)
			(xy 35.240699 -397.937999) (xy 35.324281 -397.914218) (xy 35.409701 -397.89825) (xy 35.49623 -397.890232)
			(xy 35.58313 -397.890232) (xy 35.669659 -397.89825) (xy 35.755079 -397.914218) (xy 35.838661 -397.937999)
			(xy 35.839293 -397.938244) (xy 84.320378 -397.938244) (xy 84.324449 -397.882622) (xy 84.336575 -397.828185)
			(xy 84.356498 -397.776094) (xy 84.383794 -397.727459) (xy 84.41788 -397.683316) (xy 84.458029 -397.644607)
			(xy 84.503387 -397.612156) (xy 84.552987 -397.586655) (xy 84.605771 -397.568648) (xy 84.660614 -397.558518)
			(xy 84.716348 -397.556481) (xy 84.771785 -397.562581) (xy 84.825742 -397.576687) (xy 84.877071 -397.598499)
			(xy 84.924677 -397.627553) (xy 84.967545 -397.663228) (xy 85.004762 -397.704765) (xy 85.035535 -397.751278)
			(xy 85.054358 -397.791432) (xy 93.046548 -397.791432) (xy 93.050619 -397.73581) (xy 93.062745 -397.681373)
			(xy 93.082668 -397.629282) (xy 93.109964 -397.580647) (xy 93.14405 -397.536504) (xy 93.184199 -397.497795)
			(xy 93.229557 -397.465344) (xy 93.279157 -397.439843) (xy 93.331941 -397.421836) (xy 93.386784 -397.411706)
			(xy 93.442518 -397.409669) (xy 93.497955 -397.415769) (xy 93.551912 -397.429875) (xy 93.603241 -397.451687)
			(xy 93.650847 -397.480741) (xy 93.693715 -397.516416) (xy 93.730932 -397.557953) (xy 93.761705 -397.604466)
			(xy 93.785377 -397.654963) (xy 93.801445 -397.70837) (xy 93.809565 -397.763546) (xy 93.810074 -397.791432)
			(xy 93.809565 -397.819318) (xy 93.801445 -397.874494) (xy 93.785377 -397.927901) (xy 93.761705 -397.978398)
			(xy 93.730932 -398.024911) (xy 93.693715 -398.066448) (xy 93.650847 -398.102123) (xy 93.603241 -398.131177)
			(xy 93.551912 -398.152989) (xy 93.497955 -398.167095) (xy 93.442518 -398.173195) (xy 93.386784 -398.171158)
			(xy 93.331941 -398.161028) (xy 93.279157 -398.143021) (xy 93.229557 -398.11752) (xy 93.184199 -398.085069)
			(xy 93.14405 -398.04636) (xy 93.109964 -398.002217) (xy 93.082668 -397.953582) (xy 93.062745 -397.901491)
			(xy 93.050619 -397.847054) (xy 93.046548 -397.791432) (xy 85.054358 -397.791432) (xy 85.059207 -397.801775)
			(xy 85.075275 -397.855182) (xy 85.083395 -397.910358) (xy 85.083904 -397.938244) (xy 85.083395 -397.96613)
			(xy 85.075275 -398.021306) (xy 85.059207 -398.074713) (xy 85.035535 -398.12521) (xy 85.004762 -398.171723)
			(xy 84.967545 -398.21326) (xy 84.924677 -398.248935) (xy 84.877071 -398.277989) (xy 84.825742 -398.299801)
			(xy 84.771785 -398.313907) (xy 84.716348 -398.320007) (xy 84.660614 -398.31797) (xy 84.605771 -398.30784)
			(xy 84.552987 -398.289833) (xy 84.503387 -398.264332) (xy 84.458029 -398.231881) (xy 84.41788 -398.193172)
			(xy 84.383794 -398.149029) (xy 84.356498 -398.100394) (xy 84.336575 -398.048303) (xy 84.324449 -397.993866)
			(xy 84.320378 -397.938244) (xy 35.839293 -397.938244) (xy 35.919693 -397.969391) (xy 35.997482 -398.008125)
			(xy 36.071366 -398.053872) (xy 36.140713 -398.106241) (xy 36.204933 -398.164785) (xy 36.263477 -398.229005)
			(xy 36.315846 -398.298352) (xy 36.361593 -398.372236) (xy 36.400327 -398.450025) (xy 36.431719 -398.531057)
			(xy 36.4555 -398.614639) (xy 36.471468 -398.700059) (xy 36.479486 -398.786588) (xy 36.479988 -398.830038)
			(xy 36.479486 -398.873488) (xy 36.471468 -398.960017) (xy 36.461247 -399.014696) (xy 81.842862 -399.014696)
			(xy 81.846933 -398.959074) (xy 81.859059 -398.904637) (xy 81.878982 -398.852546) (xy 81.906278 -398.803911)
			(xy 81.940364 -398.759768) (xy 81.980513 -398.721059) (xy 82.025871 -398.688608) (xy 82.075471 -398.663107)
			(xy 82.128255 -398.6451) (xy 82.183098 -398.63497) (xy 82.238832 -398.632933) (xy 82.294269 -398.639033)
			(xy 82.348226 -398.653139) (xy 82.399555 -398.674951) (xy 82.447161 -398.704005) (xy 82.490029 -398.73968)
			(xy 82.527246 -398.781217) (xy 82.557866 -398.827498) (xy 88.190322 -398.827498) (xy 88.194393 -398.771876)
			(xy 88.206519 -398.717439) (xy 88.226442 -398.665348) (xy 88.253738 -398.616713) (xy 88.287824 -398.57257)
			(xy 88.327973 -398.533861) (xy 88.373331 -398.50141) (xy 88.422931 -398.475909) (xy 88.475715 -398.457902)
			(xy 88.530558 -398.447772) (xy 88.586292 -398.445735) (xy 88.641729 -398.451835) (xy 88.695686 -398.465941)
			(xy 88.747015 -398.487753) (xy 88.763903 -398.49806) (xy 91.314776 -398.49806) (xy 91.318847 -398.442438)
			(xy 91.330973 -398.388001) (xy 91.350896 -398.33591) (xy 91.378192 -398.287275) (xy 91.412278 -398.243132)
			(xy 91.452427 -398.204423) (xy 91.497785 -398.171972) (xy 91.547385 -398.146471) (xy 91.600169 -398.128464)
			(xy 91.655012 -398.118334) (xy 91.710746 -398.116297) (xy 91.766183 -398.122397) (xy 91.82014 -398.136503)
			(xy 91.871469 -398.158315) (xy 91.919075 -398.187369) (xy 91.961943 -398.223044) (xy 91.99916 -398.264581)
			(xy 92.029933 -398.311094) (xy 92.053605 -398.361591) (xy 92.069673 -398.414998) (xy 92.077793 -398.470174)
			(xy 92.078302 -398.49806) (xy 92.077793 -398.525946) (xy 92.069673 -398.581122) (xy 92.053605 -398.634529)
			(xy 92.029933 -398.685026) (xy 91.99916 -398.731539) (xy 91.961943 -398.773076) (xy 91.919075 -398.808751)
			(xy 91.871469 -398.837805) (xy 91.82014 -398.859617) (xy 91.766183 -398.873723) (xy 91.710746 -398.879823)
			(xy 91.655012 -398.877786) (xy 91.600169 -398.867656) (xy 91.547385 -398.849649) (xy 91.497785 -398.824148)
			(xy 91.452427 -398.791697) (xy 91.412278 -398.752988) (xy 91.378192 -398.708845) (xy 91.350896 -398.66021)
			(xy 91.330973 -398.608119) (xy 91.318847 -398.553682) (xy 91.314776 -398.49806) (xy 88.763903 -398.49806)
			(xy 88.794621 -398.516807) (xy 88.837489 -398.552482) (xy 88.874706 -398.594019) (xy 88.905479 -398.640532)
			(xy 88.929151 -398.691029) (xy 88.945219 -398.744436) (xy 88.953339 -398.799612) (xy 88.953848 -398.827498)
			(xy 88.953339 -398.855384) (xy 88.945219 -398.91056) (xy 88.929151 -398.963967) (xy 88.905479 -399.014464)
			(xy 88.894234 -399.03146) (xy 89.880438 -399.03146) (xy 89.884509 -398.975838) (xy 89.896635 -398.921401)
			(xy 89.916558 -398.86931) (xy 89.943854 -398.820675) (xy 89.97794 -398.776532) (xy 90.018089 -398.737823)
			(xy 90.063447 -398.705372) (xy 90.113047 -398.679871) (xy 90.165831 -398.661864) (xy 90.220674 -398.651734)
			(xy 90.276408 -398.649697) (xy 90.331845 -398.655797) (xy 90.385802 -398.669903) (xy 90.437131 -398.691715)
			(xy 90.484737 -398.720769) (xy 90.527605 -398.756444) (xy 90.564822 -398.797981) (xy 90.595595 -398.844494)
			(xy 90.619267 -398.894991) (xy 90.635335 -398.948398) (xy 90.643455 -399.003574) (xy 90.643964 -399.03146)
			(xy 90.643455 -399.059346) (xy 90.635335 -399.114522) (xy 90.619267 -399.167929) (xy 90.595595 -399.218426)
			(xy 90.564822 -399.264939) (xy 90.527605 -399.306476) (xy 90.484737 -399.342151) (xy 90.437131 -399.371205)
			(xy 90.385802 -399.393017) (xy 90.331845 -399.407123) (xy 90.276408 -399.413223) (xy 90.220674 -399.411186)
			(xy 90.165831 -399.401056) (xy 90.113047 -399.383049) (xy 90.063447 -399.357548) (xy 90.018089 -399.325097)
			(xy 89.97794 -399.286388) (xy 89.943854 -399.242245) (xy 89.916558 -399.19361) (xy 89.896635 -399.141519)
			(xy 89.884509 -399.087082) (xy 89.880438 -399.03146) (xy 88.894234 -399.03146) (xy 88.874706 -399.060977)
			(xy 88.837489 -399.102514) (xy 88.794621 -399.138189) (xy 88.747015 -399.167243) (xy 88.695686 -399.189055)
			(xy 88.641729 -399.203161) (xy 88.586292 -399.209261) (xy 88.530558 -399.207224) (xy 88.475715 -399.197094)
			(xy 88.422931 -399.179087) (xy 88.373331 -399.153586) (xy 88.327973 -399.121135) (xy 88.287824 -399.082426)
			(xy 88.253738 -399.038283) (xy 88.226442 -398.989648) (xy 88.206519 -398.937557) (xy 88.194393 -398.88312)
			(xy 88.190322 -398.827498) (xy 82.557866 -398.827498) (xy 82.558019 -398.82773) (xy 82.581691 -398.878227)
			(xy 82.597759 -398.931634) (xy 82.605879 -398.98681) (xy 82.606388 -399.014696) (xy 82.605879 -399.042582)
			(xy 82.597759 -399.097758) (xy 82.581691 -399.151165) (xy 82.558019 -399.201662) (xy 82.527246 -399.248175)
			(xy 82.505446 -399.272506) (xy 83.285328 -399.272506) (xy 83.289399 -399.216884) (xy 83.301525 -399.162447)
			(xy 83.321448 -399.110356) (xy 83.348744 -399.061721) (xy 83.38283 -399.017578) (xy 83.422979 -398.978869)
			(xy 83.468337 -398.946418) (xy 83.517937 -398.920917) (xy 83.570721 -398.90291) (xy 83.625564 -398.89278)
			(xy 83.681298 -398.890743) (xy 83.736735 -398.896843) (xy 83.790692 -398.910949) (xy 83.842021 -398.932761)
			(xy 83.889627 -398.961815) (xy 83.932495 -398.99749) (xy 83.969712 -399.039027) (xy 84.000485 -399.08554)
			(xy 84.024157 -399.136037) (xy 84.040225 -399.189444) (xy 84.048345 -399.24462) (xy 84.048854 -399.272506)
			(xy 84.048345 -399.300392) (xy 84.047178 -399.30832) (xy 86.84209 -399.30832) (xy 86.846161 -399.252698)
			(xy 86.858287 -399.198261) (xy 86.87821 -399.14617) (xy 86.905506 -399.097535) (xy 86.939592 -399.053392)
			(xy 86.979741 -399.014683) (xy 87.025099 -398.982232) (xy 87.074699 -398.956731) (xy 87.127483 -398.938724)
			(xy 87.182326 -398.928594) (xy 87.23806 -398.926557) (xy 87.293497 -398.932657) (xy 87.347454 -398.946763)
			(xy 87.398783 -398.968575) (xy 87.446389 -398.997629) (xy 87.489257 -399.033304) (xy 87.526474 -399.074841)
			(xy 87.557247 -399.121354) (xy 87.580919 -399.171851) (xy 87.596987 -399.225258) (xy 87.605107 -399.280434)
			(xy 87.605616 -399.30832) (xy 87.605107 -399.336206) (xy 87.596987 -399.391382) (xy 87.580919 -399.444789)
			(xy 87.557247 -399.495286) (xy 87.526474 -399.541799) (xy 87.489257 -399.583336) (xy 87.446389 -399.619011)
			(xy 87.398783 -399.648065) (xy 87.347454 -399.669877) (xy 87.293497 -399.683983) (xy 87.23806 -399.690083)
			(xy 87.182326 -399.688046) (xy 87.127483 -399.677916) (xy 87.074699 -399.659909) (xy 87.025099 -399.634408)
			(xy 86.979741 -399.601957) (xy 86.939592 -399.563248) (xy 86.905506 -399.519105) (xy 86.87821 -399.47047)
			(xy 86.858287 -399.418379) (xy 86.846161 -399.363942) (xy 86.84209 -399.30832) (xy 84.047178 -399.30832)
			(xy 84.040225 -399.355568) (xy 84.024157 -399.408975) (xy 84.000485 -399.459472) (xy 83.969712 -399.505985)
			(xy 83.932495 -399.547522) (xy 83.889627 -399.583197) (xy 83.842021 -399.612251) (xy 83.790692 -399.634063)
			(xy 83.736735 -399.648169) (xy 83.681298 -399.654269) (xy 83.625564 -399.652232) (xy 83.570721 -399.642102)
			(xy 83.517937 -399.624095) (xy 83.468337 -399.598594) (xy 83.422979 -399.566143) (xy 83.38283 -399.527434)
			(xy 83.348744 -399.483291) (xy 83.321448 -399.434656) (xy 83.301525 -399.382565) (xy 83.289399 -399.328128)
			(xy 83.285328 -399.272506) (xy 82.505446 -399.272506) (xy 82.490029 -399.289712) (xy 82.447161 -399.325387)
			(xy 82.399555 -399.354441) (xy 82.348226 -399.376253) (xy 82.294269 -399.390359) (xy 82.238832 -399.396459)
			(xy 82.183098 -399.394422) (xy 82.128255 -399.384292) (xy 82.075471 -399.366285) (xy 82.025871 -399.340784)
			(xy 81.980513 -399.308333) (xy 81.940364 -399.269624) (xy 81.906278 -399.225481) (xy 81.878982 -399.176846)
			(xy 81.859059 -399.124755) (xy 81.846933 -399.070318) (xy 81.842862 -399.014696) (xy 36.461247 -399.014696)
			(xy 36.4555 -399.045437) (xy 36.431719 -399.129019) (xy 36.400327 -399.210051) (xy 36.361593 -399.28784)
			(xy 36.315846 -399.361724) (xy 36.263477 -399.431071) (xy 36.204933 -399.495291) (xy 36.140713 -399.553835)
			(xy 36.071366 -399.606204) (xy 35.997482 -399.651951) (xy 35.919693 -399.690685) (xy 35.838661 -399.722077)
			(xy 35.755079 -399.745858) (xy 35.669659 -399.761826) (xy 35.58313 -399.769844) (xy 35.49623 -399.769844)
			(xy 35.409701 -399.761826) (xy 35.324281 -399.745858) (xy 35.240699 -399.722077) (xy 35.159667 -399.690685)
			(xy 35.081878 -399.651951) (xy 35.007994 -399.606204) (xy 34.938647 -399.553835) (xy 34.874427 -399.495291)
			(xy 34.815883 -399.431071) (xy 34.763514 -399.361724) (xy 34.717767 -399.28784) (xy 34.679033 -399.210051)
			(xy 34.647641 -399.129019) (xy 34.62386 -399.045437) (xy 34.607892 -398.960017) (xy 34.599874 -398.873488)
			(xy 31.3995 -398.873488) (xy 31.391522 -398.959749) (xy 31.375606 -399.04504) (xy 31.351902 -399.128501)
			(xy 31.320609 -399.209424) (xy 31.281995 -399.287119) (xy 31.236387 -399.360928) (xy 31.184174 -399.43022)
			(xy 31.125799 -399.494409) (xy 31.061759 -399.552946) (xy 30.992599 -399.605335) (xy 30.918907 -399.65113)
			(xy 30.84131 -399.689942) (xy 30.760467 -399.72144) (xy 30.677066 -399.745357) (xy 30.591817 -399.761489)
			(xy 30.505444 -399.769699) (xy 30.418681 -399.769917) (xy 30.332268 -399.762141) (xy 30.246939 -399.746438)
			(xy 30.163419 -399.722941) (xy 30.082418 -399.69185) (xy 30.004627 -399.653429) (xy 29.930705 -399.608005)
			(xy 29.861283 -399.555964) (xy 29.828744 -399.527268) (xy 29.811703 -399.512502) (xy 29.773459 -399.488621)
			(xy 29.731602 -399.471862) (xy 29.687444 -399.462753) (xy 29.642372 -399.461577) (xy 29.5978 -399.468373)
			(xy 29.555126 -399.482928) (xy 29.51569 -399.504783) (xy 29.48073 -399.533254) (xy 29.451341 -399.567447)
			(xy 29.428447 -399.60629) (xy 29.412766 -399.648562) (xy 29.404789 -399.692939) (xy 29.40431 -399.715482)
			(xy 29.40431 -400.271234) (xy 78.88554 -400.271234) (xy 78.889611 -400.215612) (xy 78.901737 -400.161175)
			(xy 78.92166 -400.109084) (xy 78.948956 -400.060449) (xy 78.983042 -400.016306) (xy 79.023191 -399.977597)
			(xy 79.068549 -399.945146) (xy 79.118149 -399.919645) (xy 79.170933 -399.901638) (xy 79.225776 -399.891508)
			(xy 79.28151 -399.889471) (xy 79.336947 -399.895571) (xy 79.390904 -399.909677) (xy 79.442233 -399.931489)
			(xy 79.489839 -399.960543) (xy 79.532707 -399.996218) (xy 79.542662 -400.007328) (xy 80.197704 -400.007328)
			(xy 80.201775 -399.951706) (xy 80.213901 -399.897269) (xy 80.233824 -399.845178) (xy 80.26112 -399.796543)
			(xy 80.295206 -399.7524) (xy 80.335355 -399.713691) (xy 80.380713 -399.68124) (xy 80.430313 -399.655739)
			(xy 80.483097 -399.637732) (xy 80.53794 -399.627602) (xy 80.593674 -399.625565) (xy 80.649111 -399.631665)
			(xy 80.703068 -399.645771) (xy 80.754397 -399.667583) (xy 80.802003 -399.696637) (xy 80.844871 -399.732312)
			(xy 80.855736 -399.744438) (xy 84.952584 -399.744438) (xy 84.956655 -399.688816) (xy 84.968781 -399.634379)
			(xy 84.988704 -399.582288) (xy 85.016 -399.533653) (xy 85.050086 -399.48951) (xy 85.090235 -399.450801)
			(xy 85.135593 -399.41835) (xy 85.185193 -399.392849) (xy 85.237977 -399.374842) (xy 85.29282 -399.364712)
			(xy 85.348554 -399.362675) (xy 85.403991 -399.368775) (xy 85.457948 -399.382881) (xy 85.509277 -399.404693)
			(xy 85.556883 -399.433747) (xy 85.599751 -399.469422) (xy 85.636968 -399.510959) (xy 85.667741 -399.557472)
			(xy 85.691413 -399.607969) (xy 85.707481 -399.661376) (xy 85.715601 -399.716552) (xy 85.71611 -399.744438)
			(xy 85.715601 -399.772324) (xy 85.707481 -399.8275) (xy 85.691413 -399.880907) (xy 85.667741 -399.931404)
			(xy 85.636968 -399.977917) (xy 85.599751 -400.019454) (xy 85.556883 -400.055129) (xy 85.509277 -400.084183)
			(xy 85.457948 -400.105995) (xy 85.437985 -400.111214) (xy 88.072212 -400.111214) (xy 88.076283 -400.055592)
			(xy 88.088409 -400.001155) (xy 88.108332 -399.949064) (xy 88.135628 -399.900429) (xy 88.169714 -399.856286)
			(xy 88.209863 -399.817577) (xy 88.255221 -399.785126) (xy 88.304821 -399.759625) (xy 88.357605 -399.741618)
			(xy 88.412448 -399.731488) (xy 88.468182 -399.729451) (xy 88.523619 -399.735551) (xy 88.577576 -399.749657)
			(xy 88.628905 -399.771469) (xy 88.676511 -399.800523) (xy 88.719379 -399.836198) (xy 88.756596 -399.877735)
			(xy 88.787369 -399.924248) (xy 88.811041 -399.974745) (xy 88.827109 -400.028152) (xy 88.835229 -400.083328)
			(xy 88.835738 -400.111214) (xy 88.835229 -400.1391) (xy 88.827109 -400.194276) (xy 88.811041 -400.247683)
			(xy 88.787369 -400.29818) (xy 88.756596 -400.344693) (xy 88.719379 -400.38623) (xy 88.676511 -400.421905)
			(xy 88.628905 -400.450959) (xy 88.577576 -400.472771) (xy 88.523619 -400.486877) (xy 88.468182 -400.492977)
			(xy 88.412448 -400.49094) (xy 88.357605 -400.48081) (xy 88.304821 -400.462803) (xy 88.255221 -400.437302)
			(xy 88.209863 -400.404851) (xy 88.169714 -400.366142) (xy 88.135628 -400.321999) (xy 88.108332 -400.273364)
			(xy 88.088409 -400.221273) (xy 88.076283 -400.166836) (xy 88.072212 -400.111214) (xy 85.437985 -400.111214)
			(xy 85.403991 -400.120101) (xy 85.348554 -400.126201) (xy 85.29282 -400.124164) (xy 85.237977 -400.114034)
			(xy 85.185193 -400.096027) (xy 85.135593 -400.070526) (xy 85.090235 -400.038075) (xy 85.050086 -399.999366)
			(xy 85.016 -399.955223) (xy 84.988704 -399.906588) (xy 84.968781 -399.854497) (xy 84.956655 -399.80006)
			(xy 84.952584 -399.744438) (xy 80.855736 -399.744438) (xy 80.882088 -399.773849) (xy 80.912861 -399.820362)
			(xy 80.936533 -399.870859) (xy 80.952601 -399.924266) (xy 80.960721 -399.979442) (xy 80.96123 -400.007328)
			(xy 80.960721 -400.035214) (xy 80.952601 -400.09039) (xy 80.936533 -400.143797) (xy 80.912861 -400.194294)
			(xy 80.882088 -400.240807) (xy 80.844871 -400.282344) (xy 80.802003 -400.318019) (xy 80.754397 -400.347073)
			(xy 80.703068 -400.368885) (xy 80.649111 -400.382991) (xy 80.593674 -400.389091) (xy 80.53794 -400.387054)
			(xy 80.483097 -400.376924) (xy 80.430313 -400.358917) (xy 80.380713 -400.333416) (xy 80.335355 -400.300965)
			(xy 80.295206 -400.262256) (xy 80.26112 -400.218113) (xy 80.233824 -400.169478) (xy 80.213901 -400.117387)
			(xy 80.201775 -400.06295) (xy 80.197704 -400.007328) (xy 79.542662 -400.007328) (xy 79.569924 -400.037755)
			(xy 79.600697 -400.084268) (xy 79.624369 -400.134765) (xy 79.640437 -400.188172) (xy 79.648557 -400.243348)
			(xy 79.649066 -400.271234) (xy 79.648557 -400.29912) (xy 79.640437 -400.354296) (xy 79.624369 -400.407703)
			(xy 79.600697 -400.4582) (xy 79.569924 -400.504713) (xy 79.532707 -400.54625) (xy 79.489839 -400.581925)
			(xy 79.442233 -400.610979) (xy 79.390904 -400.632791) (xy 79.336947 -400.646897) (xy 79.28151 -400.652997)
			(xy 79.225776 -400.65096) (xy 79.170933 -400.64083) (xy 79.118149 -400.622823) (xy 79.068549 -400.597322)
			(xy 79.023191 -400.564871) (xy 78.983042 -400.526162) (xy 78.948956 -400.482019) (xy 78.92166 -400.433384)
			(xy 78.901737 -400.381293) (xy 78.889611 -400.326856) (xy 78.88554 -400.271234) (xy 29.40431 -400.271234)
			(xy 29.40431 -400.484594) (xy 29.404797 -400.507138) (xy 29.412756 -400.551518) (xy 29.428424 -400.593796)
			(xy 29.451309 -400.632644) (xy 29.480693 -400.666842) (xy 29.515653 -400.695316) (xy 29.55509 -400.717171)
			(xy 29.597766 -400.731721) (xy 29.64234 -400.738508) (xy 29.687412 -400.73732) (xy 29.731567 -400.728194)
			(xy 29.773417 -400.711417) (xy 29.811648 -400.687515) (xy 29.828744 -400.672808) (xy 29.861244 -400.644069)
			(xy 29.930663 -400.592024) (xy 30.004582 -400.546596) (xy 30.082372 -400.508171) (xy 30.16337 -400.477075)
			(xy 30.246889 -400.453573) (xy 30.332218 -400.437866) (xy 30.41863 -400.430085) (xy 30.505393 -400.430299)
			(xy 30.591766 -400.438504) (xy 30.677016 -400.454631) (xy 30.760419 -400.478543) (xy 30.841263 -400.510037)
			(xy 30.918863 -400.548845) (xy 30.992557 -400.594636) (xy 31.06172 -400.647021) (xy 31.125763 -400.705555)
			(xy 31.184141 -400.76974) (xy 31.236358 -400.83903) (xy 31.28197 -400.912836) (xy 31.320588 -400.99053)
			(xy 31.351885 -401.071451) (xy 31.375595 -401.154911) (xy 31.391515 -401.2402) (xy 31.39951 -401.326593)
			(xy 31.399512 -401.413356) (xy 31.3995 -401.413488) (xy 34.599874 -401.413488) (xy 34.599874 -401.326588)
			(xy 34.607892 -401.240059) (xy 34.62386 -401.154639) (xy 34.647641 -401.071057) (xy 34.679033 -400.990025)
			(xy 34.717767 -400.912236) (xy 34.763514 -400.838352) (xy 34.815883 -400.769005) (xy 34.874427 -400.704785)
			(xy 34.938647 -400.646241) (xy 35.007994 -400.593872) (xy 35.081878 -400.548125) (xy 35.159667 -400.509391)
			(xy 35.240699 -400.477999) (xy 35.324281 -400.454218) (xy 35.409701 -400.43825) (xy 35.49623 -400.430232)
			(xy 35.58313 -400.430232) (xy 35.669659 -400.43825) (xy 35.755079 -400.454218) (xy 35.838661 -400.477999)
			(xy 35.919693 -400.509391) (xy 35.997482 -400.548125) (xy 36.071366 -400.593872) (xy 36.140713 -400.646241)
			(xy 36.204933 -400.704785) (xy 36.263477 -400.769005) (xy 36.315846 -400.838352) (xy 36.361593 -400.912236)
			(xy 36.400327 -400.990025) (xy 36.431719 -401.071057) (xy 36.4555 -401.154639) (xy 36.471468 -401.240059)
			(xy 36.479486 -401.326588) (xy 36.479988 -401.370038) (xy 36.479486 -401.413488) (xy 36.471468 -401.500017)
			(xy 36.4555 -401.585437) (xy 36.431719 -401.669019) (xy 36.400327 -401.750051) (xy 36.361593 -401.82784)
			(xy 36.315846 -401.901724) (xy 36.263477 -401.971071) (xy 36.204933 -402.035291) (xy 36.140713 -402.093835)
			(xy 36.071366 -402.146204) (xy 35.997482 -402.191951) (xy 35.919693 -402.230685) (xy 35.838661 -402.262077)
			(xy 35.755079 -402.285858) (xy 35.669659 -402.301826) (xy 35.58313 -402.309844) (xy 35.49623 -402.309844)
			(xy 35.409701 -402.301826) (xy 35.324281 -402.285858) (xy 35.240699 -402.262077) (xy 35.159667 -402.230685)
			(xy 35.081878 -402.191951) (xy 35.007994 -402.146204) (xy 34.938647 -402.093835) (xy 34.874427 -402.035291)
			(xy 34.815883 -401.971071) (xy 34.763514 -401.901724) (xy 34.717767 -401.82784) (xy 34.679033 -401.750051)
			(xy 34.647641 -401.669019) (xy 34.62386 -401.585437) (xy 34.607892 -401.500017) (xy 34.599874 -401.413488)
			(xy 31.3995 -401.413488) (xy 31.391522 -401.499749) (xy 31.375606 -401.58504) (xy 31.351902 -401.668501)
			(xy 31.320609 -401.749424) (xy 31.281995 -401.827119) (xy 31.236387 -401.900928) (xy 31.184174 -401.97022)
			(xy 31.125799 -402.034409) (xy 31.061759 -402.092946) (xy 30.992599 -402.145335) (xy 30.918907 -402.19113)
			(xy 30.84131 -402.229942) (xy 30.760467 -402.26144) (xy 30.677066 -402.285357) (xy 30.591817 -402.301489)
			(xy 30.505444 -402.309699) (xy 30.418681 -402.309917) (xy 30.332268 -402.302141) (xy 30.246939 -402.286438)
			(xy 30.163419 -402.262941) (xy 30.082418 -402.23185) (xy 30.004627 -402.193429) (xy 29.930705 -402.148005)
			(xy 29.861283 -402.095964) (xy 29.828744 -402.067268) (xy 29.811703 -402.052502) (xy 29.773459 -402.028621)
			(xy 29.731602 -402.011862) (xy 29.687444 -402.002753) (xy 29.642372 -402.001577) (xy 29.5978 -402.008373)
			(xy 29.555126 -402.022928) (xy 29.51569 -402.044783) (xy 29.48073 -402.073254) (xy 29.451341 -402.107447)
			(xy 29.428447 -402.14629) (xy 29.412766 -402.188562) (xy 29.404789 -402.232939) (xy 29.40431 -402.255482)
			(xy 29.40431 -403.024594) (xy 29.404797 -403.047138) (xy 29.412756 -403.091518) (xy 29.428424 -403.133796)
			(xy 29.451309 -403.172644) (xy 29.480693 -403.206842) (xy 29.515653 -403.235316) (xy 29.55509 -403.257171)
			(xy 29.597766 -403.271721) (xy 29.64234 -403.278508) (xy 29.687412 -403.27732) (xy 29.731567 -403.268194)
			(xy 29.773417 -403.251417) (xy 29.811648 -403.227515) (xy 29.828744 -403.212808) (xy 29.861244 -403.184069)
			(xy 29.930663 -403.132024) (xy 30.004582 -403.086596) (xy 30.082372 -403.048171) (xy 30.16337 -403.017075)
			(xy 30.246889 -402.993573) (xy 30.332218 -402.977866) (xy 30.41863 -402.970085) (xy 30.505393 -402.970299)
			(xy 30.591766 -402.978504) (xy 30.677016 -402.994631) (xy 30.760419 -403.018543) (xy 30.841263 -403.050037)
			(xy 30.918863 -403.088845) (xy 30.992557 -403.134636) (xy 31.06172 -403.187021) (xy 31.125763 -403.245555)
			(xy 31.184141 -403.30974) (xy 31.236358 -403.37903) (xy 31.28197 -403.452836) (xy 31.320588 -403.53053)
			(xy 31.351885 -403.611451) (xy 31.375595 -403.694911) (xy 31.391515 -403.7802) (xy 31.39951 -403.866593)
			(xy 31.399512 -403.953356) (xy 31.3995 -403.953488) (xy 34.599874 -403.953488) (xy 34.599874 -403.866588)
			(xy 34.607892 -403.780059) (xy 34.62386 -403.694639) (xy 34.647641 -403.611057) (xy 34.679033 -403.530025)
			(xy 34.717767 -403.452236) (xy 34.763514 -403.378352) (xy 34.815883 -403.309005) (xy 34.874427 -403.244785)
			(xy 34.938647 -403.186241) (xy 35.007994 -403.133872) (xy 35.081878 -403.088125) (xy 35.159667 -403.049391)
			(xy 35.240699 -403.017999) (xy 35.324281 -402.994218) (xy 35.409701 -402.97825) (xy 35.49623 -402.970232)
			(xy 35.58313 -402.970232) (xy 35.669659 -402.97825) (xy 35.755079 -402.994218) (xy 35.838661 -403.017999)
			(xy 35.919693 -403.049391) (xy 35.997482 -403.088125) (xy 36.071366 -403.133872) (xy 36.140713 -403.186241)
			(xy 36.204933 -403.244785) (xy 36.263477 -403.309005) (xy 36.315846 -403.378352) (xy 36.361593 -403.452236)
			(xy 36.400327 -403.530025) (xy 36.431719 -403.611057) (xy 36.4555 -403.694639) (xy 36.471468 -403.780059)
			(xy 36.479486 -403.866588) (xy 36.479988 -403.910038) (xy 36.479486 -403.953488) (xy 36.471468 -404.040017)
			(xy 36.4555 -404.125437) (xy 36.431719 -404.209019) (xy 36.400327 -404.290051) (xy 36.361593 -404.36784)
			(xy 36.315846 -404.441724) (xy 36.263477 -404.511071) (xy 36.204933 -404.575291) (xy 36.140713 -404.633835)
			(xy 36.071366 -404.686204) (xy 35.997482 -404.731951) (xy 35.919693 -404.770685) (xy 35.838661 -404.802077)
			(xy 35.755079 -404.825858) (xy 35.669659 -404.841826) (xy 35.58313 -404.849844) (xy 35.49623 -404.849844)
			(xy 35.409701 -404.841826) (xy 35.324281 -404.825858) (xy 35.240699 -404.802077) (xy 35.159667 -404.770685)
			(xy 35.081878 -404.731951) (xy 35.007994 -404.686204) (xy 34.938647 -404.633835) (xy 34.874427 -404.575291)
			(xy 34.815883 -404.511071) (xy 34.763514 -404.441724) (xy 34.717767 -404.36784) (xy 34.679033 -404.290051)
			(xy 34.647641 -404.209019) (xy 34.62386 -404.125437) (xy 34.607892 -404.040017) (xy 34.599874 -403.953488)
			(xy 31.3995 -403.953488) (xy 31.391522 -404.039749) (xy 31.375606 -404.12504) (xy 31.351902 -404.208501)
			(xy 31.320609 -404.289424) (xy 31.281995 -404.367119) (xy 31.236387 -404.440928) (xy 31.184174 -404.51022)
			(xy 31.125799 -404.574409) (xy 31.061759 -404.632946) (xy 30.992599 -404.685335) (xy 30.918907 -404.73113)
			(xy 30.84131 -404.769942) (xy 30.760467 -404.80144) (xy 30.677066 -404.825357) (xy 30.591817 -404.841489)
			(xy 30.505444 -404.849699) (xy 30.418681 -404.849917) (xy 30.332268 -404.842141) (xy 30.246939 -404.826438)
			(xy 30.163419 -404.802941) (xy 30.082418 -404.77185) (xy 30.004627 -404.733429) (xy 29.930705 -404.688005)
			(xy 29.861283 -404.635964) (xy 29.828744 -404.607268) (xy 29.811703 -404.592502) (xy 29.773459 -404.568621)
			(xy 29.731602 -404.551862) (xy 29.687444 -404.542753) (xy 29.642372 -404.541577) (xy 29.5978 -404.548373)
			(xy 29.555126 -404.562928) (xy 29.51569 -404.584783) (xy 29.48073 -404.613254) (xy 29.451341 -404.647447)
			(xy 29.428447 -404.68629) (xy 29.412766 -404.728562) (xy 29.404789 -404.772939) (xy 29.40431 -404.795482)
			(xy 29.40431 -405.564594) (xy 29.404797 -405.587138) (xy 29.412756 -405.631518) (xy 29.428424 -405.673796)
			(xy 29.451309 -405.712644) (xy 29.480693 -405.746842) (xy 29.515653 -405.775316) (xy 29.55509 -405.797171)
			(xy 29.597766 -405.811721) (xy 29.64234 -405.818508) (xy 29.687412 -405.81732) (xy 29.731567 -405.808194)
			(xy 29.773417 -405.791417) (xy 29.811648 -405.767515) (xy 29.828744 -405.752808) (xy 29.861244 -405.724069)
			(xy 29.930663 -405.672024) (xy 30.004582 -405.626596) (xy 30.082372 -405.588171) (xy 30.16337 -405.557075)
			(xy 30.246889 -405.533573) (xy 30.332218 -405.517866) (xy 30.41863 -405.510085) (xy 30.505393 -405.510299)
			(xy 30.591766 -405.518504) (xy 30.677016 -405.534631) (xy 30.760419 -405.558543) (xy 30.841263 -405.590037)
			(xy 30.918863 -405.628845) (xy 30.992557 -405.674636) (xy 31.06172 -405.727021) (xy 31.125763 -405.785555)
			(xy 31.184141 -405.84974) (xy 31.236358 -405.91903) (xy 31.28197 -405.992836) (xy 31.320588 -406.07053)
			(xy 31.351885 -406.151451) (xy 31.375595 -406.234911) (xy 31.391515 -406.3202) (xy 31.39951 -406.406593)
			(xy 31.399512 -406.493356) (xy 31.3995 -406.493488) (xy 34.599874 -406.493488) (xy 34.599874 -406.406588)
			(xy 34.607892 -406.320059) (xy 34.62386 -406.234639) (xy 34.647641 -406.151057) (xy 34.679033 -406.070025)
			(xy 34.717767 -405.992236) (xy 34.763514 -405.918352) (xy 34.815883 -405.849005) (xy 34.874427 -405.784785)
			(xy 34.938647 -405.726241) (xy 35.007994 -405.673872) (xy 35.081878 -405.628125) (xy 35.159667 -405.589391)
			(xy 35.240699 -405.557999) (xy 35.324281 -405.534218) (xy 35.409701 -405.51825) (xy 35.49623 -405.510232)
			(xy 35.58313 -405.510232) (xy 35.669659 -405.51825) (xy 35.755079 -405.534218) (xy 35.838661 -405.557999)
			(xy 35.919693 -405.589391) (xy 35.997482 -405.628125) (xy 36.071366 -405.673872) (xy 36.140713 -405.726241)
			(xy 36.204933 -405.784785) (xy 36.263477 -405.849005) (xy 36.315846 -405.918352) (xy 36.361593 -405.992236)
			(xy 36.400327 -406.070025) (xy 36.431719 -406.151057) (xy 36.4555 -406.234639) (xy 36.471468 -406.320059)
			(xy 36.479486 -406.406588) (xy 36.479988 -406.450038) (xy 36.479486 -406.493488) (xy 36.471468 -406.580017)
			(xy 36.4555 -406.665437) (xy 36.431719 -406.749019) (xy 36.400327 -406.830051) (xy 36.361593 -406.90784)
			(xy 36.329254 -406.96007) (xy 39.818063 -406.96007) (xy 39.82207 -406.844046) (xy 39.834072 -406.728574)
			(xy 39.854012 -406.614206) (xy 39.881795 -406.501486) (xy 39.917289 -406.390952) (xy 39.960324 -406.283129)
			(xy 40.010695 -406.178532) (xy 40.068162 -406.07766) (xy 40.132452 -405.980993) (xy 40.203257 -405.888992)
			(xy 40.280241 -405.802095) (xy 40.363037 -405.720716) (xy 40.45125 -405.645243) (xy 40.54446 -405.576036)
			(xy 40.642223 -405.513424) (xy 40.744072 -405.457707) (xy 40.849522 -405.409149) (xy 40.958071 -405.367981)
			(xy 41.069202 -405.334401) (xy 41.182385 -405.308568) (xy 41.29708 -405.290605) (xy 41.412742 -405.280597)
			(xy 41.528818 -405.278594) (xy 41.644756 -405.284603) (xy 41.760003 -405.298596) (xy 41.874009 -405.320507)
			(xy 41.986233 -405.350232) (xy 42.096139 -405.387628) (xy 42.203202 -405.432517) (xy 42.306914 -405.484686)
			(xy 42.406779 -405.543886) (xy 42.502322 -405.609835) (xy 42.502604 -405.61006) (xy 43.327577 -405.61006)
			(xy 43.331612 -405.534356) (xy 43.343671 -405.459511) (xy 43.363617 -405.38637) (xy 43.391224 -405.315765)
			(xy 43.42618 -405.248494) (xy 43.468088 -405.185319) (xy 43.516474 -405.126957) (xy 43.57079 -405.074069)
			(xy 43.630419 -405.027254) (xy 43.694687 -404.987042) (xy 43.762864 -404.95389) (xy 43.83418 -404.928172)
			(xy 43.907825 -404.91018) (xy 43.982965 -404.900118) (xy 44.058749 -404.898099) (xy 44.134319 -404.904148)
			(xy 44.208817 -404.918195) (xy 44.2814 -404.940081) (xy 44.351246 -404.969558) (xy 44.417563 -405.006293)
			(xy 44.479599 -405.049868) (xy 44.536652 -405.09979) (xy 44.588076 -405.155494) (xy 44.633287 -405.216349)
			(xy 44.671774 -405.281664) (xy 44.7031 -405.3507) (xy 44.72691 -405.422675) (xy 44.742935 -405.496773)
			(xy 44.750994 -405.572154) (xy 44.751498 -405.61006) (xy 45.867577 -405.61006) (xy 45.871612 -405.534356)
			(xy 45.883671 -405.459511) (xy 45.903617 -405.38637) (xy 45.931224 -405.315765) (xy 45.96618 -405.248494)
			(xy 46.008088 -405.185319) (xy 46.056474 -405.126957) (xy 46.11079 -405.074069) (xy 46.170419 -405.027254)
			(xy 46.234687 -404.987042) (xy 46.302864 -404.95389) (xy 46.37418 -404.928172) (xy 46.447825 -404.91018)
			(xy 46.522965 -404.900118) (xy 46.598749 -404.898099) (xy 46.674319 -404.904148) (xy 46.748817 -404.918195)
			(xy 46.8214 -404.940081) (xy 46.891246 -404.969558) (xy 46.957563 -405.006293) (xy 47.019599 -405.049868)
			(xy 47.076652 -405.09979) (xy 47.128076 -405.155494) (xy 47.173287 -405.216349) (xy 47.211774 -405.281664)
			(xy 47.2431 -405.3507) (xy 47.26691 -405.422675) (xy 47.282935 -405.496773) (xy 47.290994 -405.572154)
			(xy 47.291498 -405.61006) (xy 48.407577 -405.61006) (xy 48.411612 -405.534356) (xy 48.423671 -405.459511)
			(xy 48.443617 -405.38637) (xy 48.471224 -405.315765) (xy 48.50618 -405.248494) (xy 48.548088 -405.185319)
			(xy 48.596474 -405.126957) (xy 48.65079 -405.074069) (xy 48.710419 -405.027254) (xy 48.774687 -404.987042)
			(xy 48.842864 -404.95389) (xy 48.91418 -404.928172) (xy 48.987825 -404.91018) (xy 49.062965 -404.900118)
			(xy 49.138749 -404.898099) (xy 49.214319 -404.904148) (xy 49.288817 -404.918195) (xy 49.3614 -404.940081)
			(xy 49.431246 -404.969558) (xy 49.497563 -405.006293) (xy 49.559599 -405.049868) (xy 49.616652 -405.09979)
			(xy 49.668076 -405.155494) (xy 49.713287 -405.216349) (xy 49.751774 -405.281664) (xy 49.7831 -405.3507)
			(xy 49.80691 -405.422675) (xy 49.822935 -405.496773) (xy 49.830994 -405.572154) (xy 49.831498 -405.61006)
			(xy 50.947577 -405.61006) (xy 50.951612 -405.534356) (xy 50.963671 -405.459511) (xy 50.983617 -405.38637)
			(xy 51.011224 -405.315765) (xy 51.04618 -405.248494) (xy 51.088088 -405.185319) (xy 51.136474 -405.126957)
			(xy 51.19079 -405.074069) (xy 51.250419 -405.027254) (xy 51.314687 -404.987042) (xy 51.382864 -404.95389)
			(xy 51.45418 -404.928172) (xy 51.527825 -404.91018) (xy 51.602965 -404.900118) (xy 51.678749 -404.898099)
			(xy 51.754319 -404.904148) (xy 51.828817 -404.918195) (xy 51.9014 -404.940081) (xy 51.971246 -404.969558)
			(xy 52.037563 -405.006293) (xy 52.099599 -405.049868) (xy 52.156652 -405.09979) (xy 52.208076 -405.155494)
			(xy 52.253287 -405.216349) (xy 52.291774 -405.281664) (xy 52.3231 -405.3507) (xy 52.34691 -405.422675)
			(xy 52.362935 -405.496773) (xy 52.370994 -405.572154) (xy 52.371498 -405.61006) (xy 53.487577 -405.61006)
			(xy 53.491612 -405.534356) (xy 53.503671 -405.459511) (xy 53.523617 -405.38637) (xy 53.551224 -405.315765)
			(xy 53.58618 -405.248494) (xy 53.628088 -405.185319) (xy 53.676474 -405.126957) (xy 53.73079 -405.074069)
			(xy 53.790419 -405.027254) (xy 53.854687 -404.987042) (xy 53.922864 -404.95389) (xy 53.99418 -404.928172)
			(xy 54.067825 -404.91018) (xy 54.142965 -404.900118) (xy 54.218749 -404.898099) (xy 54.294319 -404.904148)
			(xy 54.368817 -404.918195) (xy 54.4414 -404.940081) (xy 54.511246 -404.969558) (xy 54.577563 -405.006293)
			(xy 54.639599 -405.049868) (xy 54.696652 -405.09979) (xy 54.748076 -405.155494) (xy 54.793287 -405.216349)
			(xy 54.831774 -405.281664) (xy 54.8631 -405.3507) (xy 54.88691 -405.422675) (xy 54.902935 -405.496773)
			(xy 54.910994 -405.572154) (xy 54.911498 -405.61006) (xy 56.027577 -405.61006) (xy 56.031612 -405.534356)
			(xy 56.043671 -405.459511) (xy 56.063617 -405.38637) (xy 56.091224 -405.315765) (xy 56.12618 -405.248494)
			(xy 56.168088 -405.185319) (xy 56.216474 -405.126957) (xy 56.27079 -405.074069) (xy 56.330419 -405.027254)
			(xy 56.394687 -404.987042) (xy 56.462864 -404.95389) (xy 56.53418 -404.928172) (xy 56.607825 -404.91018)
			(xy 56.682965 -404.900118) (xy 56.758749 -404.898099) (xy 56.834319 -404.904148) (xy 56.908817 -404.918195)
			(xy 56.9814 -404.940081) (xy 57.051246 -404.969558) (xy 57.117563 -405.006293) (xy 57.179599 -405.049868)
			(xy 57.236652 -405.09979) (xy 57.288076 -405.155494) (xy 57.333287 -405.216349) (xy 57.371774 -405.281664)
			(xy 57.4031 -405.3507) (xy 57.42691 -405.422675) (xy 57.442935 -405.496773) (xy 57.450994 -405.572154)
			(xy 57.451498 -405.61006) (xy 58.567577 -405.61006) (xy 58.571612 -405.534356) (xy 58.583671 -405.459511)
			(xy 58.603617 -405.38637) (xy 58.631224 -405.315765) (xy 58.66618 -405.248494) (xy 58.708088 -405.185319)
			(xy 58.756474 -405.126957) (xy 58.81079 -405.074069) (xy 58.870419 -405.027254) (xy 58.934687 -404.987042)
			(xy 59.002864 -404.95389) (xy 59.07418 -404.928172) (xy 59.147825 -404.91018) (xy 59.222965 -404.900118)
			(xy 59.298749 -404.898099) (xy 59.374319 -404.904148) (xy 59.448817 -404.918195) (xy 59.5214 -404.940081)
			(xy 59.591246 -404.969558) (xy 59.657563 -405.006293) (xy 59.719599 -405.049868) (xy 59.776652 -405.09979)
			(xy 59.828076 -405.155494) (xy 59.873287 -405.216349) (xy 59.911774 -405.281664) (xy 59.9431 -405.3507)
			(xy 59.96691 -405.422675) (xy 59.982935 -405.496773) (xy 59.990994 -405.572154) (xy 59.991498 -405.61006)
			(xy 61.107577 -405.61006) (xy 61.111612 -405.534356) (xy 61.123671 -405.459511) (xy 61.143617 -405.38637)
			(xy 61.171224 -405.315765) (xy 61.20618 -405.248494) (xy 61.248088 -405.185319) (xy 61.296474 -405.126957)
			(xy 61.35079 -405.074069) (xy 61.410419 -405.027254) (xy 61.474687 -404.987042) (xy 61.542864 -404.95389)
			(xy 61.61418 -404.928172) (xy 61.687825 -404.91018) (xy 61.762965 -404.900118) (xy 61.838749 -404.898099)
			(xy 61.914319 -404.904148) (xy 61.988817 -404.918195) (xy 62.0614 -404.940081) (xy 62.131246 -404.969558)
			(xy 62.197563 -405.006293) (xy 62.259599 -405.049868) (xy 62.265544 -405.05507) (xy 86.197697 -405.05507)
			(xy 86.201732 -404.979366) (xy 86.213791 -404.904521) (xy 86.233737 -404.83138) (xy 86.261344 -404.760775)
			(xy 86.2963 -404.693504) (xy 86.338208 -404.630329) (xy 86.386594 -404.571967) (xy 86.44091 -404.519079)
			(xy 86.500539 -404.472264) (xy 86.564807 -404.432052) (xy 86.632984 -404.3989) (xy 86.7043 -404.373182)
			(xy 86.777945 -404.35519) (xy 86.853085 -404.345128) (xy 86.928869 -404.343109) (xy 87.004439 -404.349158)
			(xy 87.078937 -404.363205) (xy 87.15152 -404.385091) (xy 87.221366 -404.414568) (xy 87.287683 -404.451303)
			(xy 87.349719 -404.494878) (xy 87.406772 -404.5448) (xy 87.458196 -404.600504) (xy 87.503407 -404.661359)
			(xy 87.541894 -404.726674) (xy 87.57322 -404.79571) (xy 87.59703 -404.867685) (xy 87.613055 -404.941783)
			(xy 87.621114 -405.017164) (xy 87.621618 -405.05507) (xy 88.737697 -405.05507) (xy 88.741732 -404.979366)
			(xy 88.753791 -404.904521) (xy 88.773737 -404.83138) (xy 88.801344 -404.760775) (xy 88.8363 -404.693504)
			(xy 88.878208 -404.630329) (xy 88.926594 -404.571967) (xy 88.98091 -404.519079) (xy 89.040539 -404.472264)
			(xy 89.104807 -404.432052) (xy 89.172984 -404.3989) (xy 89.2443 -404.373182) (xy 89.317945 -404.35519)
			(xy 89.393085 -404.345128) (xy 89.468869 -404.343109) (xy 89.544439 -404.349158) (xy 89.618937 -404.363205)
			(xy 89.69152 -404.385091) (xy 89.761366 -404.414568) (xy 89.827683 -404.451303) (xy 89.889719 -404.494878)
			(xy 89.946772 -404.5448) (xy 89.998196 -404.600504) (xy 90.043407 -404.661359) (xy 90.081894 -404.726674)
			(xy 90.11322 -404.79571) (xy 90.13703 -404.867685) (xy 90.153055 -404.941783) (xy 90.161114 -405.017164)
			(xy 90.161618 -405.05507) (xy 91.277697 -405.05507) (xy 91.281732 -404.979366) (xy 91.293791 -404.904521)
			(xy 91.313737 -404.83138) (xy 91.341344 -404.760775) (xy 91.3763 -404.693504) (xy 91.418208 -404.630329)
			(xy 91.466594 -404.571967) (xy 91.52091 -404.519079) (xy 91.580539 -404.472264) (xy 91.644807 -404.432052)
			(xy 91.712984 -404.3989) (xy 91.7843 -404.373182) (xy 91.857945 -404.35519) (xy 91.933085 -404.345128)
			(xy 92.008869 -404.343109) (xy 92.084439 -404.349158) (xy 92.158937 -404.363205) (xy 92.23152 -404.385091)
			(xy 92.301366 -404.414568) (xy 92.367683 -404.451303) (xy 92.429719 -404.494878) (xy 92.486772 -404.5448)
			(xy 92.538196 -404.600504) (xy 92.583407 -404.661359) (xy 92.621894 -404.726674) (xy 92.65322 -404.79571)
			(xy 92.67703 -404.867685) (xy 92.693055 -404.941783) (xy 92.701114 -405.017164) (xy 92.701618 -405.05507)
			(xy 92.701114 -405.092976) (xy 92.693055 -405.168357) (xy 92.67703 -405.242455) (xy 92.65322 -405.31443)
			(xy 92.621894 -405.383466) (xy 92.583407 -405.448781) (xy 92.538196 -405.509636) (xy 92.486772 -405.56534)
			(xy 92.429719 -405.615262) (xy 92.367683 -405.658837) (xy 92.301366 -405.695572) (xy 92.23152 -405.725049)
			(xy 92.158937 -405.746935) (xy 92.084439 -405.760982) (xy 92.008869 -405.767031) (xy 91.933085 -405.765012)
			(xy 91.857945 -405.75495) (xy 91.7843 -405.736958) (xy 91.712984 -405.71124) (xy 91.644807 -405.678088)
			(xy 91.580539 -405.637876) (xy 91.52091 -405.591061) (xy 91.466594 -405.538173) (xy 91.418208 -405.479811)
			(xy 91.3763 -405.416636) (xy 91.341344 -405.349365) (xy 91.313737 -405.27876) (xy 91.293791 -405.205619)
			(xy 91.281732 -405.130774) (xy 91.277697 -405.05507) (xy 90.161618 -405.05507) (xy 90.161114 -405.092976)
			(xy 90.153055 -405.168357) (xy 90.13703 -405.242455) (xy 90.11322 -405.31443) (xy 90.081894 -405.383466)
			(xy 90.043407 -405.448781) (xy 89.998196 -405.509636) (xy 89.946772 -405.56534) (xy 89.889719 -405.615262)
			(xy 89.827683 -405.658837) (xy 89.761366 -405.695572) (xy 89.69152 -405.725049) (xy 89.618937 -405.746935)
			(xy 89.544439 -405.760982) (xy 89.468869 -405.767031) (xy 89.393085 -405.765012) (xy 89.317945 -405.75495)
			(xy 89.2443 -405.736958) (xy 89.172984 -405.71124) (xy 89.104807 -405.678088) (xy 89.040539 -405.637876)
			(xy 88.98091 -405.591061) (xy 88.926594 -405.538173) (xy 88.878208 -405.479811) (xy 88.8363 -405.416636)
			(xy 88.801344 -405.349365) (xy 88.773737 -405.27876) (xy 88.753791 -405.205619) (xy 88.741732 -405.130774)
			(xy 88.737697 -405.05507) (xy 87.621618 -405.05507) (xy 87.621114 -405.092976) (xy 87.613055 -405.168357)
			(xy 87.59703 -405.242455) (xy 87.57322 -405.31443) (xy 87.541894 -405.383466) (xy 87.503407 -405.448781)
			(xy 87.458196 -405.509636) (xy 87.406772 -405.56534) (xy 87.349719 -405.615262) (xy 87.287683 -405.658837)
			(xy 87.221366 -405.695572) (xy 87.15152 -405.725049) (xy 87.078937 -405.746935) (xy 87.004439 -405.760982)
			(xy 86.928869 -405.767031) (xy 86.853085 -405.765012) (xy 86.777945 -405.75495) (xy 86.7043 -405.736958)
			(xy 86.632984 -405.71124) (xy 86.564807 -405.678088) (xy 86.500539 -405.637876) (xy 86.44091 -405.591061)
			(xy 86.386594 -405.538173) (xy 86.338208 -405.479811) (xy 86.2963 -405.416636) (xy 86.261344 -405.349365)
			(xy 86.233737 -405.27876) (xy 86.213791 -405.205619) (xy 86.201732 -405.130774) (xy 86.197697 -405.05507)
			(xy 62.265544 -405.05507) (xy 62.316652 -405.09979) (xy 62.368076 -405.155494) (xy 62.413287 -405.216349)
			(xy 62.451774 -405.281664) (xy 62.4831 -405.3507) (xy 62.50691 -405.422675) (xy 62.522935 -405.496773)
			(xy 62.530994 -405.572154) (xy 62.531498 -405.61006) (xy 62.530994 -405.647966) (xy 62.522935 -405.723347)
			(xy 62.50691 -405.797445) (xy 62.4831 -405.86942) (xy 62.451774 -405.938456) (xy 62.413287 -406.003771)
			(xy 62.368076 -406.064626) (xy 62.316652 -406.12033) (xy 62.259599 -406.170252) (xy 62.197563 -406.213827)
			(xy 62.131246 -406.250562) (xy 62.0614 -406.280039) (xy 61.988817 -406.301925) (xy 61.914319 -406.315972)
			(xy 61.838749 -406.322021) (xy 61.762965 -406.320002) (xy 61.687825 -406.30994) (xy 61.61418 -406.291948)
			(xy 61.542864 -406.26623) (xy 61.474687 -406.233078) (xy 61.410419 -406.192866) (xy 61.35079 -406.146051)
			(xy 61.296474 -406.093163) (xy 61.248088 -406.034801) (xy 61.20618 -405.971626) (xy 61.171224 -405.904355)
			(xy 61.143617 -405.83375) (xy 61.123671 -405.760609) (xy 61.111612 -405.685764) (xy 61.107577 -405.61006)
			(xy 59.991498 -405.61006) (xy 59.990994 -405.647966) (xy 59.982935 -405.723347) (xy 59.96691 -405.797445)
			(xy 59.9431 -405.86942) (xy 59.911774 -405.938456) (xy 59.873287 -406.003771) (xy 59.828076 -406.064626)
			(xy 59.776652 -406.12033) (xy 59.719599 -406.170252) (xy 59.657563 -406.213827) (xy 59.591246 -406.250562)
			(xy 59.5214 -406.280039) (xy 59.448817 -406.301925) (xy 59.374319 -406.315972) (xy 59.298749 -406.322021)
			(xy 59.222965 -406.320002) (xy 59.147825 -406.30994) (xy 59.07418 -406.291948) (xy 59.002864 -406.26623)
			(xy 58.934687 -406.233078) (xy 58.870419 -406.192866) (xy 58.81079 -406.146051) (xy 58.756474 -406.093163)
			(xy 58.708088 -406.034801) (xy 58.66618 -405.971626) (xy 58.631224 -405.904355) (xy 58.603617 -405.83375)
			(xy 58.583671 -405.760609) (xy 58.571612 -405.685764) (xy 58.567577 -405.61006) (xy 57.451498 -405.61006)
			(xy 57.450994 -405.647966) (xy 57.442935 -405.723347) (xy 57.42691 -405.797445) (xy 57.4031 -405.86942)
			(xy 57.371774 -405.938456) (xy 57.333287 -406.003771) (xy 57.288076 -406.064626) (xy 57.236652 -406.12033)
			(xy 57.179599 -406.170252) (xy 57.117563 -406.213827) (xy 57.051246 -406.250562) (xy 56.9814 -406.280039)
			(xy 56.908817 -406.301925) (xy 56.834319 -406.315972) (xy 56.758749 -406.322021) (xy 56.682965 -406.320002)
			(xy 56.607825 -406.30994) (xy 56.53418 -406.291948) (xy 56.462864 -406.26623) (xy 56.394687 -406.233078)
			(xy 56.330419 -406.192866) (xy 56.27079 -406.146051) (xy 56.216474 -406.093163) (xy 56.168088 -406.034801)
			(xy 56.12618 -405.971626) (xy 56.091224 -405.904355) (xy 56.063617 -405.83375) (xy 56.043671 -405.760609)
			(xy 56.031612 -405.685764) (xy 56.027577 -405.61006) (xy 54.911498 -405.61006) (xy 54.910994 -405.647966)
			(xy 54.902935 -405.723347) (xy 54.88691 -405.797445) (xy 54.8631 -405.86942) (xy 54.831774 -405.938456)
			(xy 54.793287 -406.003771) (xy 54.748076 -406.064626) (xy 54.696652 -406.12033) (xy 54.639599 -406.170252)
			(xy 54.577563 -406.213827) (xy 54.511246 -406.250562) (xy 54.4414 -406.280039) (xy 54.368817 -406.301925)
			(xy 54.294319 -406.315972) (xy 54.218749 -406.322021) (xy 54.142965 -406.320002) (xy 54.067825 -406.30994)
			(xy 53.99418 -406.291948) (xy 53.922864 -406.26623) (xy 53.854687 -406.233078) (xy 53.790419 -406.192866)
			(xy 53.73079 -406.146051) (xy 53.676474 -406.093163) (xy 53.628088 -406.034801) (xy 53.58618 -405.971626)
			(xy 53.551224 -405.904355) (xy 53.523617 -405.83375) (xy 53.503671 -405.760609) (xy 53.491612 -405.685764)
			(xy 53.487577 -405.61006) (xy 52.371498 -405.61006) (xy 52.370994 -405.647966) (xy 52.362935 -405.723347)
			(xy 52.34691 -405.797445) (xy 52.3231 -405.86942) (xy 52.291774 -405.938456) (xy 52.253287 -406.003771)
			(xy 52.208076 -406.064626) (xy 52.156652 -406.12033) (xy 52.099599 -406.170252) (xy 52.037563 -406.213827)
			(xy 51.971246 -406.250562) (xy 51.9014 -406.280039) (xy 51.828817 -406.301925) (xy 51.754319 -406.315972)
			(xy 51.678749 -406.322021) (xy 51.602965 -406.320002) (xy 51.527825 -406.30994) (xy 51.45418 -406.291948)
			(xy 51.382864 -406.26623) (xy 51.314687 -406.233078) (xy 51.250419 -406.192866) (xy 51.19079 -406.146051)
			(xy 51.136474 -406.093163) (xy 51.088088 -406.034801) (xy 51.04618 -405.971626) (xy 51.011224 -405.904355)
			(xy 50.983617 -405.83375) (xy 50.963671 -405.760609) (xy 50.951612 -405.685764) (xy 50.947577 -405.61006)
			(xy 49.831498 -405.61006) (xy 49.830994 -405.647966) (xy 49.822935 -405.723347) (xy 49.80691 -405.797445)
			(xy 49.7831 -405.86942) (xy 49.751774 -405.938456) (xy 49.713287 -406.003771) (xy 49.668076 -406.064626)
			(xy 49.616652 -406.12033) (xy 49.559599 -406.170252) (xy 49.497563 -406.213827) (xy 49.431246 -406.250562)
			(xy 49.3614 -406.280039) (xy 49.288817 -406.301925) (xy 49.214319 -406.315972) (xy 49.138749 -406.322021)
			(xy 49.062965 -406.320002) (xy 48.987825 -406.30994) (xy 48.91418 -406.291948) (xy 48.842864 -406.26623)
			(xy 48.774687 -406.233078) (xy 48.710419 -406.192866) (xy 48.65079 -406.146051) (xy 48.596474 -406.093163)
			(xy 48.548088 -406.034801) (xy 48.50618 -405.971626) (xy 48.471224 -405.904355) (xy 48.443617 -405.83375)
			(xy 48.423671 -405.760609) (xy 48.411612 -405.685764) (xy 48.407577 -405.61006) (xy 47.291498 -405.61006)
			(xy 47.290994 -405.647966) (xy 47.282935 -405.723347) (xy 47.26691 -405.797445) (xy 47.2431 -405.86942)
			(xy 47.211774 -405.938456) (xy 47.173287 -406.003771) (xy 47.128076 -406.064626) (xy 47.076652 -406.12033)
			(xy 47.019599 -406.170252) (xy 46.957563 -406.213827) (xy 46.891246 -406.250562) (xy 46.8214 -406.280039)
			(xy 46.748817 -406.301925) (xy 46.674319 -406.315972) (xy 46.598749 -406.322021) (xy 46.522965 -406.320002)
			(xy 46.447825 -406.30994) (xy 46.37418 -406.291948) (xy 46.302864 -406.26623) (xy 46.234687 -406.233078)
			(xy 46.170419 -406.192866) (xy 46.11079 -406.146051) (xy 46.056474 -406.093163) (xy 46.008088 -406.034801)
			(xy 45.96618 -405.971626) (xy 45.931224 -405.904355) (xy 45.903617 -405.83375) (xy 45.883671 -405.760609)
			(xy 45.871612 -405.685764) (xy 45.867577 -405.61006) (xy 44.751498 -405.61006) (xy 44.750994 -405.647966)
			(xy 44.742935 -405.723347) (xy 44.72691 -405.797445) (xy 44.7031 -405.86942) (xy 44.671774 -405.938456)
			(xy 44.633287 -406.003771) (xy 44.588076 -406.064626) (xy 44.536652 -406.12033) (xy 44.479599 -406.170252)
			(xy 44.417563 -406.213827) (xy 44.351246 -406.250562) (xy 44.2814 -406.280039) (xy 44.208817 -406.301925)
			(xy 44.134319 -406.315972) (xy 44.058749 -406.322021) (xy 43.982965 -406.320002) (xy 43.907825 -406.30994)
			(xy 43.83418 -406.291948) (xy 43.762864 -406.26623) (xy 43.694687 -406.233078) (xy 43.630419 -406.192866)
			(xy 43.57079 -406.146051) (xy 43.516474 -406.093163) (xy 43.468088 -406.034801) (xy 43.42618 -405.971626)
			(xy 43.391224 -405.904355) (xy 43.363617 -405.83375) (xy 43.343671 -405.760609) (xy 43.331612 -405.685764)
			(xy 43.327577 -405.61006) (xy 42.502604 -405.61006) (xy 42.593088 -405.682218) (xy 42.678643 -405.760691)
			(xy 42.758581 -405.844879) (xy 42.83252 -405.934381) (xy 42.900108 -406.028772) (xy 42.961022 -406.1276)
			(xy 43.014974 -406.230396) (xy 43.056604 -406.32507) (xy 84.927697 -406.32507) (xy 84.931732 -406.249366)
			(xy 84.943791 -406.174521) (xy 84.963737 -406.10138) (xy 84.991344 -406.030775) (xy 85.0263 -405.963504)
			(xy 85.068208 -405.900329) (xy 85.116594 -405.841967) (xy 85.17091 -405.789079) (xy 85.230539 -405.742264)
			(xy 85.294807 -405.702052) (xy 85.362984 -405.6689) (xy 85.4343 -405.643182) (xy 85.507945 -405.62519)
			(xy 85.583085 -405.615128) (xy 85.658869 -405.613109) (xy 85.734439 -405.619158) (xy 85.808937 -405.633205)
			(xy 85.88152 -405.655091) (xy 85.951366 -405.684568) (xy 86.017683 -405.721303) (xy 86.079719 -405.764878)
			(xy 86.136772 -405.8148) (xy 86.188196 -405.870504) (xy 86.233407 -405.931359) (xy 86.271894 -405.996674)
			(xy 86.30322 -406.06571) (xy 86.32703 -406.137685) (xy 86.343055 -406.211783) (xy 86.351114 -406.287164)
			(xy 86.351618 -406.32507) (xy 87.467697 -406.32507) (xy 87.471732 -406.249366) (xy 87.483791 -406.174521)
			(xy 87.503737 -406.10138) (xy 87.531344 -406.030775) (xy 87.5663 -405.963504) (xy 87.608208 -405.900329)
			(xy 87.656594 -405.841967) (xy 87.71091 -405.789079) (xy 87.770539 -405.742264) (xy 87.834807 -405.702052)
			(xy 87.902984 -405.6689) (xy 87.9743 -405.643182) (xy 88.047945 -405.62519) (xy 88.123085 -405.615128)
			(xy 88.198869 -405.613109) (xy 88.274439 -405.619158) (xy 88.348937 -405.633205) (xy 88.42152 -405.655091)
			(xy 88.491366 -405.684568) (xy 88.557683 -405.721303) (xy 88.619719 -405.764878) (xy 88.676772 -405.8148)
			(xy 88.728196 -405.870504) (xy 88.773407 -405.931359) (xy 88.811894 -405.996674) (xy 88.84322 -406.06571)
			(xy 88.86703 -406.137685) (xy 88.883055 -406.211783) (xy 88.891114 -406.287164) (xy 88.891618 -406.32507)
			(xy 90.007697 -406.32507) (xy 90.011732 -406.249366) (xy 90.023791 -406.174521) (xy 90.043737 -406.10138)
			(xy 90.071344 -406.030775) (xy 90.1063 -405.963504) (xy 90.148208 -405.900329) (xy 90.196594 -405.841967)
			(xy 90.25091 -405.789079) (xy 90.310539 -405.742264) (xy 90.374807 -405.702052) (xy 90.442984 -405.6689)
			(xy 90.5143 -405.643182) (xy 90.587945 -405.62519) (xy 90.663085 -405.615128) (xy 90.738869 -405.613109)
			(xy 90.814439 -405.619158) (xy 90.888937 -405.633205) (xy 90.96152 -405.655091) (xy 91.031366 -405.684568)
			(xy 91.097683 -405.721303) (xy 91.159719 -405.764878) (xy 91.216772 -405.8148) (xy 91.268196 -405.870504)
			(xy 91.313407 -405.931359) (xy 91.351894 -405.996674) (xy 91.38322 -406.06571) (xy 91.40703 -406.137685)
			(xy 91.423055 -406.211783) (xy 91.431114 -406.287164) (xy 91.431618 -406.32507) (xy 91.431114 -406.362976)
			(xy 91.423055 -406.438357) (xy 91.40703 -406.512455) (xy 91.38322 -406.58443) (xy 91.351894 -406.653466)
			(xy 91.313407 -406.718781) (xy 91.268196 -406.779636) (xy 91.216772 -406.83534) (xy 91.159719 -406.885262)
			(xy 91.097683 -406.928837) (xy 91.031366 -406.965572) (xy 90.96152 -406.995049) (xy 90.888937 -407.016935)
			(xy 90.814439 -407.030982) (xy 90.738869 -407.037031) (xy 90.663085 -407.035012) (xy 90.587945 -407.02495)
			(xy 90.5143 -407.006958) (xy 90.442984 -406.98124) (xy 90.374807 -406.948088) (xy 90.310539 -406.907876)
			(xy 90.25091 -406.861061) (xy 90.196594 -406.808173) (xy 90.148208 -406.749811) (xy 90.1063 -406.686636)
			(xy 90.071344 -406.619365) (xy 90.043737 -406.54876) (xy 90.023791 -406.475619) (xy 90.011732 -406.400774)
			(xy 90.007697 -406.32507) (xy 88.891618 -406.32507) (xy 88.891114 -406.362976) (xy 88.883055 -406.438357)
			(xy 88.86703 -406.512455) (xy 88.84322 -406.58443) (xy 88.811894 -406.653466) (xy 88.773407 -406.718781)
			(xy 88.728196 -406.779636) (xy 88.676772 -406.83534) (xy 88.619719 -406.885262) (xy 88.557683 -406.928837)
			(xy 88.491366 -406.965572) (xy 88.42152 -406.995049) (xy 88.348937 -407.016935) (xy 88.274439 -407.030982)
			(xy 88.198869 -407.037031) (xy 88.123085 -407.035012) (xy 88.047945 -407.02495) (xy 87.9743 -407.006958)
			(xy 87.902984 -406.98124) (xy 87.834807 -406.948088) (xy 87.770539 -406.907876) (xy 87.71091 -406.861061)
			(xy 87.656594 -406.808173) (xy 87.608208 -406.749811) (xy 87.5663 -406.686636) (xy 87.531344 -406.619365)
			(xy 87.503737 -406.54876) (xy 87.483791 -406.475619) (xy 87.471732 -406.400774) (xy 87.467697 -406.32507)
			(xy 86.351618 -406.32507) (xy 86.351114 -406.362976) (xy 86.343055 -406.438357) (xy 86.32703 -406.512455)
			(xy 86.30322 -406.58443) (xy 86.271894 -406.653466) (xy 86.233407 -406.718781) (xy 86.188196 -406.779636)
			(xy 86.136772 -406.83534) (xy 86.079719 -406.885262) (xy 86.017683 -406.928837) (xy 85.951366 -406.965572)
			(xy 85.88152 -406.995049) (xy 85.808937 -407.016935) (xy 85.734439 -407.030982) (xy 85.658869 -407.037031)
			(xy 85.583085 -407.035012) (xy 85.507945 -407.02495) (xy 85.4343 -407.006958) (xy 85.362984 -406.98124)
			(xy 85.294807 -406.948088) (xy 85.230539 -406.907876) (xy 85.17091 -406.861061) (xy 85.116594 -406.808173)
			(xy 85.068208 -406.749811) (xy 85.0263 -406.686636) (xy 84.991344 -406.619365) (xy 84.963737 -406.54876)
			(xy 84.943791 -406.475619) (xy 84.931732 -406.400774) (xy 84.927697 -406.32507) (xy 43.056604 -406.32507)
			(xy 43.061704 -406.336669) (xy 43.100992 -406.445913) (xy 43.132649 -406.557606) (xy 43.156525 -406.671218)
			(xy 43.172506 -406.786206) (xy 43.180515 -406.902023) (xy 43.181016 -406.96007) (xy 43.180515 -407.018117)
			(xy 43.172506 -407.133934) (xy 43.156525 -407.248922) (xy 43.132649 -407.362534) (xy 43.100992 -407.474227)
			(xy 43.061704 -407.583471) (xy 43.056604 -407.59507) (xy 86.197697 -407.59507) (xy 86.201732 -407.519366)
			(xy 86.213791 -407.444521) (xy 86.233737 -407.37138) (xy 86.261344 -407.300775) (xy 86.2963 -407.233504)
			(xy 86.338208 -407.170329) (xy 86.386594 -407.111967) (xy 86.44091 -407.059079) (xy 86.500539 -407.012264)
			(xy 86.564807 -406.972052) (xy 86.632984 -406.9389) (xy 86.7043 -406.913182) (xy 86.777945 -406.89519)
			(xy 86.853085 -406.885128) (xy 86.928869 -406.883109) (xy 87.004439 -406.889158) (xy 87.078937 -406.903205)
			(xy 87.15152 -406.925091) (xy 87.221366 -406.954568) (xy 87.287683 -406.991303) (xy 87.349719 -407.034878)
			(xy 87.406772 -407.0848) (xy 87.458196 -407.140504) (xy 87.503407 -407.201359) (xy 87.541894 -407.266674)
			(xy 87.57322 -407.33571) (xy 87.59703 -407.407685) (xy 87.613055 -407.481783) (xy 87.621114 -407.557164)
			(xy 87.621618 -407.59507) (xy 88.737697 -407.59507) (xy 88.741732 -407.519366) (xy 88.753791 -407.444521)
			(xy 88.773737 -407.37138) (xy 88.801344 -407.300775) (xy 88.8363 -407.233504) (xy 88.878208 -407.170329)
			(xy 88.926594 -407.111967) (xy 88.98091 -407.059079) (xy 89.040539 -407.012264) (xy 89.104807 -406.972052)
			(xy 89.172984 -406.9389) (xy 89.2443 -406.913182) (xy 89.317945 -406.89519) (xy 89.393085 -406.885128)
			(xy 89.468869 -406.883109) (xy 89.544439 -406.889158) (xy 89.618937 -406.903205) (xy 89.69152 -406.925091)
			(xy 89.761366 -406.954568) (xy 89.827683 -406.991303) (xy 89.889719 -407.034878) (xy 89.946772 -407.0848)
			(xy 89.998196 -407.140504) (xy 90.043407 -407.201359) (xy 90.081894 -407.266674) (xy 90.11322 -407.33571)
			(xy 90.13703 -407.407685) (xy 90.153055 -407.481783) (xy 90.161114 -407.557164) (xy 90.161618 -407.59507)
			(xy 91.277697 -407.59507) (xy 91.281732 -407.519366) (xy 91.293791 -407.444521) (xy 91.313737 -407.37138)
			(xy 91.341344 -407.300775) (xy 91.3763 -407.233504) (xy 91.418208 -407.170329) (xy 91.466594 -407.111967)
			(xy 91.52091 -407.059079) (xy 91.580539 -407.012264) (xy 91.644807 -406.972052) (xy 91.712984 -406.9389)
			(xy 91.7843 -406.913182) (xy 91.857945 -406.89519) (xy 91.933085 -406.885128) (xy 92.008869 -406.883109)
			(xy 92.084439 -406.889158) (xy 92.158937 -406.903205) (xy 92.23152 -406.925091) (xy 92.301366 -406.954568)
			(xy 92.367683 -406.991303) (xy 92.429719 -407.034878) (xy 92.486772 -407.0848) (xy 92.538196 -407.140504)
			(xy 92.583407 -407.201359) (xy 92.621894 -407.266674) (xy 92.65322 -407.33571) (xy 92.67703 -407.407685)
			(xy 92.693055 -407.481783) (xy 92.701114 -407.557164) (xy 92.701618 -407.59507) (xy 92.701114 -407.632976)
			(xy 92.693055 -407.708357) (xy 92.67703 -407.782455) (xy 92.65322 -407.85443) (xy 92.621894 -407.923466)
			(xy 92.583407 -407.988781) (xy 92.538196 -408.049636) (xy 92.486772 -408.10534) (xy 92.429719 -408.155262)
			(xy 92.367683 -408.198837) (xy 92.301366 -408.235572) (xy 92.23152 -408.265049) (xy 92.158937 -408.286935)
			(xy 92.084439 -408.300982) (xy 92.008869 -408.307031) (xy 91.933085 -408.305012) (xy 91.857945 -408.29495)
			(xy 91.7843 -408.276958) (xy 91.712984 -408.25124) (xy 91.644807 -408.218088) (xy 91.580539 -408.177876)
			(xy 91.52091 -408.131061) (xy 91.466594 -408.078173) (xy 91.418208 -408.019811) (xy 91.3763 -407.956636)
			(xy 91.341344 -407.889365) (xy 91.313737 -407.81876) (xy 91.293791 -407.745619) (xy 91.281732 -407.670774)
			(xy 91.277697 -407.59507) (xy 90.161618 -407.59507) (xy 90.161114 -407.632976) (xy 90.153055 -407.708357)
			(xy 90.13703 -407.782455) (xy 90.11322 -407.85443) (xy 90.081894 -407.923466) (xy 90.043407 -407.988781)
			(xy 89.998196 -408.049636) (xy 89.946772 -408.10534) (xy 89.889719 -408.155262) (xy 89.827683 -408.198837)
			(xy 89.761366 -408.235572) (xy 89.69152 -408.265049) (xy 89.618937 -408.286935) (xy 89.544439 -408.300982)
			(xy 89.468869 -408.307031) (xy 89.393085 -408.305012) (xy 89.317945 -408.29495) (xy 89.2443 -408.276958)
			(xy 89.172984 -408.25124) (xy 89.104807 -408.218088) (xy 89.040539 -408.177876) (xy 88.98091 -408.131061)
			(xy 88.926594 -408.078173) (xy 88.878208 -408.019811) (xy 88.8363 -407.956636) (xy 88.801344 -407.889365)
			(xy 88.773737 -407.81876) (xy 88.753791 -407.745619) (xy 88.741732 -407.670774) (xy 88.737697 -407.59507)
			(xy 87.621618 -407.59507) (xy 87.621114 -407.632976) (xy 87.613055 -407.708357) (xy 87.59703 -407.782455)
			(xy 87.57322 -407.85443) (xy 87.541894 -407.923466) (xy 87.503407 -407.988781) (xy 87.458196 -408.049636)
			(xy 87.406772 -408.10534) (xy 87.349719 -408.155262) (xy 87.287683 -408.198837) (xy 87.221366 -408.235572)
			(xy 87.15152 -408.265049) (xy 87.078937 -408.286935) (xy 87.004439 -408.300982) (xy 86.928869 -408.307031)
			(xy 86.853085 -408.305012) (xy 86.777945 -408.29495) (xy 86.7043 -408.276958) (xy 86.632984 -408.25124)
			(xy 86.564807 -408.218088) (xy 86.500539 -408.177876) (xy 86.44091 -408.131061) (xy 86.386594 -408.078173)
			(xy 86.338208 -408.019811) (xy 86.2963 -407.956636) (xy 86.261344 -407.889365) (xy 86.233737 -407.81876)
			(xy 86.213791 -407.745619) (xy 86.201732 -407.670774) (xy 86.197697 -407.59507) (xy 43.056604 -407.59507)
			(xy 43.055152 -407.598372) (xy 43.328336 -407.598372) (xy 44.751244 -407.598372) (xy 44.751244 -408.31008)
			(xy 45.867577 -408.31008) (xy 45.871612 -408.234376) (xy 45.883671 -408.159531) (xy 45.903617 -408.08639)
			(xy 45.931224 -408.015785) (xy 45.96618 -407.948514) (xy 46.008088 -407.885339) (xy 46.056474 -407.826977)
			(xy 46.11079 -407.774089) (xy 46.170419 -407.727274) (xy 46.234687 -407.687062) (xy 46.302864 -407.65391)
			(xy 46.37418 -407.628192) (xy 46.447825 -407.6102) (xy 46.522965 -407.600138) (xy 46.598749 -407.598119)
			(xy 46.674319 -407.604168) (xy 46.748817 -407.618215) (xy 46.8214 -407.640101) (xy 46.891246 -407.669578)
			(xy 46.957563 -407.706313) (xy 47.019599 -407.749888) (xy 47.076652 -407.79981) (xy 47.128076 -407.855514)
			(xy 47.173287 -407.916369) (xy 47.211774 -407.981684) (xy 47.2431 -408.05072) (xy 47.26691 -408.122695)
			(xy 47.282935 -408.196793) (xy 47.290994 -408.272174) (xy 47.291498 -408.31008) (xy 48.407577 -408.31008)
			(xy 48.411612 -408.234376) (xy 48.423671 -408.159531) (xy 48.443617 -408.08639) (xy 48.471224 -408.015785)
			(xy 48.50618 -407.948514) (xy 48.548088 -407.885339) (xy 48.596474 -407.826977) (xy 48.65079 -407.774089)
			(xy 48.710419 -407.727274) (xy 48.774687 -407.687062) (xy 48.842864 -407.65391) (xy 48.91418 -407.628192)
			(xy 48.987825 -407.6102) (xy 49.062965 -407.600138) (xy 49.138749 -407.598119) (xy 49.214319 -407.604168)
			(xy 49.288817 -407.618215) (xy 49.3614 -407.640101) (xy 49.431246 -407.669578) (xy 49.497563 -407.706313)
			(xy 49.559599 -407.749888) (xy 49.616652 -407.79981) (xy 49.668076 -407.855514) (xy 49.713287 -407.916369)
			(xy 49.751774 -407.981684) (xy 49.7831 -408.05072) (xy 49.80691 -408.122695) (xy 49.822935 -408.196793)
			(xy 49.830994 -408.272174) (xy 49.831498 -408.31008) (xy 50.947577 -408.31008) (xy 50.951612 -408.234376)
			(xy 50.963671 -408.159531) (xy 50.983617 -408.08639) (xy 51.011224 -408.015785) (xy 51.04618 -407.948514)
			(xy 51.088088 -407.885339) (xy 51.136474 -407.826977) (xy 51.19079 -407.774089) (xy 51.250419 -407.727274)
			(xy 51.314687 -407.687062) (xy 51.382864 -407.65391) (xy 51.45418 -407.628192) (xy 51.527825 -407.6102)
			(xy 51.602965 -407.600138) (xy 51.678749 -407.598119) (xy 51.754319 -407.604168) (xy 51.828817 -407.618215)
			(xy 51.9014 -407.640101) (xy 51.971246 -407.669578) (xy 52.037563 -407.706313) (xy 52.099599 -407.749888)
			(xy 52.156652 -407.79981) (xy 52.208076 -407.855514) (xy 52.253287 -407.916369) (xy 52.291774 -407.981684)
			(xy 52.3231 -408.05072) (xy 52.34691 -408.122695) (xy 52.362935 -408.196793) (xy 52.370994 -408.272174)
			(xy 52.371498 -408.31008) (xy 53.487577 -408.31008) (xy 53.491612 -408.234376) (xy 53.503671 -408.159531)
			(xy 53.523617 -408.08639) (xy 53.551224 -408.015785) (xy 53.58618 -407.948514) (xy 53.628088 -407.885339)
			(xy 53.676474 -407.826977) (xy 53.73079 -407.774089) (xy 53.790419 -407.727274) (xy 53.854687 -407.687062)
			(xy 53.922864 -407.65391) (xy 53.99418 -407.628192) (xy 54.067825 -407.6102) (xy 54.142965 -407.600138)
			(xy 54.218749 -407.598119) (xy 54.294319 -407.604168) (xy 54.368817 -407.618215) (xy 54.4414 -407.640101)
			(xy 54.511246 -407.669578) (xy 54.577563 -407.706313) (xy 54.639599 -407.749888) (xy 54.696652 -407.79981)
			(xy 54.748076 -407.855514) (xy 54.793287 -407.916369) (xy 54.831774 -407.981684) (xy 54.8631 -408.05072)
			(xy 54.88691 -408.122695) (xy 54.902935 -408.196793) (xy 54.910994 -408.272174) (xy 54.911498 -408.31008)
			(xy 56.027577 -408.31008) (xy 56.031612 -408.234376) (xy 56.043671 -408.159531) (xy 56.063617 -408.08639)
			(xy 56.091224 -408.015785) (xy 56.12618 -407.948514) (xy 56.168088 -407.885339) (xy 56.216474 -407.826977)
			(xy 56.27079 -407.774089) (xy 56.330419 -407.727274) (xy 56.394687 -407.687062) (xy 56.462864 -407.65391)
			(xy 56.53418 -407.628192) (xy 56.607825 -407.6102) (xy 56.682965 -407.600138) (xy 56.758749 -407.598119)
			(xy 56.834319 -407.604168) (xy 56.908817 -407.618215) (xy 56.9814 -407.640101) (xy 57.051246 -407.669578)
			(xy 57.117563 -407.706313) (xy 57.179599 -407.749888) (xy 57.236652 -407.79981) (xy 57.288076 -407.855514)
			(xy 57.333287 -407.916369) (xy 57.371774 -407.981684) (xy 57.4031 -408.05072) (xy 57.42691 -408.122695)
			(xy 57.442935 -408.196793) (xy 57.450994 -408.272174) (xy 57.451498 -408.31008) (xy 58.567577 -408.31008)
			(xy 58.571612 -408.234376) (xy 58.583671 -408.159531) (xy 58.603617 -408.08639) (xy 58.631224 -408.015785)
			(xy 58.66618 -407.948514) (xy 58.708088 -407.885339) (xy 58.756474 -407.826977) (xy 58.81079 -407.774089)
			(xy 58.870419 -407.727274) (xy 58.934687 -407.687062) (xy 59.002864 -407.65391) (xy 59.07418 -407.628192)
			(xy 59.147825 -407.6102) (xy 59.222965 -407.600138) (xy 59.298749 -407.598119) (xy 59.374319 -407.604168)
			(xy 59.448817 -407.618215) (xy 59.5214 -407.640101) (xy 59.591246 -407.669578) (xy 59.657563 -407.706313)
			(xy 59.719599 -407.749888) (xy 59.776652 -407.79981) (xy 59.828076 -407.855514) (xy 59.873287 -407.916369)
			(xy 59.911774 -407.981684) (xy 59.9431 -408.05072) (xy 59.96691 -408.122695) (xy 59.982935 -408.196793)
			(xy 59.990994 -408.272174) (xy 59.991498 -408.31008) (xy 61.107577 -408.31008) (xy 61.111612 -408.234376)
			(xy 61.123671 -408.159531) (xy 61.143617 -408.08639) (xy 61.171224 -408.015785) (xy 61.20618 -407.948514)
			(xy 61.248088 -407.885339) (xy 61.296474 -407.826977) (xy 61.35079 -407.774089) (xy 61.410419 -407.727274)
			(xy 61.474687 -407.687062) (xy 61.542864 -407.65391) (xy 61.61418 -407.628192) (xy 61.687825 -407.6102)
			(xy 61.762965 -407.600138) (xy 61.838749 -407.598119) (xy 61.914319 -407.604168) (xy 61.988817 -407.618215)
			(xy 62.0614 -407.640101) (xy 62.131246 -407.669578) (xy 62.197563 -407.706313) (xy 62.259599 -407.749888)
			(xy 62.316652 -407.79981) (xy 62.368076 -407.855514) (xy 62.413287 -407.916369) (xy 62.451774 -407.981684)
			(xy 62.4831 -408.05072) (xy 62.50691 -408.122695) (xy 62.522935 -408.196793) (xy 62.530994 -408.272174)
			(xy 62.531498 -408.31008) (xy 62.530994 -408.347986) (xy 62.522935 -408.423367) (xy 62.50691 -408.497465)
			(xy 62.4831 -408.56944) (xy 62.451774 -408.638476) (xy 62.413287 -408.703791) (xy 62.368076 -408.764646)
			(xy 62.316652 -408.82035) (xy 62.265544 -408.86507) (xy 84.927697 -408.86507) (xy 84.931732 -408.789366)
			(xy 84.943791 -408.714521) (xy 84.963737 -408.64138) (xy 84.991344 -408.570775) (xy 85.0263 -408.503504)
			(xy 85.068208 -408.440329) (xy 85.116594 -408.381967) (xy 85.17091 -408.329079) (xy 85.230539 -408.282264)
			(xy 85.294807 -408.242052) (xy 85.362984 -408.2089) (xy 85.4343 -408.183182) (xy 85.507945 -408.16519)
			(xy 85.583085 -408.155128) (xy 85.658869 -408.153109) (xy 85.734439 -408.159158) (xy 85.808937 -408.173205)
			(xy 85.88152 -408.195091) (xy 85.951366 -408.224568) (xy 86.017683 -408.261303) (xy 86.079719 -408.304878)
			(xy 86.136772 -408.3548) (xy 86.188196 -408.410504) (xy 86.233407 -408.471359) (xy 86.271894 -408.536674)
			(xy 86.30322 -408.60571) (xy 86.32703 -408.677685) (xy 86.343055 -408.751783) (xy 86.351114 -408.827164)
			(xy 86.351618 -408.86507) (xy 87.467697 -408.86507) (xy 87.471732 -408.789366) (xy 87.483791 -408.714521)
			(xy 87.503737 -408.64138) (xy 87.531344 -408.570775) (xy 87.5663 -408.503504) (xy 87.608208 -408.440329)
			(xy 87.656594 -408.381967) (xy 87.71091 -408.329079) (xy 87.770539 -408.282264) (xy 87.834807 -408.242052)
			(xy 87.902984 -408.2089) (xy 87.9743 -408.183182) (xy 88.047945 -408.16519) (xy 88.123085 -408.155128)
			(xy 88.198869 -408.153109) (xy 88.274439 -408.159158) (xy 88.348937 -408.173205) (xy 88.42152 -408.195091)
			(xy 88.491366 -408.224568) (xy 88.557683 -408.261303) (xy 88.619719 -408.304878) (xy 88.676772 -408.3548)
			(xy 88.728196 -408.410504) (xy 88.773407 -408.471359) (xy 88.811894 -408.536674) (xy 88.84322 -408.60571)
			(xy 88.86703 -408.677685) (xy 88.883055 -408.751783) (xy 88.891114 -408.827164) (xy 88.891618 -408.86507)
			(xy 90.007697 -408.86507) (xy 90.011732 -408.789366) (xy 90.023791 -408.714521) (xy 90.043737 -408.64138)
			(xy 90.071344 -408.570775) (xy 90.1063 -408.503504) (xy 90.148208 -408.440329) (xy 90.196594 -408.381967)
			(xy 90.25091 -408.329079) (xy 90.310539 -408.282264) (xy 90.374807 -408.242052) (xy 90.442984 -408.2089)
			(xy 90.5143 -408.183182) (xy 90.587945 -408.16519) (xy 90.663085 -408.155128) (xy 90.738869 -408.153109)
			(xy 90.814439 -408.159158) (xy 90.888937 -408.173205) (xy 90.96152 -408.195091) (xy 91.031366 -408.224568)
			(xy 91.097683 -408.261303) (xy 91.159719 -408.304878) (xy 91.165664 -408.31008) (xy 93.154506 -408.31008)
			(xy 93.158522 -408.19381) (xy 93.170549 -408.078095) (xy 93.190531 -407.963485) (xy 93.218373 -407.850526)
			(xy 93.253942 -407.739758) (xy 93.297068 -407.631707) (xy 93.347545 -407.526889) (xy 93.405134 -407.425804)
			(xy 93.46956 -407.328932) (xy 93.540515 -407.236736) (xy 93.617662 -407.149655) (xy 93.700633 -407.068104)
			(xy 93.789033 -406.992472) (xy 93.88244 -406.923118) (xy 93.980409 -406.860375) (xy 94.082473 -406.804539)
			(xy 94.188147 -406.755878) (xy 94.296926 -406.714624) (xy 94.408291 -406.680973) (xy 94.521714 -406.655085)
			(xy 94.636651 -406.637084) (xy 94.752557 -406.627055) (xy 94.868879 -406.625047) (xy 94.985062 -406.631069)
			(xy 95.100553 -406.645092) (xy 95.214801 -406.66705) (xy 95.327262 -406.696837) (xy 95.4374 -406.734312)
			(xy 95.54469 -406.779297) (xy 95.648621 -406.831576) (xy 95.748697 -406.890901) (xy 95.844443 -406.956989)
			(xy 95.9354 -407.029525) (xy 96.021136 -407.108164) (xy 96.101243 -407.19253) (xy 96.175339 -407.282222)
			(xy 96.243069 -407.376812) (xy 96.304113 -407.47585) (xy 96.358178 -407.578863) (xy 96.405008 -407.68536)
			(xy 96.444379 -407.794835) (xy 96.476103 -407.906765) (xy 96.500029 -408.020617) (xy 96.516043 -408.135849)
			(xy 96.52407 -408.251911) (xy 96.524572 -408.31008) (xy 96.52407 -408.368249) (xy 96.516043 -408.484311)
			(xy 96.500029 -408.599543) (xy 96.476103 -408.713395) (xy 96.444379 -408.825325) (xy 96.405008 -408.9348)
			(xy 96.358178 -409.041297) (xy 96.304113 -409.14431) (xy 96.243069 -409.243348) (xy 96.175339 -409.337938)
			(xy 96.101243 -409.42763) (xy 96.021136 -409.511996) (xy 95.9354 -409.590635) (xy 95.844443 -409.663171)
			(xy 95.748697 -409.729259) (xy 95.648621 -409.788584) (xy 95.54469 -409.840863) (xy 95.4374 -409.885848)
			(xy 95.327262 -409.923323) (xy 95.214801 -409.95311) (xy 95.100553 -409.975068) (xy 94.985062 -409.989091)
			(xy 94.868879 -409.995113) (xy 94.752557 -409.993105) (xy 94.636651 -409.983076) (xy 94.521714 -409.965075)
			(xy 94.408291 -409.939187) (xy 94.296926 -409.905536) (xy 94.188147 -409.864282) (xy 94.082473 -409.815621)
			(xy 93.980409 -409.759785) (xy 93.88244 -409.697042) (xy 93.789033 -409.627688) (xy 93.700633 -409.552056)
			(xy 93.617662 -409.470505) (xy 93.540515 -409.383424) (xy 93.46956 -409.291228) (xy 93.405134 -409.194356)
			(xy 93.347545 -409.093271) (xy 93.297068 -408.988453) (xy 93.253942 -408.880402) (xy 93.218373 -408.769634)
			(xy 93.190531 -408.656675) (xy 93.170549 -408.542065) (xy 93.158522 -408.42635) (xy 93.154506 -408.31008)
			(xy 91.165664 -408.31008) (xy 91.216772 -408.3548) (xy 91.268196 -408.410504) (xy 91.313407 -408.471359)
			(xy 91.351894 -408.536674) (xy 91.38322 -408.60571) (xy 91.40703 -408.677685) (xy 91.423055 -408.751783)
			(xy 91.431114 -408.827164) (xy 91.431618 -408.86507) (xy 91.431114 -408.902976) (xy 91.423055 -408.978357)
			(xy 91.40703 -409.052455) (xy 91.38322 -409.12443) (xy 91.351894 -409.193466) (xy 91.313407 -409.258781)
			(xy 91.268196 -409.319636) (xy 91.216772 -409.37534) (xy 91.159719 -409.425262) (xy 91.097683 -409.468837)
			(xy 91.031366 -409.505572) (xy 90.96152 -409.535049) (xy 90.888937 -409.556935) (xy 90.814439 -409.570982)
			(xy 90.738869 -409.577031) (xy 90.663085 -409.575012) (xy 90.587945 -409.56495) (xy 90.5143 -409.546958)
			(xy 90.442984 -409.52124) (xy 90.374807 -409.488088) (xy 90.310539 -409.447876) (xy 90.25091 -409.401061)
			(xy 90.196594 -409.348173) (xy 90.148208 -409.289811) (xy 90.1063 -409.226636) (xy 90.071344 -409.159365)
			(xy 90.043737 -409.08876) (xy 90.023791 -409.015619) (xy 90.011732 -408.940774) (xy 90.007697 -408.86507)
			(xy 88.891618 -408.86507) (xy 88.891114 -408.902976) (xy 88.883055 -408.978357) (xy 88.86703 -409.052455)
			(xy 88.84322 -409.12443) (xy 88.811894 -409.193466) (xy 88.773407 -409.258781) (xy 88.728196 -409.319636)
			(xy 88.676772 -409.37534) (xy 88.619719 -409.425262) (xy 88.557683 -409.468837) (xy 88.491366 -409.505572)
			(xy 88.42152 -409.535049) (xy 88.348937 -409.556935) (xy 88.274439 -409.570982) (xy 88.198869 -409.577031)
			(xy 88.123085 -409.575012) (xy 88.047945 -409.56495) (xy 87.9743 -409.546958) (xy 87.902984 -409.52124)
			(xy 87.834807 -409.488088) (xy 87.770539 -409.447876) (xy 87.71091 -409.401061) (xy 87.656594 -409.348173)
			(xy 87.608208 -409.289811) (xy 87.5663 -409.226636) (xy 87.531344 -409.159365) (xy 87.503737 -409.08876)
			(xy 87.483791 -409.015619) (xy 87.471732 -408.940774) (xy 87.467697 -408.86507) (xy 86.351618 -408.86507)
			(xy 86.351114 -408.902976) (xy 86.343055 -408.978357) (xy 86.32703 -409.052455) (xy 86.30322 -409.12443)
			(xy 86.271894 -409.193466) (xy 86.233407 -409.258781) (xy 86.188196 -409.319636) (xy 86.136772 -409.37534)
			(xy 86.079719 -409.425262) (xy 86.017683 -409.468837) (xy 85.951366 -409.505572) (xy 85.88152 -409.535049)
			(xy 85.808937 -409.556935) (xy 85.734439 -409.570982) (xy 85.658869 -409.577031) (xy 85.583085 -409.575012)
			(xy 85.507945 -409.56495) (xy 85.4343 -409.546958) (xy 85.362984 -409.52124) (xy 85.294807 -409.488088)
			(xy 85.230539 -409.447876) (xy 85.17091 -409.401061) (xy 85.116594 -409.348173) (xy 85.068208 -409.289811)
			(xy 85.0263 -409.226636) (xy 84.991344 -409.159365) (xy 84.963737 -409.08876) (xy 84.943791 -409.015619)
			(xy 84.931732 -408.940774) (xy 84.927697 -408.86507) (xy 62.265544 -408.86507) (xy 62.259599 -408.870272)
			(xy 62.197563 -408.913847) (xy 62.131246 -408.950582) (xy 62.0614 -408.980059) (xy 61.988817 -409.001945)
			(xy 61.914319 -409.015992) (xy 61.838749 -409.022041) (xy 61.762965 -409.020022) (xy 61.687825 -409.00996)
			(xy 61.61418 -408.991968) (xy 61.542864 -408.96625) (xy 61.474687 -408.933098) (xy 61.410419 -408.892886)
			(xy 61.35079 -408.846071) (xy 61.296474 -408.793183) (xy 61.248088 -408.734821) (xy 61.20618 -408.671646)
			(xy 61.171224 -408.604375) (xy 61.143617 -408.53377) (xy 61.123671 -408.460629) (xy 61.111612 -408.385784)
			(xy 61.107577 -408.31008) (xy 59.991498 -408.31008) (xy 59.990994 -408.347986) (xy 59.982935 -408.423367)
			(xy 59.96691 -408.497465) (xy 59.9431 -408.56944) (xy 59.911774 -408.638476) (xy 59.873287 -408.703791)
			(xy 59.828076 -408.764646) (xy 59.776652 -408.82035) (xy 59.719599 -408.870272) (xy 59.657563 -408.913847)
			(xy 59.591246 -408.950582) (xy 59.5214 -408.980059) (xy 59.448817 -409.001945) (xy 59.374319 -409.015992)
			(xy 59.298749 -409.022041) (xy 59.222965 -409.020022) (xy 59.147825 -409.00996) (xy 59.07418 -408.991968)
			(xy 59.002864 -408.96625) (xy 58.934687 -408.933098) (xy 58.870419 -408.892886) (xy 58.81079 -408.846071)
			(xy 58.756474 -408.793183) (xy 58.708088 -408.734821) (xy 58.66618 -408.671646) (xy 58.631224 -408.604375)
			(xy 58.603617 -408.53377) (xy 58.583671 -408.460629) (xy 58.571612 -408.385784) (xy 58.567577 -408.31008)
			(xy 57.451498 -408.31008) (xy 57.450994 -408.347986) (xy 57.442935 -408.423367) (xy 57.42691 -408.497465)
			(xy 57.4031 -408.56944) (xy 57.371774 -408.638476) (xy 57.333287 -408.703791) (xy 57.288076 -408.764646)
			(xy 57.236652 -408.82035) (xy 57.179599 -408.870272) (xy 57.117563 -408.913847) (xy 57.051246 -408.950582)
			(xy 56.9814 -408.980059) (xy 56.908817 -409.001945) (xy 56.834319 -409.015992) (xy 56.758749 -409.022041)
			(xy 56.682965 -409.020022) (xy 56.607825 -409.00996) (xy 56.53418 -408.991968) (xy 56.462864 -408.96625)
			(xy 56.394687 -408.933098) (xy 56.330419 -408.892886) (xy 56.27079 -408.846071) (xy 56.216474 -408.793183)
			(xy 56.168088 -408.734821) (xy 56.12618 -408.671646) (xy 56.091224 -408.604375) (xy 56.063617 -408.53377)
			(xy 56.043671 -408.460629) (xy 56.031612 -408.385784) (xy 56.027577 -408.31008) (xy 54.911498 -408.31008)
			(xy 54.910994 -408.347986) (xy 54.902935 -408.423367) (xy 54.88691 -408.497465) (xy 54.8631 -408.56944)
			(xy 54.831774 -408.638476) (xy 54.793287 -408.703791) (xy 54.748076 -408.764646) (xy 54.696652 -408.82035)
			(xy 54.639599 -408.870272) (xy 54.577563 -408.913847) (xy 54.511246 -408.950582) (xy 54.4414 -408.980059)
			(xy 54.368817 -409.001945) (xy 54.294319 -409.015992) (xy 54.218749 -409.022041) (xy 54.142965 -409.020022)
			(xy 54.067825 -409.00996) (xy 53.99418 -408.991968) (xy 53.922864 -408.96625) (xy 53.854687 -408.933098)
			(xy 53.790419 -408.892886) (xy 53.73079 -408.846071) (xy 53.676474 -408.793183) (xy 53.628088 -408.734821)
			(xy 53.58618 -408.671646) (xy 53.551224 -408.604375) (xy 53.523617 -408.53377) (xy 53.503671 -408.460629)
			(xy 53.491612 -408.385784) (xy 53.487577 -408.31008) (xy 52.371498 -408.31008) (xy 52.370994 -408.347986)
			(xy 52.362935 -408.423367) (xy 52.34691 -408.497465) (xy 52.3231 -408.56944) (xy 52.291774 -408.638476)
			(xy 52.253287 -408.703791) (xy 52.208076 -408.764646) (xy 52.156652 -408.82035) (xy 52.099599 -408.870272)
			(xy 52.037563 -408.913847) (xy 51.971246 -408.950582) (xy 51.9014 -408.980059) (xy 51.828817 -409.001945)
			(xy 51.754319 -409.015992) (xy 51.678749 -409.022041) (xy 51.602965 -409.020022) (xy 51.527825 -409.00996)
			(xy 51.45418 -408.991968) (xy 51.382864 -408.96625) (xy 51.314687 -408.933098) (xy 51.250419 -408.892886)
			(xy 51.19079 -408.846071) (xy 51.136474 -408.793183) (xy 51.088088 -408.734821) (xy 51.04618 -408.671646)
			(xy 51.011224 -408.604375) (xy 50.983617 -408.53377) (xy 50.963671 -408.460629) (xy 50.951612 -408.385784)
			(xy 50.947577 -408.31008) (xy 49.831498 -408.31008) (xy 49.830994 -408.347986) (xy 49.822935 -408.423367)
			(xy 49.80691 -408.497465) (xy 49.7831 -408.56944) (xy 49.751774 -408.638476) (xy 49.713287 -408.703791)
			(xy 49.668076 -408.764646) (xy 49.616652 -408.82035) (xy 49.559599 -408.870272) (xy 49.497563 -408.913847)
			(xy 49.431246 -408.950582) (xy 49.3614 -408.980059) (xy 49.288817 -409.001945) (xy 49.214319 -409.015992)
			(xy 49.138749 -409.022041) (xy 49.062965 -409.020022) (xy 48.987825 -409.00996) (xy 48.91418 -408.991968)
			(xy 48.842864 -408.96625) (xy 48.774687 -408.933098) (xy 48.710419 -408.892886) (xy 48.65079 -408.846071)
			(xy 48.596474 -408.793183) (xy 48.548088 -408.734821) (xy 48.50618 -408.671646) (xy 48.471224 -408.604375)
			(xy 48.443617 -408.53377) (xy 48.423671 -408.460629) (xy 48.411612 -408.385784) (xy 48.407577 -408.31008)
			(xy 47.291498 -408.31008) (xy 47.290994 -408.347986) (xy 47.282935 -408.423367) (xy 47.26691 -408.497465)
			(xy 47.2431 -408.56944) (xy 47.211774 -408.638476) (xy 47.173287 -408.703791) (xy 47.128076 -408.764646)
			(xy 47.076652 -408.82035) (xy 47.019599 -408.870272) (xy 46.957563 -408.913847) (xy 46.891246 -408.950582)
			(xy 46.8214 -408.980059) (xy 46.748817 -409.001945) (xy 46.674319 -409.015992) (xy 46.598749 -409.022041)
			(xy 46.522965 -409.020022) (xy 46.447825 -409.00996) (xy 46.37418 -408.991968) (xy 46.302864 -408.96625)
			(xy 46.234687 -408.933098) (xy 46.170419 -408.892886) (xy 46.11079 -408.846071) (xy 46.056474 -408.793183)
			(xy 46.008088 -408.734821) (xy 45.96618 -408.671646) (xy 45.931224 -408.604375) (xy 45.903617 -408.53377)
			(xy 45.883671 -408.460629) (xy 45.871612 -408.385784) (xy 45.867577 -408.31008) (xy 44.751244 -408.31008)
			(xy 44.751244 -409.021788) (xy 43.328336 -409.021788) (xy 43.328336 -407.598372) (xy 43.055152 -407.598372)
			(xy 43.014974 -407.689744) (xy 42.961022 -407.79254) (xy 42.900108 -407.891368) (xy 42.83252 -407.985759)
			(xy 42.758581 -408.075261) (xy 42.678643 -408.159449) (xy 42.593088 -408.237922) (xy 42.502322 -408.310305)
			(xy 42.406779 -408.376254) (xy 42.306914 -408.435454) (xy 42.203202 -408.487623) (xy 42.096139 -408.532512)
			(xy 41.986233 -408.569908) (xy 41.874009 -408.599633) (xy 41.760003 -408.621544) (xy 41.644756 -408.635537)
			(xy 41.528818 -408.641546) (xy 41.412742 -408.639543) (xy 41.29708 -408.629535) (xy 41.182385 -408.611572)
			(xy 41.069202 -408.585739) (xy 40.958071 -408.552159) (xy 40.849522 -408.510991) (xy 40.744072 -408.462433)
			(xy 40.642223 -408.406716) (xy 40.54446 -408.344104) (xy 40.45125 -408.274897) (xy 40.363037 -408.199424)
			(xy 40.280241 -408.118045) (xy 40.203257 -408.031148) (xy 40.132452 -407.939147) (xy 40.068162 -407.84248)
			(xy 40.010695 -407.741608) (xy 39.960324 -407.637011) (xy 39.917289 -407.529188) (xy 39.881795 -407.418654)
			(xy 39.854012 -407.305934) (xy 39.834072 -407.191566) (xy 39.82207 -407.076094) (xy 39.818063 -406.96007)
			(xy 36.329254 -406.96007) (xy 36.315846 -406.981724) (xy 36.263477 -407.051071) (xy 36.204933 -407.115291)
			(xy 36.140713 -407.173835) (xy 36.071366 -407.226204) (xy 35.997482 -407.271951) (xy 35.919693 -407.310685)
			(xy 35.838661 -407.342077) (xy 35.755079 -407.365858) (xy 35.669659 -407.381826) (xy 35.58313 -407.389844)
			(xy 35.49623 -407.389844) (xy 35.409701 -407.381826) (xy 35.324281 -407.365858) (xy 35.240699 -407.342077)
			(xy 35.159667 -407.310685) (xy 35.081878 -407.271951) (xy 35.007994 -407.226204) (xy 34.938647 -407.173835)
			(xy 34.874427 -407.115291) (xy 34.815883 -407.051071) (xy 34.763514 -406.981724) (xy 34.717767 -406.90784)
			(xy 34.679033 -406.830051) (xy 34.647641 -406.749019) (xy 34.62386 -406.665437) (xy 34.607892 -406.580017)
			(xy 34.599874 -406.493488) (xy 31.3995 -406.493488) (xy 31.391522 -406.579749) (xy 31.375606 -406.66504)
			(xy 31.351902 -406.748501) (xy 31.320609 -406.829424) (xy 31.281995 -406.907119) (xy 31.236387 -406.980928)
			(xy 31.184174 -407.05022) (xy 31.125799 -407.114409) (xy 31.061759 -407.172946) (xy 30.992599 -407.225335)
			(xy 30.918907 -407.27113) (xy 30.84131 -407.309942) (xy 30.760467 -407.34144) (xy 30.677066 -407.365357)
			(xy 30.591817 -407.381489) (xy 30.505444 -407.389699) (xy 30.418681 -407.389917) (xy 30.332268 -407.382141)
			(xy 30.246939 -407.366438) (xy 30.163419 -407.342941) (xy 30.082418 -407.31185) (xy 30.004627 -407.273429)
			(xy 29.930705 -407.228005) (xy 29.861283 -407.175964) (xy 29.828744 -407.147268) (xy 29.811703 -407.132502)
			(xy 29.773459 -407.108621) (xy 29.731602 -407.091862) (xy 29.687444 -407.082753) (xy 29.642372 -407.081577)
			(xy 29.5978 -407.088373) (xy 29.555126 -407.102928) (xy 29.51569 -407.124783) (xy 29.48073 -407.153254)
			(xy 29.451341 -407.187447) (xy 29.428447 -407.22629) (xy 29.412766 -407.268562) (xy 29.404789 -407.312939)
			(xy 29.40431 -407.335482) (xy 29.40431 -417.800282) (xy 71.649336 -417.800282) (xy 71.649336 -416.723322)
			(xy 71.650025 -416.687256) (xy 71.660349 -416.615864) (xy 71.66991 -416.581082) (xy 71.674736 -416.563556)
			(xy 71.674736 -416.189668) (xy 72.640952 -416.189668) (xy 72.640952 -416.563556) (xy 72.645778 -416.581082)
			(xy 72.655331 -416.615866) (xy 72.665651 -416.687257) (xy 72.666352 -416.723322) (xy 72.666352 -416.955732)
			(xy 73.00468 -416.955732) (xy 73.00468 -415.878772) (xy 73.005163 -415.846045) (xy 73.013561 -415.781132)
			(xy 73.030216 -415.717833) (xy 73.054851 -415.657192) (xy 73.08706 -415.600211) (xy 73.10628 -415.573718)
			(xy 73.13168 -415.539936) (xy 73.13168 -415.522664) (xy 73.14692 -415.522664) (xy 73.182734 -415.492438)
			(xy 73.207911 -415.471585) (xy 73.262643 -415.435834) (xy 73.321508 -415.407395) (xy 73.383533 -415.38674)
			(xy 73.447695 -415.374209) (xy 73.512934 -415.370009) (xy 73.578173 -415.374209) (xy 73.642335 -415.38674)
			(xy 73.70436 -415.407395) (xy 73.763225 -415.435834) (xy 73.817957 -415.471585) (xy 73.843134 -415.492438)
			(xy 73.878948 -415.522664) (xy 73.894188 -415.522664) (xy 73.894188 -415.539936) (xy 73.919588 -415.573718)
			(xy 73.940197 -415.602156) (xy 73.974225 -415.663593) (xy 73.987406 -415.696146) (xy 73.993349 -415.710233)
			(xy 74.010856 -415.735289) (xy 74.033821 -415.75546) (xy 74.060926 -415.769588) (xy 74.090614 -415.77686)
			(xy 74.12118 -415.77686) (xy 74.150868 -415.769588) (xy 74.177973 -415.75546) (xy 74.200938 -415.735289)
			(xy 74.218445 -415.710233) (xy 74.224388 -415.696146) (xy 74.237568 -415.663592) (xy 74.271597 -415.602156)
			(xy 74.292206 -415.573718) (xy 74.317352 -415.539936) (xy 74.317352 -415.522664) (xy 74.332846 -415.522664)
			(xy 74.36866 -415.492438) (xy 74.393837 -415.471585) (xy 74.448569 -415.435834) (xy 74.507434 -415.407395)
			(xy 74.569459 -415.38674) (xy 74.633621 -415.374209) (xy 74.69886 -415.370009) (xy 74.764099 -415.374209)
			(xy 74.828261 -415.38674) (xy 74.890286 -415.407395) (xy 74.949151 -415.435834) (xy 75.003883 -415.471585)
			(xy 75.02906 -415.492438) (xy 75.064874 -415.522664) (xy 75.080368 -415.522664) (xy 75.080368 -415.539936)
			(xy 75.105514 -415.573718) (xy 75.124768 -415.600197) (xy 75.157032 -415.657166) (xy 75.181716 -415.717805)
			(xy 75.198412 -415.781111) (xy 75.206845 -415.846037) (xy 75.207368 -415.878772) (xy 75.207368 -416.955732)
			(xy 75.206901 -416.987038) (xy 75.199209 -417.049177) (xy 75.183945 -417.109901) (xy 75.161341 -417.168292)
			(xy 75.131738 -417.223465) (xy 75.095585 -417.274586) (xy 75.053428 -417.32088) (xy 75.005906 -417.361648)
			(xy 74.953738 -417.396273) (xy 74.897713 -417.42423) (xy 74.838679 -417.445096) (xy 74.77753 -417.458556)
			(xy 74.715191 -417.464406) (xy 74.652605 -417.462557) (xy 74.59072 -417.453037) (xy 74.530472 -417.435991)
			(xy 74.472773 -417.411676) (xy 74.418497 -417.38046) (xy 74.368463 -417.342816) (xy 74.323431 -417.299313)
			(xy 74.303382 -417.275264) (xy 74.288768 -417.25796) (xy 74.254515 -417.228333) (xy 74.215551 -417.205249)
			(xy 74.173112 -417.189441) (xy 74.128541 -417.18141) (xy 74.083253 -417.18141) (xy 74.038682 -417.189441)
			(xy 73.996243 -417.205249) (xy 73.957279 -417.228333) (xy 73.923026 -417.25796) (xy 73.908412 -417.275264)
			(xy 73.888387 -417.299318) (xy 73.843355 -417.342787) (xy 73.793327 -417.3804) (xy 73.739061 -417.411587)
			(xy 73.681376 -417.435876) (xy 73.621146 -417.452901) (xy 73.559282 -417.462403) (xy 73.496719 -417.464239)
			(xy 73.434404 -417.458381) (xy 73.373279 -417.444918) (xy 73.314269 -417.424053) (xy 73.258267 -417.396103)
			(xy 73.20612 -417.361489) (xy 73.158616 -417.320735) (xy 73.116474 -417.274458) (xy 73.080332 -417.223358)
			(xy 73.050736 -417.168207) (xy 73.028134 -417.109841) (xy 73.012868 -417.049141) (xy 73.005168 -416.987027)
			(xy 73.00468 -416.955732) (xy 72.666352 -416.955732) (xy 72.666352 -417.800282) (xy 72.66585 -417.832243)
			(xy 72.657839 -417.895661) (xy 72.641942 -417.957575) (xy 72.61841 -418.017008) (xy 72.587616 -418.073023)
			(xy 72.550043 -418.124738) (xy 72.506286 -418.171335) (xy 72.457033 -418.21208) (xy 72.403062 -418.246331)
			(xy 72.345223 -418.273548) (xy 72.28443 -418.293301) (xy 72.22164 -418.305279) (xy 72.157844 -418.309293)
			(xy 72.094048 -418.305279) (xy 72.031258 -418.293301) (xy 71.970465 -418.273548) (xy 71.912626 -418.246331)
			(xy 71.858655 -418.21208) (xy 71.809402 -418.171335) (xy 71.765645 -418.124738) (xy 71.728072 -418.073023)
			(xy 71.697278 -418.017008) (xy 71.673746 -417.957575) (xy 71.657849 -417.895661) (xy 71.649838 -417.832243)
			(xy 71.649336 -417.800282) (xy 29.40431 -417.800282) (xy 29.40431 -418.677513) (xy 47.978812 -418.677513)
			(xy 47.978812 -418.596403) (xy 47.986762 -418.515684) (xy 48.002585 -418.436133) (xy 48.02613 -418.358517)
			(xy 48.057169 -418.283581) (xy 48.095404 -418.212049) (xy 48.140466 -418.144609) (xy 48.191921 -418.08191)
			(xy 48.249274 -418.024557) (xy 48.311973 -417.973102) (xy 48.379413 -417.92804) (xy 48.450945 -417.889805)
			(xy 48.525881 -417.858766) (xy 48.603497 -417.835221) (xy 48.683048 -417.819398) (xy 48.763767 -417.811448)
			(xy 48.844877 -417.811448) (xy 48.925596 -417.819398) (xy 49.005147 -417.835221) (xy 49.082763 -417.858766)
			(xy 49.157699 -417.889805) (xy 49.229231 -417.92804) (xy 49.296671 -417.973102) (xy 49.35937 -418.024557)
			(xy 49.416723 -418.08191) (xy 49.468178 -418.144609) (xy 49.51324 -418.212049) (xy 49.551475 -418.283581)
			(xy 49.582514 -418.358517) (xy 49.606059 -418.436133) (xy 49.621882 -418.515684) (xy 49.629832 -418.596403)
			(xy 49.63033 -418.636958) (xy 49.629832 -418.677513) (xy 49.621882 -418.758232) (xy 49.606059 -418.837783)
			(xy 49.582514 -418.915399) (xy 49.551475 -418.990335) (xy 49.51324 -419.061867) (xy 49.468178 -419.129307)
			(xy 49.416723 -419.192006) (xy 49.35937 -419.249359) (xy 49.296671 -419.300814) (xy 49.229231 -419.345876)
			(xy 49.157699 -419.384111) (xy 49.082763 -419.41515) (xy 49.005147 -419.438695) (xy 48.925596 -419.454518)
			(xy 48.844877 -419.462468) (xy 48.763767 -419.462468) (xy 48.683048 -419.454518) (xy 48.603497 -419.438695)
			(xy 48.525881 -419.41515) (xy 48.450945 -419.384111) (xy 48.379413 -419.345876) (xy 48.311973 -419.300814)
			(xy 48.249274 -419.249359) (xy 48.191921 -419.192006) (xy 48.140466 -419.129307) (xy 48.095404 -419.061867)
			(xy 48.057169 -418.990335) (xy 48.02613 -418.915399) (xy 48.002585 -418.837783) (xy 47.986762 -418.758232)
			(xy 47.978812 -418.677513) (xy 29.40431 -418.677513) (xy 29.40431 -420.06012) (xy 86.39887 -420.06012)
			(xy 86.402874 -419.860022) (xy 86.414881 -419.660244) (xy 86.434872 -419.461107) (xy 86.462814 -419.262929)
			(xy 86.498662 -419.066027) (xy 86.54236 -418.870718) (xy 86.593837 -418.677313) (xy 86.653011 -418.486123)
			(xy 86.719787 -418.297453) (xy 86.794059 -418.111606) (xy 86.875706 -417.928879) (xy 86.964599 -417.749566)
			(xy 87.060595 -417.573952) (xy 87.16354 -417.40232) (xy 87.27327 -417.234944) (xy 87.389608 -417.072093)
			(xy 87.512369 -416.914026) (xy 87.641356 -416.760998) (xy 87.776363 -416.613253) (xy 87.917172 -416.471027)
			(xy 88.063559 -416.33455) (xy 88.215289 -416.204038) (xy 88.37212 -416.079702) (xy 88.533799 -415.96174)
			(xy 88.700069 -415.850341) (xy 88.870662 -415.745684) (xy 89.045306 -415.647936) (xy 89.223722 -415.557253)
			(xy 89.405622 -415.473782) (xy 89.590717 -415.397655) (xy 89.778709 -415.328995) (xy 89.969298 -415.267911)
			(xy 90.162178 -415.214501) (xy 90.35704 -415.168852) (xy 90.553573 -415.131035) (xy 90.751462 -415.101111)
			(xy 90.950389 -415.079129) (xy 91.150037 -415.065124) (xy 91.350085 -415.059118) (xy 91.550213 -415.06112)
			(xy 91.750101 -415.071128) (xy 91.949428 -415.089125) (xy 92.147876 -415.115083) (xy 92.345126 -415.14896)
			(xy 92.540863 -415.190702) (xy 92.734773 -415.240241) (xy 92.926546 -415.297499) (xy 93.115875 -415.362384)
			(xy 93.302455 -415.434792) (xy 93.48599 -415.514608) (xy 93.666184 -415.601702) (xy 93.842749 -415.695936)
			(xy 94.015402 -415.797159) (xy 94.183867 -415.905209) (xy 94.347875 -416.019912) (xy 94.507162 -416.141086)
			(xy 94.661473 -416.268535) (xy 94.810561 -416.402056) (xy 94.954188 -416.541436) (xy 95.092124 -416.68645)
			(xy 95.224147 -416.836867) (xy 95.350046 -416.992445) (xy 95.46962 -417.152937) (xy 95.582676 -417.318083)
			(xy 95.689035 -417.487621) (xy 95.788526 -417.661279) (xy 95.880989 -417.838778) (xy 95.966276 -418.019834)
			(xy 96.044251 -418.204158) (xy 96.114788 -418.391454) (xy 96.177776 -418.581422) (xy 96.233113 -418.773758)
			(xy 96.28071 -418.968154) (xy 96.320491 -419.164299) (xy 96.352393 -419.361878) (xy 96.376364 -419.560575)
			(xy 96.392366 -419.760073) (xy 96.400373 -419.960051) (xy 96.400874 -420.06012) (xy 96.400373 -420.160189)
			(xy 96.392366 -420.360167) (xy 96.376364 -420.559665) (xy 96.352393 -420.758362) (xy 96.320491 -420.955941)
			(xy 96.28071 -421.152086) (xy 96.233113 -421.346482) (xy 96.177776 -421.538818) (xy 96.114788 -421.728786)
			(xy 96.044251 -421.916082) (xy 95.966276 -422.100406) (xy 95.880989 -422.281462) (xy 95.788526 -422.458961)
			(xy 95.689035 -422.632619) (xy 95.582676 -422.802157) (xy 95.46962 -422.967303) (xy 95.350046 -423.127795)
			(xy 95.224147 -423.283373) (xy 95.092124 -423.43379) (xy 94.954188 -423.578804) (xy 94.810561 -423.718184)
			(xy 94.661473 -423.851705) (xy 94.507162 -423.979154) (xy 94.347875 -424.100328) (xy 94.183867 -424.215031)
			(xy 94.015402 -424.323081) (xy 93.842749 -424.424304) (xy 93.666184 -424.518538) (xy 93.48599 -424.605632)
			(xy 93.302455 -424.685448) (xy 93.115875 -424.757856) (xy 92.926546 -424.822741) (xy 92.734773 -424.879999)
			(xy 92.540863 -424.929538) (xy 92.345126 -424.97128) (xy 92.147876 -425.005157) (xy 91.949428 -425.031115)
			(xy 91.750101 -425.049112) (xy 91.550213 -425.05912) (xy 91.350085 -425.061122) (xy 91.150037 -425.055116)
			(xy 90.950389 -425.041111) (xy 90.751462 -425.019129) (xy 90.553573 -424.989205) (xy 90.35704 -424.951388)
			(xy 90.162178 -424.905739) (xy 89.969298 -424.852329) (xy 89.778709 -424.791245) (xy 89.590717 -424.722585)
			(xy 89.405622 -424.646458) (xy 89.223722 -424.562987) (xy 89.045306 -424.472304) (xy 88.870662 -424.374556)
			(xy 88.700069 -424.269899) (xy 88.533799 -424.1585) (xy 88.37212 -424.040538) (xy 88.215289 -423.916202)
			(xy 88.063559 -423.78569) (xy 87.917172 -423.649213) (xy 87.776363 -423.506987) (xy 87.641356 -423.359242)
			(xy 87.512369 -423.206214) (xy 87.389608 -423.048147) (xy 87.27327 -422.885296) (xy 87.16354 -422.71792)
			(xy 87.060595 -422.546288) (xy 86.964599 -422.370674) (xy 86.875706 -422.191361) (xy 86.794059 -422.008634)
			(xy 86.719787 -421.822787) (xy 86.653011 -421.634117) (xy 86.593837 -421.442927) (xy 86.54236 -421.249522)
			(xy 86.498662 -421.054213) (xy 86.462814 -420.857311) (xy 86.434872 -420.659133) (xy 86.414881 -420.459996)
			(xy 86.402874 -420.260218) (xy 86.39887 -420.06012) (xy 29.40431 -420.06012) (xy 29.40431 -422.480079)
			(xy 56.548266 -422.480079) (xy 56.548266 -422.408757) (xy 56.556252 -422.337883) (xy 56.572122 -422.268348)
			(xy 56.595679 -422.201028) (xy 56.626624 -422.136769) (xy 56.66457 -422.076378) (xy 56.709039 -422.020616)
			(xy 56.759472 -421.970183) (xy 56.815234 -421.925714) (xy 56.875625 -421.887768) (xy 56.939884 -421.856823)
			(xy 57.007204 -421.833266) (xy 57.076739 -421.817396) (xy 57.147613 -421.80941) (xy 57.218935 -421.80941)
			(xy 57.289809 -421.817396) (xy 57.359344 -421.833266) (xy 57.426664 -421.856823) (xy 57.490923 -421.887768)
			(xy 57.551314 -421.925714) (xy 57.607076 -421.970183) (xy 57.657509 -422.020616) (xy 57.701978 -422.076378)
			(xy 57.739924 -422.136769) (xy 57.770869 -422.201028) (xy 57.794426 -422.268348) (xy 57.810296 -422.337883)
			(xy 57.818282 -422.408757) (xy 57.818782 -422.444418) (xy 57.818282 -422.480079) (xy 58.434978 -422.480079)
			(xy 58.434978 -422.408757) (xy 58.442964 -422.337883) (xy 58.458834 -422.268348) (xy 58.482391 -422.201028)
			(xy 58.513336 -422.136769) (xy 58.551282 -422.076378) (xy 58.595751 -422.020616) (xy 58.646184 -421.970183)
			(xy 58.701946 -421.925714) (xy 58.762337 -421.887768) (xy 58.826596 -421.856823) (xy 58.893916 -421.833266)
			(xy 58.963451 -421.817396) (xy 59.034325 -421.80941) (xy 59.105647 -421.80941) (xy 59.176521 -421.817396)
			(xy 59.246056 -421.833266) (xy 59.313376 -421.856823) (xy 59.377635 -421.887768) (xy 59.438026 -421.925714)
			(xy 59.493788 -421.970183) (xy 59.544221 -422.020616) (xy 59.58869 -422.076378) (xy 59.626636 -422.136769)
			(xy 59.657581 -422.201028) (xy 59.681138 -422.268348) (xy 59.697008 -422.337883) (xy 59.704994 -422.408757)
			(xy 59.705494 -422.444418) (xy 59.704994 -422.480079) (xy 59.697008 -422.550953) (xy 59.681138 -422.620488)
			(xy 59.657581 -422.687808) (xy 59.626636 -422.752067) (xy 59.58869 -422.812458) (xy 59.544221 -422.86822)
			(xy 59.493788 -422.918653) (xy 59.438026 -422.963122) (xy 59.377635 -423.001068) (xy 59.313376 -423.032013)
			(xy 59.246056 -423.05557) (xy 59.176521 -423.07144) (xy 59.105647 -423.079426) (xy 59.034325 -423.079426)
			(xy 58.963451 -423.07144) (xy 58.893916 -423.05557) (xy 58.826596 -423.032013) (xy 58.762337 -423.001068)
			(xy 58.701946 -422.963122) (xy 58.646184 -422.918653) (xy 58.595751 -422.86822) (xy 58.551282 -422.812458)
			(xy 58.513336 -422.752067) (xy 58.482391 -422.687808) (xy 58.458834 -422.620488) (xy 58.442964 -422.550953)
			(xy 58.434978 -422.480079) (xy 57.818282 -422.480079) (xy 57.810296 -422.550953) (xy 57.794426 -422.620488)
			(xy 57.770869 -422.687808) (xy 57.739924 -422.752067) (xy 57.701978 -422.812458) (xy 57.657509 -422.86822)
			(xy 57.607076 -422.918653) (xy 57.551314 -422.963122) (xy 57.490923 -423.001068) (xy 57.426664 -423.032013)
			(xy 57.359344 -423.05557) (xy 57.289809 -423.07144) (xy 57.218935 -423.079426) (xy 57.147613 -423.079426)
			(xy 57.076739 -423.07144) (xy 57.007204 -423.05557) (xy 56.939884 -423.032013) (xy 56.875625 -423.001068)
			(xy 56.815234 -422.963122) (xy 56.759472 -422.918653) (xy 56.709039 -422.86822) (xy 56.66457 -422.812458)
			(xy 56.626624 -422.752067) (xy 56.595679 -422.687808) (xy 56.572122 -422.620488) (xy 56.556252 -422.550953)
			(xy 56.548266 -422.480079) (xy 29.40431 -422.480079) (xy 29.40431 -424.313705) (xy 56.548266 -424.313705)
			(xy 56.548266 -424.242383) (xy 56.556252 -424.171509) (xy 56.572122 -424.101974) (xy 56.595679 -424.034654)
			(xy 56.626624 -423.970395) (xy 56.66457 -423.910004) (xy 56.709039 -423.854242) (xy 56.759472 -423.803809)
			(xy 56.815234 -423.75934) (xy 56.875625 -423.721394) (xy 56.939884 -423.690449) (xy 57.007204 -423.666892)
			(xy 57.076739 -423.651022) (xy 57.147613 -423.643036) (xy 57.218935 -423.643036) (xy 57.289809 -423.651022)
			(xy 57.359344 -423.666892) (xy 57.426664 -423.690449) (xy 57.490923 -423.721394) (xy 57.551314 -423.75934)
			(xy 57.607076 -423.803809) (xy 57.657509 -423.854242) (xy 57.701978 -423.910004) (xy 57.739924 -423.970395)
			(xy 57.770869 -424.034654) (xy 57.794426 -424.101974) (xy 57.810296 -424.171509) (xy 57.818282 -424.242383)
			(xy 57.818782 -424.278044) (xy 57.818282 -424.313705) (xy 58.434978 -424.313705) (xy 58.434978 -424.242383)
			(xy 58.442964 -424.171509) (xy 58.458834 -424.101974) (xy 58.482391 -424.034654) (xy 58.513336 -423.970395)
			(xy 58.551282 -423.910004) (xy 58.595751 -423.854242) (xy 58.646184 -423.803809) (xy 58.701946 -423.75934)
			(xy 58.762337 -423.721394) (xy 58.826596 -423.690449) (xy 58.893916 -423.666892) (xy 58.963451 -423.651022)
			(xy 59.034325 -423.643036) (xy 59.105647 -423.643036) (xy 59.176521 -423.651022) (xy 59.246056 -423.666892)
			(xy 59.313376 -423.690449) (xy 59.377635 -423.721394) (xy 59.438026 -423.75934) (xy 59.493788 -423.803809)
			(xy 59.544221 -423.854242) (xy 59.58869 -423.910004) (xy 59.626636 -423.970395) (xy 59.657581 -424.034654)
			(xy 59.681138 -424.101974) (xy 59.697008 -424.171509) (xy 59.704994 -424.242383) (xy 59.705494 -424.278044)
			(xy 59.704994 -424.313705) (xy 60.67602 -424.313705) (xy 60.67602 -424.242383) (xy 60.684006 -424.171509)
			(xy 60.699876 -424.101974) (xy 60.723433 -424.034654) (xy 60.754378 -423.970395) (xy 60.792324 -423.910004)
			(xy 60.836793 -423.854242) (xy 60.887226 -423.803809) (xy 60.942988 -423.75934) (xy 61.003379 -423.721394)
			(xy 61.067638 -423.690449) (xy 61.134958 -423.666892) (xy 61.204493 -423.651022) (xy 61.275367 -423.643036)
			(xy 61.346689 -423.643036) (xy 61.417563 -423.651022) (xy 61.487098 -423.666892) (xy 61.554418 -423.690449)
			(xy 61.618677 -423.721394) (xy 61.679068 -423.75934) (xy 61.73483 -423.803809) (xy 61.785263 -423.854242)
			(xy 61.829732 -423.910004) (xy 61.867678 -423.970395) (xy 61.898623 -424.034654) (xy 61.92218 -424.101974)
			(xy 61.93805 -424.171509) (xy 61.946036 -424.242383) (xy 61.946536 -424.278044) (xy 61.946036 -424.313705)
			(xy 62.580004 -424.313705) (xy 62.580004 -424.242383) (xy 62.58799 -424.171509) (xy 62.60386 -424.101974)
			(xy 62.627417 -424.034654) (xy 62.658362 -423.970395) (xy 62.696308 -423.910004) (xy 62.740777 -423.854242)
			(xy 62.79121 -423.803809) (xy 62.846972 -423.75934) (xy 62.907363 -423.721394) (xy 62.971622 -423.690449)
			(xy 63.038942 -423.666892) (xy 63.108477 -423.651022) (xy 63.179351 -423.643036) (xy 63.250673 -423.643036)
			(xy 63.321547 -423.651022) (xy 63.391082 -423.666892) (xy 63.458402 -423.690449) (xy 63.522661 -423.721394)
			(xy 63.583052 -423.75934) (xy 63.638814 -423.803809) (xy 63.689247 -423.854242) (xy 63.733716 -423.910004)
			(xy 63.771662 -423.970395) (xy 63.802607 -424.034654) (xy 63.826164 -424.101974) (xy 63.842034 -424.171509)
			(xy 63.85002 -424.242383) (xy 63.85052 -424.278044) (xy 63.85002 -424.313705) (xy 63.842034 -424.384579)
			(xy 63.826164 -424.454114) (xy 63.802607 -424.521434) (xy 63.771662 -424.585693) (xy 63.733716 -424.646084)
			(xy 63.689247 -424.701846) (xy 63.638814 -424.752279) (xy 63.583052 -424.796748) (xy 63.522661 -424.834694)
			(xy 63.458402 -424.865639) (xy 63.391082 -424.889196) (xy 63.321547 -424.905066) (xy 63.250673 -424.913052)
			(xy 63.179351 -424.913052) (xy 63.108477 -424.905066) (xy 63.038942 -424.889196) (xy 62.971622 -424.865639)
			(xy 62.907363 -424.834694) (xy 62.846972 -424.796748) (xy 62.79121 -424.752279) (xy 62.740777 -424.701846)
			(xy 62.696308 -424.646084) (xy 62.658362 -424.585693) (xy 62.627417 -424.521434) (xy 62.60386 -424.454114)
			(xy 62.58799 -424.384579) (xy 62.580004 -424.313705) (xy 61.946036 -424.313705) (xy 61.93805 -424.384579)
			(xy 61.92218 -424.454114) (xy 61.898623 -424.521434) (xy 61.867678 -424.585693) (xy 61.829732 -424.646084)
			(xy 61.785263 -424.701846) (xy 61.73483 -424.752279) (xy 61.679068 -424.796748) (xy 61.618677 -424.834694)
			(xy 61.554418 -424.865639) (xy 61.487098 -424.889196) (xy 61.417563 -424.905066) (xy 61.346689 -424.913052)
			(xy 61.275367 -424.913052) (xy 61.204493 -424.905066) (xy 61.134958 -424.889196) (xy 61.067638 -424.865639)
			(xy 61.003379 -424.834694) (xy 60.942988 -424.796748) (xy 60.887226 -424.752279) (xy 60.836793 -424.701846)
			(xy 60.792324 -424.646084) (xy 60.754378 -424.585693) (xy 60.723433 -424.521434) (xy 60.699876 -424.454114)
			(xy 60.684006 -424.384579) (xy 60.67602 -424.313705) (xy 59.704994 -424.313705) (xy 59.697008 -424.384579)
			(xy 59.681138 -424.454114) (xy 59.657581 -424.521434) (xy 59.626636 -424.585693) (xy 59.58869 -424.646084)
			(xy 59.544221 -424.701846) (xy 59.493788 -424.752279) (xy 59.438026 -424.796748) (xy 59.377635 -424.834694)
			(xy 59.313376 -424.865639) (xy 59.246056 -424.889196) (xy 59.176521 -424.905066) (xy 59.105647 -424.913052)
			(xy 59.034325 -424.913052) (xy 58.963451 -424.905066) (xy 58.893916 -424.889196) (xy 58.826596 -424.865639)
			(xy 58.762337 -424.834694) (xy 58.701946 -424.796748) (xy 58.646184 -424.752279) (xy 58.595751 -424.701846)
			(xy 58.551282 -424.646084) (xy 58.513336 -424.585693) (xy 58.482391 -424.521434) (xy 58.458834 -424.454114)
			(xy 58.442964 -424.384579) (xy 58.434978 -424.313705) (xy 57.818282 -424.313705) (xy 57.810296 -424.384579)
			(xy 57.794426 -424.454114) (xy 57.770869 -424.521434) (xy 57.739924 -424.585693) (xy 57.701978 -424.646084)
			(xy 57.657509 -424.701846) (xy 57.607076 -424.752279) (xy 57.551314 -424.796748) (xy 57.490923 -424.834694)
			(xy 57.426664 -424.865639) (xy 57.359344 -424.889196) (xy 57.289809 -424.905066) (xy 57.218935 -424.913052)
			(xy 57.147613 -424.913052) (xy 57.076739 -424.905066) (xy 57.007204 -424.889196) (xy 56.939884 -424.865639)
			(xy 56.875625 -424.834694) (xy 56.815234 -424.796748) (xy 56.759472 -424.752279) (xy 56.709039 -424.701846)
			(xy 56.66457 -424.646084) (xy 56.626624 -424.585693) (xy 56.595679 -424.521434) (xy 56.572122 -424.454114)
			(xy 56.556252 -424.384579) (xy 56.548266 -424.313705) (xy 29.40431 -424.313705) (xy 29.40431 -426.214641)
			(xy 56.548266 -426.214641) (xy 56.548266 -426.143319) (xy 56.556252 -426.072445) (xy 56.572122 -426.00291)
			(xy 56.595679 -425.93559) (xy 56.626624 -425.871331) (xy 56.66457 -425.81094) (xy 56.709039 -425.755178)
			(xy 56.759472 -425.704745) (xy 56.815234 -425.660276) (xy 56.875625 -425.62233) (xy 56.939884 -425.591385)
			(xy 57.007204 -425.567828) (xy 57.076739 -425.551958) (xy 57.147613 -425.543972) (xy 57.218935 -425.543972)
			(xy 57.289809 -425.551958) (xy 57.359344 -425.567828) (xy 57.426664 -425.591385) (xy 57.490923 -425.62233)
			(xy 57.551314 -425.660276) (xy 57.607076 -425.704745) (xy 57.657509 -425.755178) (xy 57.701978 -425.81094)
			(xy 57.739924 -425.871331) (xy 57.770869 -425.93559) (xy 57.794426 -426.00291) (xy 57.810296 -426.072445)
			(xy 57.818282 -426.143319) (xy 57.818782 -426.17898) (xy 57.818282 -426.214641) (xy 58.434978 -426.214641)
			(xy 58.434978 -426.143319) (xy 58.442964 -426.072445) (xy 58.458834 -426.00291) (xy 58.482391 -425.93559)
			(xy 58.513336 -425.871331) (xy 58.551282 -425.81094) (xy 58.595751 -425.755178) (xy 58.646184 -425.704745)
			(xy 58.701946 -425.660276) (xy 58.762337 -425.62233) (xy 58.826596 -425.591385) (xy 58.893916 -425.567828)
			(xy 58.963451 -425.551958) (xy 59.034325 -425.543972) (xy 59.105647 -425.543972) (xy 59.176521 -425.551958)
			(xy 59.246056 -425.567828) (xy 59.313376 -425.591385) (xy 59.377635 -425.62233) (xy 59.438026 -425.660276)
			(xy 59.493788 -425.704745) (xy 59.544221 -425.755178) (xy 59.58869 -425.81094) (xy 59.626636 -425.871331)
			(xy 59.657581 -425.93559) (xy 59.681138 -426.00291) (xy 59.697008 -426.072445) (xy 59.704994 -426.143319)
			(xy 59.705494 -426.17898) (xy 59.704994 -426.214641) (xy 60.67602 -426.214641) (xy 60.67602 -426.143319)
			(xy 60.684006 -426.072445) (xy 60.699876 -426.00291) (xy 60.723433 -425.93559) (xy 60.754378 -425.871331)
			(xy 60.792324 -425.81094) (xy 60.836793 -425.755178) (xy 60.887226 -425.704745) (xy 60.942988 -425.660276)
			(xy 61.003379 -425.62233) (xy 61.067638 -425.591385) (xy 61.134958 -425.567828) (xy 61.204493 -425.551958)
			(xy 61.275367 -425.543972) (xy 61.346689 -425.543972) (xy 61.417563 -425.551958) (xy 61.487098 -425.567828)
			(xy 61.554418 -425.591385) (xy 61.618677 -425.62233) (xy 61.679068 -425.660276) (xy 61.73483 -425.704745)
			(xy 61.785263 -425.755178) (xy 61.829732 -425.81094) (xy 61.867678 -425.871331) (xy 61.898623 -425.93559)
			(xy 61.92218 -426.00291) (xy 61.93805 -426.072445) (xy 61.946036 -426.143319) (xy 61.946536 -426.17898)
			(xy 61.946036 -426.214641) (xy 62.580004 -426.214641) (xy 62.580004 -426.143319) (xy 62.58799 -426.072445)
			(xy 62.60386 -426.00291) (xy 62.627417 -425.93559) (xy 62.658362 -425.871331) (xy 62.696308 -425.81094)
			(xy 62.740777 -425.755178) (xy 62.79121 -425.704745) (xy 62.846972 -425.660276) (xy 62.907363 -425.62233)
			(xy 62.971622 -425.591385) (xy 63.038942 -425.567828) (xy 63.108477 -425.551958) (xy 63.179351 -425.543972)
			(xy 63.250673 -425.543972) (xy 63.321547 -425.551958) (xy 63.391082 -425.567828) (xy 63.458402 -425.591385)
			(xy 63.522661 -425.62233) (xy 63.583052 -425.660276) (xy 63.638814 -425.704745) (xy 63.689247 -425.755178)
			(xy 63.733716 -425.81094) (xy 63.771662 -425.871331) (xy 63.802607 -425.93559) (xy 63.826164 -426.00291)
			(xy 63.842034 -426.072445) (xy 63.85002 -426.143319) (xy 63.85052 -426.17898) (xy 63.85002 -426.214641)
			(xy 63.842034 -426.285515) (xy 63.826164 -426.35505) (xy 63.802607 -426.42237) (xy 63.771662 -426.486629)
			(xy 63.733716 -426.54702) (xy 63.689247 -426.602782) (xy 63.638814 -426.653215) (xy 63.583052 -426.697684)
			(xy 63.522661 -426.73563) (xy 63.458402 -426.766575) (xy 63.391082 -426.790132) (xy 63.321547 -426.806002)
			(xy 63.250673 -426.813988) (xy 63.179351 -426.813988) (xy 63.108477 -426.806002) (xy 63.038942 -426.790132)
			(xy 62.971622 -426.766575) (xy 62.907363 -426.73563) (xy 62.846972 -426.697684) (xy 62.79121 -426.653215)
			(xy 62.740777 -426.602782) (xy 62.696308 -426.54702) (xy 62.658362 -426.486629) (xy 62.627417 -426.42237)
			(xy 62.60386 -426.35505) (xy 62.58799 -426.285515) (xy 62.580004 -426.214641) (xy 61.946036 -426.214641)
			(xy 61.93805 -426.285515) (xy 61.92218 -426.35505) (xy 61.898623 -426.42237) (xy 61.867678 -426.486629)
			(xy 61.829732 -426.54702) (xy 61.785263 -426.602782) (xy 61.73483 -426.653215) (xy 61.679068 -426.697684)
			(xy 61.618677 -426.73563) (xy 61.554418 -426.766575) (xy 61.487098 -426.790132) (xy 61.417563 -426.806002)
			(xy 61.346689 -426.813988) (xy 61.275367 -426.813988) (xy 61.204493 -426.806002) (xy 61.134958 -426.790132)
			(xy 61.067638 -426.766575) (xy 61.003379 -426.73563) (xy 60.942988 -426.697684) (xy 60.887226 -426.653215)
			(xy 60.836793 -426.602782) (xy 60.792324 -426.54702) (xy 60.754378 -426.486629) (xy 60.723433 -426.42237)
			(xy 60.699876 -426.35505) (xy 60.684006 -426.285515) (xy 60.67602 -426.214641) (xy 59.704994 -426.214641)
			(xy 59.697008 -426.285515) (xy 59.681138 -426.35505) (xy 59.657581 -426.42237) (xy 59.626636 -426.486629)
			(xy 59.58869 -426.54702) (xy 59.544221 -426.602782) (xy 59.493788 -426.653215) (xy 59.438026 -426.697684)
			(xy 59.377635 -426.73563) (xy 59.313376 -426.766575) (xy 59.246056 -426.790132) (xy 59.176521 -426.806002)
			(xy 59.105647 -426.813988) (xy 59.034325 -426.813988) (xy 58.963451 -426.806002) (xy 58.893916 -426.790132)
			(xy 58.826596 -426.766575) (xy 58.762337 -426.73563) (xy 58.701946 -426.697684) (xy 58.646184 -426.653215)
			(xy 58.595751 -426.602782) (xy 58.551282 -426.54702) (xy 58.513336 -426.486629) (xy 58.482391 -426.42237)
			(xy 58.458834 -426.35505) (xy 58.442964 -426.285515) (xy 58.434978 -426.214641) (xy 57.818282 -426.214641)
			(xy 57.810296 -426.285515) (xy 57.794426 -426.35505) (xy 57.770869 -426.42237) (xy 57.739924 -426.486629)
			(xy 57.701978 -426.54702) (xy 57.657509 -426.602782) (xy 57.607076 -426.653215) (xy 57.551314 -426.697684)
			(xy 57.490923 -426.73563) (xy 57.426664 -426.766575) (xy 57.359344 -426.790132) (xy 57.289809 -426.806002)
			(xy 57.218935 -426.813988) (xy 57.147613 -426.813988) (xy 57.076739 -426.806002) (xy 57.007204 -426.790132)
			(xy 56.939884 -426.766575) (xy 56.875625 -426.73563) (xy 56.815234 -426.697684) (xy 56.759472 -426.653215)
			(xy 56.709039 -426.602782) (xy 56.66457 -426.54702) (xy 56.626624 -426.486629) (xy 56.595679 -426.42237)
			(xy 56.572122 -426.35505) (xy 56.556252 -426.285515) (xy 56.548266 -426.214641) (xy 29.40431 -426.214641)
			(xy 29.40431 -427.889771) (xy 56.548266 -427.889771) (xy 56.548266 -427.818449) (xy 56.556252 -427.747575)
			(xy 56.572122 -427.67804) (xy 56.595679 -427.61072) (xy 56.626624 -427.546461) (xy 56.66457 -427.48607)
			(xy 56.709039 -427.430308) (xy 56.759472 -427.379875) (xy 56.815234 -427.335406) (xy 56.875625 -427.29746)
			(xy 56.939884 -427.266515) (xy 57.007204 -427.242958) (xy 57.076739 -427.227088) (xy 57.147613 -427.219102)
			(xy 57.218935 -427.219102) (xy 57.289809 -427.227088) (xy 57.359344 -427.242958) (xy 57.426664 -427.266515)
			(xy 57.490923 -427.29746) (xy 57.551314 -427.335406) (xy 57.607076 -427.379875) (xy 57.657509 -427.430308)
			(xy 57.701978 -427.48607) (xy 57.739924 -427.546461) (xy 57.770869 -427.61072) (xy 57.794426 -427.67804)
			(xy 57.810296 -427.747575) (xy 57.818282 -427.818449) (xy 57.818782 -427.85411) (xy 57.818282 -427.889771)
			(xy 58.434978 -427.889771) (xy 58.434978 -427.818449) (xy 58.442964 -427.747575) (xy 58.458834 -427.67804)
			(xy 58.482391 -427.61072) (xy 58.513336 -427.546461) (xy 58.551282 -427.48607) (xy 58.595751 -427.430308)
			(xy 58.646184 -427.379875) (xy 58.701946 -427.335406) (xy 58.762337 -427.29746) (xy 58.826596 -427.266515)
			(xy 58.893916 -427.242958) (xy 58.963451 -427.227088) (xy 59.034325 -427.219102) (xy 59.105647 -427.219102)
			(xy 59.176521 -427.227088) (xy 59.246056 -427.242958) (xy 59.313376 -427.266515) (xy 59.377635 -427.29746)
			(xy 59.438026 -427.335406) (xy 59.493788 -427.379875) (xy 59.544221 -427.430308) (xy 59.58869 -427.48607)
			(xy 59.626636 -427.546461) (xy 59.657581 -427.61072) (xy 59.681138 -427.67804) (xy 59.697008 -427.747575)
			(xy 59.704994 -427.818449) (xy 59.705494 -427.85411) (xy 59.704994 -427.889771) (xy 60.67602 -427.889771)
			(xy 60.67602 -427.818449) (xy 60.684006 -427.747575) (xy 60.699876 -427.67804) (xy 60.723433 -427.61072)
			(xy 60.754378 -427.546461) (xy 60.792324 -427.48607) (xy 60.836793 -427.430308) (xy 60.887226 -427.379875)
			(xy 60.942988 -427.335406) (xy 61.003379 -427.29746) (xy 61.067638 -427.266515) (xy 61.134958 -427.242958)
			(xy 61.204493 -427.227088) (xy 61.275367 -427.219102) (xy 61.346689 -427.219102) (xy 61.417563 -427.227088)
			(xy 61.487098 -427.242958) (xy 61.554418 -427.266515) (xy 61.618677 -427.29746) (xy 61.679068 -427.335406)
			(xy 61.73483 -427.379875) (xy 61.785263 -427.430308) (xy 61.829732 -427.48607) (xy 61.867678 -427.546461)
			(xy 61.898623 -427.61072) (xy 61.92218 -427.67804) (xy 61.93805 -427.747575) (xy 61.946036 -427.818449)
			(xy 61.946536 -427.85411) (xy 61.946036 -427.889771) (xy 62.580004 -427.889771) (xy 62.580004 -427.818449)
			(xy 62.58799 -427.747575) (xy 62.60386 -427.67804) (xy 62.627417 -427.61072) (xy 62.658362 -427.546461)
			(xy 62.696308 -427.48607) (xy 62.740777 -427.430308) (xy 62.79121 -427.379875) (xy 62.846972 -427.335406)
			(xy 62.907363 -427.29746) (xy 62.971622 -427.266515) (xy 63.038942 -427.242958) (xy 63.108477 -427.227088)
			(xy 63.179351 -427.219102) (xy 63.250673 -427.219102) (xy 63.321547 -427.227088) (xy 63.391082 -427.242958)
			(xy 63.458402 -427.266515) (xy 63.522661 -427.29746) (xy 63.583052 -427.335406) (xy 63.638814 -427.379875)
			(xy 63.689247 -427.430308) (xy 63.733716 -427.48607) (xy 63.771662 -427.546461) (xy 63.802607 -427.61072)
			(xy 63.826164 -427.67804) (xy 63.842034 -427.747575) (xy 63.85002 -427.818449) (xy 63.85052 -427.85411)
			(xy 63.85002 -427.889771) (xy 63.842034 -427.960645) (xy 63.826164 -428.03018) (xy 63.802607 -428.0975)
			(xy 63.771662 -428.161759) (xy 63.733716 -428.22215) (xy 63.689247 -428.277912) (xy 63.638814 -428.328345)
			(xy 63.583052 -428.372814) (xy 63.522661 -428.41076) (xy 63.458402 -428.441705) (xy 63.391082 -428.465262)
			(xy 63.321547 -428.481132) (xy 63.250673 -428.489118) (xy 63.179351 -428.489118) (xy 63.108477 -428.481132)
			(xy 63.038942 -428.465262) (xy 62.971622 -428.441705) (xy 62.907363 -428.41076) (xy 62.846972 -428.372814)
			(xy 62.79121 -428.328345) (xy 62.740777 -428.277912) (xy 62.696308 -428.22215) (xy 62.658362 -428.161759)
			(xy 62.627417 -428.0975) (xy 62.60386 -428.03018) (xy 62.58799 -427.960645) (xy 62.580004 -427.889771)
			(xy 61.946036 -427.889771) (xy 61.93805 -427.960645) (xy 61.92218 -428.03018) (xy 61.898623 -428.0975)
			(xy 61.867678 -428.161759) (xy 61.829732 -428.22215) (xy 61.785263 -428.277912) (xy 61.73483 -428.328345)
			(xy 61.679068 -428.372814) (xy 61.618677 -428.41076) (xy 61.554418 -428.441705) (xy 61.487098 -428.465262)
			(xy 61.417563 -428.481132) (xy 61.346689 -428.489118) (xy 61.275367 -428.489118) (xy 61.204493 -428.481132)
			(xy 61.134958 -428.465262) (xy 61.067638 -428.441705) (xy 61.003379 -428.41076) (xy 60.942988 -428.372814)
			(xy 60.887226 -428.328345) (xy 60.836793 -428.277912) (xy 60.792324 -428.22215) (xy 60.754378 -428.161759)
			(xy 60.723433 -428.0975) (xy 60.699876 -428.03018) (xy 60.684006 -427.960645) (xy 60.67602 -427.889771)
			(xy 59.704994 -427.889771) (xy 59.697008 -427.960645) (xy 59.681138 -428.03018) (xy 59.657581 -428.0975)
			(xy 59.626636 -428.161759) (xy 59.58869 -428.22215) (xy 59.544221 -428.277912) (xy 59.493788 -428.328345)
			(xy 59.438026 -428.372814) (xy 59.377635 -428.41076) (xy 59.313376 -428.441705) (xy 59.246056 -428.465262)
			(xy 59.176521 -428.481132) (xy 59.105647 -428.489118) (xy 59.034325 -428.489118) (xy 58.963451 -428.481132)
			(xy 58.893916 -428.465262) (xy 58.826596 -428.441705) (xy 58.762337 -428.41076) (xy 58.701946 -428.372814)
			(xy 58.646184 -428.328345) (xy 58.595751 -428.277912) (xy 58.551282 -428.22215) (xy 58.513336 -428.161759)
			(xy 58.482391 -428.0975) (xy 58.458834 -428.03018) (xy 58.442964 -427.960645) (xy 58.434978 -427.889771)
			(xy 57.818282 -427.889771) (xy 57.810296 -427.960645) (xy 57.794426 -428.03018) (xy 57.770869 -428.0975)
			(xy 57.739924 -428.161759) (xy 57.701978 -428.22215) (xy 57.657509 -428.277912) (xy 57.607076 -428.328345)
			(xy 57.551314 -428.372814) (xy 57.490923 -428.41076) (xy 57.426664 -428.441705) (xy 57.359344 -428.465262)
			(xy 57.289809 -428.481132) (xy 57.218935 -428.489118) (xy 57.147613 -428.489118) (xy 57.076739 -428.481132)
			(xy 57.007204 -428.465262) (xy 56.939884 -428.441705) (xy 56.875625 -428.41076) (xy 56.815234 -428.372814)
			(xy 56.759472 -428.328345) (xy 56.709039 -428.277912) (xy 56.66457 -428.22215) (xy 56.626624 -428.161759)
			(xy 56.595679 -428.0975) (xy 56.572122 -428.03018) (xy 56.556252 -427.960645) (xy 56.548266 -427.889771)
			(xy 29.40431 -427.889771) (xy 29.40431 -429.900943) (xy 56.504832 -429.900943) (xy 56.504832 -429.829621)
			(xy 56.512818 -429.758747) (xy 56.528688 -429.689212) (xy 56.552245 -429.621892) (xy 56.58319 -429.557633)
			(xy 56.621136 -429.497242) (xy 56.665605 -429.44148) (xy 56.716038 -429.391047) (xy 56.7718 -429.346578)
			(xy 56.832191 -429.308632) (xy 56.89645 -429.277687) (xy 56.96377 -429.25413) (xy 57.033305 -429.23826)
			(xy 57.104179 -429.230274) (xy 57.175501 -429.230274) (xy 57.246375 -429.23826) (xy 57.31591 -429.25413)
			(xy 57.38323 -429.277687) (xy 57.447489 -429.308632) (xy 57.50788 -429.346578) (xy 57.563642 -429.391047)
			(xy 57.614075 -429.44148) (xy 57.658544 -429.497242) (xy 57.69649 -429.557633) (xy 57.727435 -429.621892)
			(xy 57.750992 -429.689212) (xy 57.766862 -429.758747) (xy 57.774848 -429.829621) (xy 57.775348 -429.865282)
			(xy 57.774848 -429.900943) (xy 58.391544 -429.900943) (xy 58.391544 -429.829621) (xy 58.39953 -429.758747)
			(xy 58.4154 -429.689212) (xy 58.438957 -429.621892) (xy 58.469902 -429.557633) (xy 58.507848 -429.497242)
			(xy 58.552317 -429.44148) (xy 58.60275 -429.391047) (xy 58.658512 -429.346578) (xy 58.718903 -429.308632)
			(xy 58.783162 -429.277687) (xy 58.850482 -429.25413) (xy 58.920017 -429.23826) (xy 58.990891 -429.230274)
			(xy 59.062213 -429.230274) (xy 59.133087 -429.23826) (xy 59.202622 -429.25413) (xy 59.269942 -429.277687)
			(xy 59.334201 -429.308632) (xy 59.394592 -429.346578) (xy 59.450354 -429.391047) (xy 59.500787 -429.44148)
			(xy 59.545256 -429.497242) (xy 59.583202 -429.557633) (xy 59.614147 -429.621892) (xy 59.637704 -429.689212)
			(xy 59.653574 -429.758747) (xy 59.66156 -429.829621) (xy 59.66206 -429.865282) (xy 59.66156 -429.900943)
			(xy 60.632586 -429.900943) (xy 60.632586 -429.829621) (xy 60.640572 -429.758747) (xy 60.656442 -429.689212)
			(xy 60.679999 -429.621892) (xy 60.710944 -429.557633) (xy 60.74889 -429.497242) (xy 60.793359 -429.44148)
			(xy 60.843792 -429.391047) (xy 60.899554 -429.346578) (xy 60.959945 -429.308632) (xy 61.024204 -429.277687)
			(xy 61.091524 -429.25413) (xy 61.161059 -429.23826) (xy 61.231933 -429.230274) (xy 61.303255 -429.230274)
			(xy 61.374129 -429.23826) (xy 61.443664 -429.25413) (xy 61.510984 -429.277687) (xy 61.575243 -429.308632)
			(xy 61.635634 -429.346578) (xy 61.691396 -429.391047) (xy 61.741829 -429.44148) (xy 61.786298 -429.497242)
			(xy 61.824244 -429.557633) (xy 61.855189 -429.621892) (xy 61.878746 -429.689212) (xy 61.894616 -429.758747)
			(xy 61.902602 -429.829621) (xy 61.903102 -429.865282) (xy 61.902602 -429.900943) (xy 62.53657 -429.900943)
			(xy 62.53657 -429.829621) (xy 62.544556 -429.758747) (xy 62.560426 -429.689212) (xy 62.583983 -429.621892)
			(xy 62.614928 -429.557633) (xy 62.652874 -429.497242) (xy 62.697343 -429.44148) (xy 62.747776 -429.391047)
			(xy 62.803538 -429.346578) (xy 62.863929 -429.308632) (xy 62.928188 -429.277687) (xy 62.995508 -429.25413)
			(xy 63.065043 -429.23826) (xy 63.135917 -429.230274) (xy 63.207239 -429.230274) (xy 63.278113 -429.23826)
			(xy 63.347648 -429.25413) (xy 63.414968 -429.277687) (xy 63.479227 -429.308632) (xy 63.539618 -429.346578)
			(xy 63.59538 -429.391047) (xy 63.645813 -429.44148) (xy 63.690282 -429.497242) (xy 63.728228 -429.557633)
			(xy 63.759173 -429.621892) (xy 63.78273 -429.689212) (xy 63.7986 -429.758747) (xy 63.806586 -429.829621)
			(xy 63.807086 -429.865282) (xy 63.806586 -429.900943) (xy 63.7986 -429.971817) (xy 63.78273 -430.041352)
			(xy 63.759173 -430.108672) (xy 63.739263 -430.150016) (xy 69.997584 -430.150016) (xy 70.001572 -429.897396)
			(xy 70.013533 -429.645028) (xy 70.033455 -429.393164) (xy 70.061319 -429.142054) (xy 70.097095 -428.891948)
			(xy 70.140749 -428.643097) (xy 70.192238 -428.395748) (xy 70.251509 -428.150147) (xy 70.318504 -427.90654)
			(xy 70.393155 -427.66517) (xy 70.47539 -427.426276) (xy 70.565124 -427.190098) (xy 70.66227 -426.95687)
			(xy 70.76673 -426.726824) (xy 70.878401 -426.500192) (xy 70.99717 -426.277197) (xy 71.122919 -426.058063)
			(xy 71.255524 -425.843008) (xy 71.394851 -425.632246) (xy 71.540763 -425.425988) (xy 71.693113 -425.224439)
			(xy 71.851749 -425.027799) (xy 72.016514 -424.836266) (xy 72.187244 -424.650029) (xy 72.363768 -424.469275)
			(xy 72.54591 -424.294184) (xy 72.733488 -424.12493) (xy 72.926316 -423.961681) (xy 73.124201 -423.804602)
			(xy 73.326947 -423.653847) (xy 73.534351 -423.509569) (xy 73.746206 -423.371909) (xy 73.962301 -423.241006)
			(xy 74.182421 -423.11699) (xy 74.406346 -422.999985) (xy 74.633853 -422.890107) (xy 74.864715 -422.787466)
			(xy 75.098703 -422.692164) (xy 75.335582 -422.604297) (xy 75.575118 -422.52395) (xy 75.81707 -422.451206)
			(xy 76.061198 -422.386136) (xy 76.307259 -422.328806) (xy 76.555007 -422.279272) (xy 76.804195 -422.237583)
			(xy 77.054575 -422.203782) (xy 77.305897 -422.177901) (xy 77.557911 -422.159968) (xy 77.810365 -422.149999)
			(xy 78.063009 -422.148005) (xy 78.315589 -422.153987) (xy 78.567855 -422.16794) (xy 78.819554 -422.18985)
			(xy 79.070437 -422.219694) (xy 79.320252 -422.257444) (xy 79.568751 -422.303061) (xy 79.815686 -422.3565)
			(xy 80.060811 -422.417708) (xy 80.303881 -422.486623) (xy 80.544655 -422.563178) (xy 80.782892 -422.647295)
			(xy 81.018355 -422.738892) (xy 81.250809 -422.837876) (xy 81.480023 -422.944148) (xy 81.705767 -423.057604)
			(xy 81.927817 -423.178129) (xy 82.145951 -423.305605) (xy 82.359953 -423.439903) (xy 82.569609 -423.580889)
			(xy 82.774709 -423.728424) (xy 82.975049 -423.88236) (xy 83.17043 -424.042544) (xy 83.360657 -424.208816)
			(xy 83.54554 -424.381011) (xy 83.724896 -424.558955) (xy 83.898544 -424.742474) (xy 84.066312 -424.931382)
			(xy 84.228033 -425.125493) (xy 84.383546 -425.324612) (xy 84.532695 -425.528541) (xy 84.675332 -425.737077)
			(xy 84.811315 -425.950012) (xy 84.940508 -426.167134) (xy 85.062783 -426.388226) (xy 85.178017 -426.613067)
			(xy 85.286096 -426.841435) (xy 85.386911 -427.0731) (xy 85.480363 -427.307833) (xy 85.566358 -427.545398)
			(xy 85.644811 -427.78556) (xy 85.715643 -428.028079) (xy 85.778784 -428.272714) (xy 85.834171 -428.519219)
			(xy 85.881748 -428.76735) (xy 85.921468 -429.01686) (xy 85.953292 -429.267499) (xy 85.977188 -429.519017)
			(xy 85.993132 -429.771165) (xy 86.001107 -430.02369) (xy 86.001606 -430.150016) (xy 86.001107 -430.276342)
			(xy 85.993132 -430.528867) (xy 85.977188 -430.781015) (xy 85.953292 -431.032533) (xy 85.921468 -431.283172)
			(xy 85.881748 -431.532682) (xy 85.834171 -431.780813) (xy 85.778784 -432.027318) (xy 85.715643 -432.271953)
			(xy 85.644811 -432.514472) (xy 85.566358 -432.754634) (xy 85.480363 -432.992199) (xy 85.386911 -433.226932)
			(xy 85.286096 -433.458597) (xy 85.178017 -433.686965) (xy 85.062783 -433.911806) (xy 84.940508 -434.132898)
			(xy 84.811315 -434.35002) (xy 84.675332 -434.562955) (xy 84.532695 -434.771491) (xy 84.383546 -434.97542)
			(xy 84.228033 -435.174539) (xy 84.066312 -435.36865) (xy 83.898544 -435.557558) (xy 83.724896 -435.741077)
			(xy 83.54554 -435.919021) (xy 83.360657 -436.091216) (xy 83.17043 -436.257488) (xy 82.975049 -436.417672)
			(xy 82.774709 -436.571608) (xy 82.569609 -436.719143) (xy 82.359953 -436.860129) (xy 82.145951 -436.994427)
			(xy 81.927817 -437.121903) (xy 81.705767 -437.242428) (xy 81.480023 -437.355884) (xy 81.250809 -437.462156)
			(xy 81.018355 -437.56114) (xy 80.782892 -437.652737) (xy 80.544655 -437.736854) (xy 80.303881 -437.813409)
			(xy 80.060811 -437.882324) (xy 79.815686 -437.943532) (xy 79.568751 -437.996971) (xy 79.320252 -438.042588)
			(xy 79.070437 -438.080338) (xy 78.819554 -438.110182) (xy 78.567855 -438.132092) (xy 78.315589 -438.146045)
			(xy 78.063009 -438.152027) (xy 77.810365 -438.150033) (xy 77.557911 -438.140064) (xy 77.305897 -438.122131)
			(xy 77.054575 -438.09625) (xy 76.804195 -438.062449) (xy 76.555007 -438.02076) (xy 76.307259 -437.971226)
			(xy 76.061198 -437.913896) (xy 75.81707 -437.848826) (xy 75.575118 -437.776082) (xy 75.335582 -437.695735)
			(xy 75.098703 -437.607868) (xy 74.864715 -437.512566) (xy 74.633853 -437.409925) (xy 74.406346 -437.300047)
			(xy 74.182421 -437.183042) (xy 73.962301 -437.059026) (xy 73.746206 -436.928123) (xy 73.534351 -436.790463)
			(xy 73.326947 -436.646185) (xy 73.124201 -436.49543) (xy 72.926316 -436.338351) (xy 72.733488 -436.175102)
			(xy 72.54591 -436.005848) (xy 72.363768 -435.830757) (xy 72.187244 -435.650003) (xy 72.016514 -435.463766)
			(xy 71.851749 -435.272233) (xy 71.693113 -435.075593) (xy 71.540763 -434.874044) (xy 71.394851 -434.667786)
			(xy 71.255524 -434.457024) (xy 71.122919 -434.241969) (xy 70.99717 -434.022835) (xy 70.878401 -433.79984)
			(xy 70.76673 -433.573208) (xy 70.66227 -433.343162) (xy 70.565124 -433.109934) (xy 70.47539 -432.873756)
			(xy 70.393155 -432.634862) (xy 70.318504 -432.393492) (xy 70.251509 -432.149885) (xy 70.192238 -431.904284)
			(xy 70.140749 -431.656935) (xy 70.097095 -431.408084) (xy 70.061319 -431.157978) (xy 70.033455 -430.906868)
			(xy 70.013533 -430.655004) (xy 70.001572 -430.402636) (xy 69.997584 -430.150016) (xy 63.739263 -430.150016)
			(xy 63.728228 -430.172931) (xy 63.690282 -430.233322) (xy 63.645813 -430.289084) (xy 63.59538 -430.339517)
			(xy 63.539618 -430.383986) (xy 63.479227 -430.421932) (xy 63.414968 -430.452877) (xy 63.347648 -430.476434)
			(xy 63.278113 -430.492304) (xy 63.207239 -430.50029) (xy 63.135917 -430.50029) (xy 63.065043 -430.492304)
			(xy 62.995508 -430.476434) (xy 62.928188 -430.452877) (xy 62.863929 -430.421932) (xy 62.803538 -430.383986)
			(xy 62.747776 -430.339517) (xy 62.697343 -430.289084) (xy 62.652874 -430.233322) (xy 62.614928 -430.172931)
			(xy 62.583983 -430.108672) (xy 62.560426 -430.041352) (xy 62.544556 -429.971817) (xy 62.53657 -429.900943)
			(xy 61.902602 -429.900943) (xy 61.894616 -429.971817) (xy 61.878746 -430.041352) (xy 61.855189 -430.108672)
			(xy 61.824244 -430.172931) (xy 61.786298 -430.233322) (xy 61.741829 -430.289084) (xy 61.691396 -430.339517)
			(xy 61.635634 -430.383986) (xy 61.575243 -430.421932) (xy 61.510984 -430.452877) (xy 61.443664 -430.476434)
			(xy 61.374129 -430.492304) (xy 61.303255 -430.50029) (xy 61.231933 -430.50029) (xy 61.161059 -430.492304)
			(xy 61.091524 -430.476434) (xy 61.024204 -430.452877) (xy 60.959945 -430.421932) (xy 60.899554 -430.383986)
			(xy 60.843792 -430.339517) (xy 60.793359 -430.289084) (xy 60.74889 -430.233322) (xy 60.710944 -430.172931)
			(xy 60.679999 -430.108672) (xy 60.656442 -430.041352) (xy 60.640572 -429.971817) (xy 60.632586 -429.900943)
			(xy 59.66156 -429.900943) (xy 59.653574 -429.971817) (xy 59.637704 -430.041352) (xy 59.614147 -430.108672)
			(xy 59.583202 -430.172931) (xy 59.545256 -430.233322) (xy 59.500787 -430.289084) (xy 59.450354 -430.339517)
			(xy 59.394592 -430.383986) (xy 59.334201 -430.421932) (xy 59.269942 -430.452877) (xy 59.202622 -430.476434)
			(xy 59.133087 -430.492304) (xy 59.062213 -430.50029) (xy 58.990891 -430.50029) (xy 58.920017 -430.492304)
			(xy 58.850482 -430.476434) (xy 58.783162 -430.452877) (xy 58.718903 -430.421932) (xy 58.658512 -430.383986)
			(xy 58.60275 -430.339517) (xy 58.552317 -430.289084) (xy 58.507848 -430.233322) (xy 58.469902 -430.172931)
			(xy 58.438957 -430.108672) (xy 58.4154 -430.041352) (xy 58.39953 -429.971817) (xy 58.391544 -429.900943)
			(xy 57.774848 -429.900943) (xy 57.766862 -429.971817) (xy 57.750992 -430.041352) (xy 57.727435 -430.108672)
			(xy 57.69649 -430.172931) (xy 57.658544 -430.233322) (xy 57.614075 -430.289084) (xy 57.563642 -430.339517)
			(xy 57.50788 -430.383986) (xy 57.447489 -430.421932) (xy 57.38323 -430.452877) (xy 57.31591 -430.476434)
			(xy 57.246375 -430.492304) (xy 57.175501 -430.50029) (xy 57.104179 -430.50029) (xy 57.033305 -430.492304)
			(xy 56.96377 -430.476434) (xy 56.89645 -430.452877) (xy 56.832191 -430.421932) (xy 56.7718 -430.383986)
			(xy 56.716038 -430.339517) (xy 56.665605 -430.289084) (xy 56.621136 -430.233322) (xy 56.58319 -430.172931)
			(xy 56.552245 -430.108672) (xy 56.528688 -430.041352) (xy 56.512818 -429.971817) (xy 56.504832 -429.900943)
			(xy 29.40431 -429.900943) (xy 29.40431 -431.791465) (xy 56.504832 -431.791465) (xy 56.504832 -431.720143)
			(xy 56.512818 -431.649269) (xy 56.528688 -431.579734) (xy 56.552245 -431.512414) (xy 56.58319 -431.448155)
			(xy 56.621136 -431.387764) (xy 56.665605 -431.332002) (xy 56.716038 -431.281569) (xy 56.7718 -431.2371)
			(xy 56.832191 -431.199154) (xy 56.89645 -431.168209) (xy 56.96377 -431.144652) (xy 57.033305 -431.128782)
			(xy 57.104179 -431.120796) (xy 57.175501 -431.120796) (xy 57.246375 -431.128782) (xy 57.31591 -431.144652)
			(xy 57.38323 -431.168209) (xy 57.447489 -431.199154) (xy 57.50788 -431.2371) (xy 57.563642 -431.281569)
			(xy 57.614075 -431.332002) (xy 57.658544 -431.387764) (xy 57.69649 -431.448155) (xy 57.727435 -431.512414)
			(xy 57.750992 -431.579734) (xy 57.766862 -431.649269) (xy 57.774848 -431.720143) (xy 57.775348 -431.755804)
			(xy 57.774848 -431.791465) (xy 58.391544 -431.791465) (xy 58.391544 -431.720143) (xy 58.39953 -431.649269)
			(xy 58.4154 -431.579734) (xy 58.438957 -431.512414) (xy 58.469902 -431.448155) (xy 58.507848 -431.387764)
			(xy 58.552317 -431.332002) (xy 58.60275 -431.281569) (xy 58.658512 -431.2371) (xy 58.718903 -431.199154)
			(xy 58.783162 -431.168209) (xy 58.850482 -431.144652) (xy 58.920017 -431.128782) (xy 58.990891 -431.120796)
			(xy 59.062213 -431.120796) (xy 59.133087 -431.128782) (xy 59.202622 -431.144652) (xy 59.269942 -431.168209)
			(xy 59.334201 -431.199154) (xy 59.394592 -431.2371) (xy 59.450354 -431.281569) (xy 59.500787 -431.332002)
			(xy 59.545256 -431.387764) (xy 59.583202 -431.448155) (xy 59.614147 -431.512414) (xy 59.637704 -431.579734)
			(xy 59.653574 -431.649269) (xy 59.66156 -431.720143) (xy 59.66206 -431.755804) (xy 59.66156 -431.791465)
			(xy 60.632586 -431.791465) (xy 60.632586 -431.720143) (xy 60.640572 -431.649269) (xy 60.656442 -431.579734)
			(xy 60.679999 -431.512414) (xy 60.710944 -431.448155) (xy 60.74889 -431.387764) (xy 60.793359 -431.332002)
			(xy 60.843792 -431.281569) (xy 60.899554 -431.2371) (xy 60.959945 -431.199154) (xy 61.024204 -431.168209)
			(xy 61.091524 -431.144652) (xy 61.161059 -431.128782) (xy 61.231933 -431.120796) (xy 61.303255 -431.120796)
			(xy 61.374129 -431.128782) (xy 61.443664 -431.144652) (xy 61.510984 -431.168209) (xy 61.575243 -431.199154)
			(xy 61.635634 -431.2371) (xy 61.691396 -431.281569) (xy 61.741829 -431.332002) (xy 61.786298 -431.387764)
			(xy 61.824244 -431.448155) (xy 61.855189 -431.512414) (xy 61.878746 -431.579734) (xy 61.894616 -431.649269)
			(xy 61.902602 -431.720143) (xy 61.903102 -431.755804) (xy 61.902602 -431.791465) (xy 62.53657 -431.791465)
			(xy 62.53657 -431.720143) (xy 62.544556 -431.649269) (xy 62.560426 -431.579734) (xy 62.583983 -431.512414)
			(xy 62.614928 -431.448155) (xy 62.652874 -431.387764) (xy 62.697343 -431.332002) (xy 62.747776 -431.281569)
			(xy 62.803538 -431.2371) (xy 62.863929 -431.199154) (xy 62.928188 -431.168209) (xy 62.995508 -431.144652)
			(xy 63.065043 -431.128782) (xy 63.135917 -431.120796) (xy 63.207239 -431.120796) (xy 63.278113 -431.128782)
			(xy 63.347648 -431.144652) (xy 63.414968 -431.168209) (xy 63.479227 -431.199154) (xy 63.539618 -431.2371)
			(xy 63.59538 -431.281569) (xy 63.645813 -431.332002) (xy 63.690282 -431.387764) (xy 63.728228 -431.448155)
			(xy 63.759173 -431.512414) (xy 63.78273 -431.579734) (xy 63.7986 -431.649269) (xy 63.806586 -431.720143)
			(xy 63.807086 -431.755804) (xy 63.806586 -431.791465) (xy 63.7986 -431.862339) (xy 63.78273 -431.931874)
			(xy 63.759173 -431.999194) (xy 63.728228 -432.063453) (xy 63.690282 -432.123844) (xy 63.645813 -432.179606)
			(xy 63.59538 -432.230039) (xy 63.539618 -432.274508) (xy 63.479227 -432.312454) (xy 63.414968 -432.343399)
			(xy 63.347648 -432.366956) (xy 63.278113 -432.382826) (xy 63.207239 -432.390812) (xy 63.135917 -432.390812)
			(xy 63.065043 -432.382826) (xy 62.995508 -432.366956) (xy 62.928188 -432.343399) (xy 62.863929 -432.312454)
			(xy 62.803538 -432.274508) (xy 62.747776 -432.230039) (xy 62.697343 -432.179606) (xy 62.652874 -432.123844)
			(xy 62.614928 -432.063453) (xy 62.583983 -431.999194) (xy 62.560426 -431.931874) (xy 62.544556 -431.862339)
			(xy 62.53657 -431.791465) (xy 61.902602 -431.791465) (xy 61.894616 -431.862339) (xy 61.878746 -431.931874)
			(xy 61.855189 -431.999194) (xy 61.824244 -432.063453) (xy 61.786298 -432.123844) (xy 61.741829 -432.179606)
			(xy 61.691396 -432.230039) (xy 61.635634 -432.274508) (xy 61.575243 -432.312454) (xy 61.510984 -432.343399)
			(xy 61.443664 -432.366956) (xy 61.374129 -432.382826) (xy 61.303255 -432.390812) (xy 61.231933 -432.390812)
			(xy 61.161059 -432.382826) (xy 61.091524 -432.366956) (xy 61.024204 -432.343399) (xy 60.959945 -432.312454)
			(xy 60.899554 -432.274508) (xy 60.843792 -432.230039) (xy 60.793359 -432.179606) (xy 60.74889 -432.123844)
			(xy 60.710944 -432.063453) (xy 60.679999 -431.999194) (xy 60.656442 -431.931874) (xy 60.640572 -431.862339)
			(xy 60.632586 -431.791465) (xy 59.66156 -431.791465) (xy 59.653574 -431.862339) (xy 59.637704 -431.931874)
			(xy 59.614147 -431.999194) (xy 59.583202 -432.063453) (xy 59.545256 -432.123844) (xy 59.500787 -432.179606)
			(xy 59.450354 -432.230039) (xy 59.394592 -432.274508) (xy 59.334201 -432.312454) (xy 59.269942 -432.343399)
			(xy 59.202622 -432.366956) (xy 59.133087 -432.382826) (xy 59.062213 -432.390812) (xy 58.990891 -432.390812)
			(xy 58.920017 -432.382826) (xy 58.850482 -432.366956) (xy 58.783162 -432.343399) (xy 58.718903 -432.312454)
			(xy 58.658512 -432.274508) (xy 58.60275 -432.230039) (xy 58.552317 -432.179606) (xy 58.507848 -432.123844)
			(xy 58.469902 -432.063453) (xy 58.438957 -431.999194) (xy 58.4154 -431.931874) (xy 58.39953 -431.862339)
			(xy 58.391544 -431.791465) (xy 57.774848 -431.791465) (xy 57.766862 -431.862339) (xy 57.750992 -431.931874)
			(xy 57.727435 -431.999194) (xy 57.69649 -432.063453) (xy 57.658544 -432.123844) (xy 57.614075 -432.179606)
			(xy 57.563642 -432.230039) (xy 57.50788 -432.274508) (xy 57.447489 -432.312454) (xy 57.38323 -432.343399)
			(xy 57.31591 -432.366956) (xy 57.246375 -432.382826) (xy 57.175501 -432.390812) (xy 57.104179 -432.390812)
			(xy 57.033305 -432.382826) (xy 56.96377 -432.366956) (xy 56.89645 -432.343399) (xy 56.832191 -432.312454)
			(xy 56.7718 -432.274508) (xy 56.716038 -432.230039) (xy 56.665605 -432.179606) (xy 56.621136 -432.123844)
			(xy 56.58319 -432.063453) (xy 56.552245 -431.999194) (xy 56.528688 -431.931874) (xy 56.512818 -431.862339)
			(xy 56.504832 -431.791465) (xy 29.40431 -431.791465) (xy 29.40431 -433.832609) (xy 56.504832 -433.832609)
			(xy 56.504832 -433.761287) (xy 56.512818 -433.690413) (xy 56.528688 -433.620878) (xy 56.552245 -433.553558)
			(xy 56.58319 -433.489299) (xy 56.621136 -433.428908) (xy 56.665605 -433.373146) (xy 56.716038 -433.322713)
			(xy 56.7718 -433.278244) (xy 56.832191 -433.240298) (xy 56.89645 -433.209353) (xy 56.96377 -433.185796)
			(xy 57.033305 -433.169926) (xy 57.104179 -433.16194) (xy 57.175501 -433.16194) (xy 57.246375 -433.169926)
			(xy 57.31591 -433.185796) (xy 57.38323 -433.209353) (xy 57.447489 -433.240298) (xy 57.50788 -433.278244)
			(xy 57.563642 -433.322713) (xy 57.614075 -433.373146) (xy 57.658544 -433.428908) (xy 57.69649 -433.489299)
			(xy 57.727435 -433.553558) (xy 57.750992 -433.620878) (xy 57.766862 -433.690413) (xy 57.774848 -433.761287)
			(xy 57.775348 -433.796948) (xy 57.774848 -433.832609) (xy 58.391544 -433.832609) (xy 58.391544 -433.761287)
			(xy 58.39953 -433.690413) (xy 58.4154 -433.620878) (xy 58.438957 -433.553558) (xy 58.469902 -433.489299)
			(xy 58.507848 -433.428908) (xy 58.552317 -433.373146) (xy 58.60275 -433.322713) (xy 58.658512 -433.278244)
			(xy 58.718903 -433.240298) (xy 58.783162 -433.209353) (xy 58.850482 -433.185796) (xy 58.920017 -433.169926)
			(xy 58.990891 -433.16194) (xy 59.062213 -433.16194) (xy 59.133087 -433.169926) (xy 59.202622 -433.185796)
			(xy 59.269942 -433.209353) (xy 59.334201 -433.240298) (xy 59.394592 -433.278244) (xy 59.450354 -433.322713)
			(xy 59.500787 -433.373146) (xy 59.545256 -433.428908) (xy 59.583202 -433.489299) (xy 59.614147 -433.553558)
			(xy 59.637704 -433.620878) (xy 59.653574 -433.690413) (xy 59.66156 -433.761287) (xy 59.66206 -433.796948)
			(xy 59.66156 -433.832609) (xy 60.632586 -433.832609) (xy 60.632586 -433.761287) (xy 60.640572 -433.690413)
			(xy 60.656442 -433.620878) (xy 60.679999 -433.553558) (xy 60.710944 -433.489299) (xy 60.74889 -433.428908)
			(xy 60.793359 -433.373146) (xy 60.843792 -433.322713) (xy 60.899554 -433.278244) (xy 60.959945 -433.240298)
			(xy 61.024204 -433.209353) (xy 61.091524 -433.185796) (xy 61.161059 -433.169926) (xy 61.231933 -433.16194)
			(xy 61.303255 -433.16194) (xy 61.374129 -433.169926) (xy 61.443664 -433.185796) (xy 61.510984 -433.209353)
			(xy 61.575243 -433.240298) (xy 61.635634 -433.278244) (xy 61.691396 -433.322713) (xy 61.741829 -433.373146)
			(xy 61.786298 -433.428908) (xy 61.824244 -433.489299) (xy 61.855189 -433.553558) (xy 61.878746 -433.620878)
			(xy 61.894616 -433.690413) (xy 61.902602 -433.761287) (xy 61.903102 -433.796948) (xy 61.902602 -433.832609)
			(xy 62.53657 -433.832609) (xy 62.53657 -433.761287) (xy 62.544556 -433.690413) (xy 62.560426 -433.620878)
			(xy 62.583983 -433.553558) (xy 62.614928 -433.489299) (xy 62.652874 -433.428908) (xy 62.697343 -433.373146)
			(xy 62.747776 -433.322713) (xy 62.803538 -433.278244) (xy 62.863929 -433.240298) (xy 62.928188 -433.209353)
			(xy 62.995508 -433.185796) (xy 63.065043 -433.169926) (xy 63.135917 -433.16194) (xy 63.207239 -433.16194)
			(xy 63.278113 -433.169926) (xy 63.347648 -433.185796) (xy 63.414968 -433.209353) (xy 63.479227 -433.240298)
			(xy 63.539618 -433.278244) (xy 63.59538 -433.322713) (xy 63.645813 -433.373146) (xy 63.690282 -433.428908)
			(xy 63.728228 -433.489299) (xy 63.759173 -433.553558) (xy 63.78273 -433.620878) (xy 63.7986 -433.690413)
			(xy 63.806586 -433.761287) (xy 63.807086 -433.796948) (xy 63.806586 -433.832609) (xy 63.7986 -433.903483)
			(xy 63.78273 -433.973018) (xy 63.759173 -434.040338) (xy 63.728228 -434.104597) (xy 63.690282 -434.164988)
			(xy 63.645813 -434.22075) (xy 63.59538 -434.271183) (xy 63.539618 -434.315652) (xy 63.479227 -434.353598)
			(xy 63.414968 -434.384543) (xy 63.347648 -434.4081) (xy 63.278113 -434.42397) (xy 63.207239 -434.431956)
			(xy 63.135917 -434.431956) (xy 63.065043 -434.42397) (xy 62.995508 -434.4081) (xy 62.928188 -434.384543)
			(xy 62.863929 -434.353598) (xy 62.803538 -434.315652) (xy 62.747776 -434.271183) (xy 62.697343 -434.22075)
			(xy 62.652874 -434.164988) (xy 62.614928 -434.104597) (xy 62.583983 -434.040338) (xy 62.560426 -433.973018)
			(xy 62.544556 -433.903483) (xy 62.53657 -433.832609) (xy 61.902602 -433.832609) (xy 61.894616 -433.903483)
			(xy 61.878746 -433.973018) (xy 61.855189 -434.040338) (xy 61.824244 -434.104597) (xy 61.786298 -434.164988)
			(xy 61.741829 -434.22075) (xy 61.691396 -434.271183) (xy 61.635634 -434.315652) (xy 61.575243 -434.353598)
			(xy 61.510984 -434.384543) (xy 61.443664 -434.4081) (xy 61.374129 -434.42397) (xy 61.303255 -434.431956)
			(xy 61.231933 -434.431956) (xy 61.161059 -434.42397) (xy 61.091524 -434.4081) (xy 61.024204 -434.384543)
			(xy 60.959945 -434.353598) (xy 60.899554 -434.315652) (xy 60.843792 -434.271183) (xy 60.793359 -434.22075)
			(xy 60.74889 -434.164988) (xy 60.710944 -434.104597) (xy 60.679999 -434.040338) (xy 60.656442 -433.973018)
			(xy 60.640572 -433.903483) (xy 60.632586 -433.832609) (xy 59.66156 -433.832609) (xy 59.653574 -433.903483)
			(xy 59.637704 -433.973018) (xy 59.614147 -434.040338) (xy 59.583202 -434.104597) (xy 59.545256 -434.164988)
			(xy 59.500787 -434.22075) (xy 59.450354 -434.271183) (xy 59.394592 -434.315652) (xy 59.334201 -434.353598)
			(xy 59.269942 -434.384543) (xy 59.202622 -434.4081) (xy 59.133087 -434.42397) (xy 59.062213 -434.431956)
			(xy 58.990891 -434.431956) (xy 58.920017 -434.42397) (xy 58.850482 -434.4081) (xy 58.783162 -434.384543)
			(xy 58.718903 -434.353598) (xy 58.658512 -434.315652) (xy 58.60275 -434.271183) (xy 58.552317 -434.22075)
			(xy 58.507848 -434.164988) (xy 58.469902 -434.104597) (xy 58.438957 -434.040338) (xy 58.4154 -433.973018)
			(xy 58.39953 -433.903483) (xy 58.391544 -433.832609) (xy 57.774848 -433.832609) (xy 57.766862 -433.903483)
			(xy 57.750992 -433.973018) (xy 57.727435 -434.040338) (xy 57.69649 -434.104597) (xy 57.658544 -434.164988)
			(xy 57.614075 -434.22075) (xy 57.563642 -434.271183) (xy 57.50788 -434.315652) (xy 57.447489 -434.353598)
			(xy 57.38323 -434.384543) (xy 57.31591 -434.4081) (xy 57.246375 -434.42397) (xy 57.175501 -434.431956)
			(xy 57.104179 -434.431956) (xy 57.033305 -434.42397) (xy 56.96377 -434.4081) (xy 56.89645 -434.384543)
			(xy 56.832191 -434.353598) (xy 56.7718 -434.315652) (xy 56.716038 -434.271183) (xy 56.665605 -434.22075)
			(xy 56.621136 -434.164988) (xy 56.58319 -434.104597) (xy 56.552245 -434.040338) (xy 56.528688 -433.973018)
			(xy 56.512818 -433.903483) (xy 56.504832 -433.832609) (xy 29.40431 -433.832609) (xy 29.40431 -435.742435)
			(xy 56.504832 -435.742435) (xy 56.504832 -435.671113) (xy 56.512818 -435.600239) (xy 56.528688 -435.530704)
			(xy 56.552245 -435.463384) (xy 56.58319 -435.399125) (xy 56.621136 -435.338734) (xy 56.665605 -435.282972)
			(xy 56.716038 -435.232539) (xy 56.7718 -435.18807) (xy 56.832191 -435.150124) (xy 56.89645 -435.119179)
			(xy 56.96377 -435.095622) (xy 57.033305 -435.079752) (xy 57.104179 -435.071766) (xy 57.175501 -435.071766)
			(xy 57.246375 -435.079752) (xy 57.31591 -435.095622) (xy 57.38323 -435.119179) (xy 57.447489 -435.150124)
			(xy 57.50788 -435.18807) (xy 57.563642 -435.232539) (xy 57.614075 -435.282972) (xy 57.658544 -435.338734)
			(xy 57.69649 -435.399125) (xy 57.727435 -435.463384) (xy 57.750992 -435.530704) (xy 57.766862 -435.600239)
			(xy 57.774848 -435.671113) (xy 57.775348 -435.706774) (xy 57.774848 -435.742435) (xy 58.391544 -435.742435)
			(xy 58.391544 -435.671113) (xy 58.39953 -435.600239) (xy 58.4154 -435.530704) (xy 58.438957 -435.463384)
			(xy 58.469902 -435.399125) (xy 58.507848 -435.338734) (xy 58.552317 -435.282972) (xy 58.60275 -435.232539)
			(xy 58.658512 -435.18807) (xy 58.718903 -435.150124) (xy 58.783162 -435.119179) (xy 58.850482 -435.095622)
			(xy 58.920017 -435.079752) (xy 58.990891 -435.071766) (xy 59.062213 -435.071766) (xy 59.133087 -435.079752)
			(xy 59.202622 -435.095622) (xy 59.269942 -435.119179) (xy 59.334201 -435.150124) (xy 59.394592 -435.18807)
			(xy 59.450354 -435.232539) (xy 59.500787 -435.282972) (xy 59.545256 -435.338734) (xy 59.583202 -435.399125)
			(xy 59.614147 -435.463384) (xy 59.637704 -435.530704) (xy 59.653574 -435.600239) (xy 59.66156 -435.671113)
			(xy 59.66206 -435.706774) (xy 59.66156 -435.742435) (xy 60.632586 -435.742435) (xy 60.632586 -435.671113)
			(xy 60.640572 -435.600239) (xy 60.656442 -435.530704) (xy 60.679999 -435.463384) (xy 60.710944 -435.399125)
			(xy 60.74889 -435.338734) (xy 60.793359 -435.282972) (xy 60.843792 -435.232539) (xy 60.899554 -435.18807)
			(xy 60.959945 -435.150124) (xy 61.024204 -435.119179) (xy 61.091524 -435.095622) (xy 61.161059 -435.079752)
			(xy 61.231933 -435.071766) (xy 61.303255 -435.071766) (xy 61.374129 -435.079752) (xy 61.443664 -435.095622)
			(xy 61.510984 -435.119179) (xy 61.575243 -435.150124) (xy 61.635634 -435.18807) (xy 61.691396 -435.232539)
			(xy 61.741829 -435.282972) (xy 61.786298 -435.338734) (xy 61.824244 -435.399125) (xy 61.855189 -435.463384)
			(xy 61.878746 -435.530704) (xy 61.894616 -435.600239) (xy 61.902602 -435.671113) (xy 61.903102 -435.706774)
			(xy 61.902602 -435.742435) (xy 62.53657 -435.742435) (xy 62.53657 -435.671113) (xy 62.544556 -435.600239)
			(xy 62.560426 -435.530704) (xy 62.583983 -435.463384) (xy 62.614928 -435.399125) (xy 62.652874 -435.338734)
			(xy 62.697343 -435.282972) (xy 62.747776 -435.232539) (xy 62.803538 -435.18807) (xy 62.863929 -435.150124)
			(xy 62.928188 -435.119179) (xy 62.995508 -435.095622) (xy 63.065043 -435.079752) (xy 63.135917 -435.071766)
			(xy 63.207239 -435.071766) (xy 63.278113 -435.079752) (xy 63.347648 -435.095622) (xy 63.414968 -435.119179)
			(xy 63.479227 -435.150124) (xy 63.539618 -435.18807) (xy 63.59538 -435.232539) (xy 63.645813 -435.282972)
			(xy 63.690282 -435.338734) (xy 63.728228 -435.399125) (xy 63.759173 -435.463384) (xy 63.78273 -435.530704)
			(xy 63.7986 -435.600239) (xy 63.806586 -435.671113) (xy 63.807086 -435.706774) (xy 63.806586 -435.742435)
			(xy 63.7986 -435.813309) (xy 63.78273 -435.882844) (xy 63.759173 -435.950164) (xy 63.728228 -436.014423)
			(xy 63.690282 -436.074814) (xy 63.645813 -436.130576) (xy 63.59538 -436.181009) (xy 63.539618 -436.225478)
			(xy 63.479227 -436.263424) (xy 63.414968 -436.294369) (xy 63.347648 -436.317926) (xy 63.278113 -436.333796)
			(xy 63.207239 -436.341782) (xy 63.135917 -436.341782) (xy 63.065043 -436.333796) (xy 62.995508 -436.317926)
			(xy 62.928188 -436.294369) (xy 62.863929 -436.263424) (xy 62.803538 -436.225478) (xy 62.747776 -436.181009)
			(xy 62.697343 -436.130576) (xy 62.652874 -436.074814) (xy 62.614928 -436.014423) (xy 62.583983 -435.950164)
			(xy 62.560426 -435.882844) (xy 62.544556 -435.813309) (xy 62.53657 -435.742435) (xy 61.902602 -435.742435)
			(xy 61.894616 -435.813309) (xy 61.878746 -435.882844) (xy 61.855189 -435.950164) (xy 61.824244 -436.014423)
			(xy 61.786298 -436.074814) (xy 61.741829 -436.130576) (xy 61.691396 -436.181009) (xy 61.635634 -436.225478)
			(xy 61.575243 -436.263424) (xy 61.510984 -436.294369) (xy 61.443664 -436.317926) (xy 61.374129 -436.333796)
			(xy 61.303255 -436.341782) (xy 61.231933 -436.341782) (xy 61.161059 -436.333796) (xy 61.091524 -436.317926)
			(xy 61.024204 -436.294369) (xy 60.959945 -436.263424) (xy 60.899554 -436.225478) (xy 60.843792 -436.181009)
			(xy 60.793359 -436.130576) (xy 60.74889 -436.074814) (xy 60.710944 -436.014423) (xy 60.679999 -435.950164)
			(xy 60.656442 -435.882844) (xy 60.640572 -435.813309) (xy 60.632586 -435.742435) (xy 59.66156 -435.742435)
			(xy 59.653574 -435.813309) (xy 59.637704 -435.882844) (xy 59.614147 -435.950164) (xy 59.583202 -436.014423)
			(xy 59.545256 -436.074814) (xy 59.500787 -436.130576) (xy 59.450354 -436.181009) (xy 59.394592 -436.225478)
			(xy 59.334201 -436.263424) (xy 59.269942 -436.294369) (xy 59.202622 -436.317926) (xy 59.133087 -436.333796)
			(xy 59.062213 -436.341782) (xy 58.990891 -436.341782) (xy 58.920017 -436.333796) (xy 58.850482 -436.317926)
			(xy 58.783162 -436.294369) (xy 58.718903 -436.263424) (xy 58.658512 -436.225478) (xy 58.60275 -436.181009)
			(xy 58.552317 -436.130576) (xy 58.507848 -436.074814) (xy 58.469902 -436.014423) (xy 58.438957 -435.950164)
			(xy 58.4154 -435.882844) (xy 58.39953 -435.813309) (xy 58.391544 -435.742435) (xy 57.774848 -435.742435)
			(xy 57.766862 -435.813309) (xy 57.750992 -435.882844) (xy 57.727435 -435.950164) (xy 57.69649 -436.014423)
			(xy 57.658544 -436.074814) (xy 57.614075 -436.130576) (xy 57.563642 -436.181009) (xy 57.50788 -436.225478)
			(xy 57.447489 -436.263424) (xy 57.38323 -436.294369) (xy 57.31591 -436.317926) (xy 57.246375 -436.333796)
			(xy 57.175501 -436.341782) (xy 57.104179 -436.341782) (xy 57.033305 -436.333796) (xy 56.96377 -436.317926)
			(xy 56.89645 -436.294369) (xy 56.832191 -436.263424) (xy 56.7718 -436.225478) (xy 56.716038 -436.181009)
			(xy 56.665605 -436.130576) (xy 56.621136 -436.074814) (xy 56.58319 -436.014423) (xy 56.552245 -435.950164)
			(xy 56.528688 -435.882844) (xy 56.512818 -435.813309) (xy 56.504832 -435.742435) (xy 29.40431 -435.742435)
			(xy 29.40431 -440.157362) (xy 41.72661 -440.157362) (xy 41.730681 -440.10174) (xy 41.742807 -440.047303)
			(xy 41.76273 -439.995212) (xy 41.790026 -439.946577) (xy 41.824112 -439.902434) (xy 41.864261 -439.863725)
			(xy 41.909619 -439.831274) (xy 41.959219 -439.805773) (xy 42.012003 -439.787766) (xy 42.066846 -439.777636)
			(xy 42.12258 -439.775599) (xy 42.178017 -439.781699) (xy 42.231974 -439.795805) (xy 42.250574 -439.803709)
			(xy 47.842668 -439.803709) (xy 47.842668 -439.722599) (xy 47.850618 -439.64188) (xy 47.866441 -439.562329)
			(xy 47.889986 -439.484713) (xy 47.921025 -439.409777) (xy 47.95926 -439.338245) (xy 48.004322 -439.270805)
			(xy 48.055777 -439.208106) (xy 48.11313 -439.150753) (xy 48.175829 -439.099298) (xy 48.243269 -439.054236)
			(xy 48.314801 -439.016001) (xy 48.389737 -438.984962) (xy 48.467353 -438.961417) (xy 48.546904 -438.945594)
			(xy 48.627623 -438.937644) (xy 48.708733 -438.937644) (xy 48.789452 -438.945594) (xy 48.869003 -438.961417)
			(xy 48.946619 -438.984962) (xy 49.021555 -439.016001) (xy 49.093087 -439.054236) (xy 49.160527 -439.099298)
			(xy 49.223226 -439.150753) (xy 49.280579 -439.208106) (xy 49.332034 -439.270805) (xy 49.377096 -439.338245)
			(xy 49.415331 -439.409777) (xy 49.44637 -439.484713) (xy 49.469915 -439.562329) (xy 49.485738 -439.64188)
			(xy 49.493688 -439.722599) (xy 49.494186 -439.763154) (xy 49.493688 -439.803709) (xy 49.485738 -439.884428)
			(xy 49.469915 -439.963979) (xy 49.44637 -440.041595) (xy 49.415331 -440.116531) (xy 49.377096 -440.188063)
			(xy 49.332034 -440.255503) (xy 49.280579 -440.318202) (xy 49.223226 -440.375555) (xy 49.160527 -440.42701)
			(xy 49.093087 -440.472072) (xy 49.021555 -440.510307) (xy 48.946619 -440.541346) (xy 48.869003 -440.564891)
			(xy 48.789452 -440.580714) (xy 48.708733 -440.588664) (xy 48.627623 -440.588664) (xy 48.546904 -440.580714)
			(xy 48.467353 -440.564891) (xy 48.389737 -440.541346) (xy 48.314801 -440.510307) (xy 48.243269 -440.472072)
			(xy 48.175829 -440.42701) (xy 48.11313 -440.375555) (xy 48.055777 -440.318202) (xy 48.004322 -440.255503)
			(xy 47.95926 -440.188063) (xy 47.921025 -440.116531) (xy 47.889986 -440.041595) (xy 47.866441 -439.963979)
			(xy 47.850618 -439.884428) (xy 47.842668 -439.803709) (xy 42.250574 -439.803709) (xy 42.283303 -439.817617)
			(xy 42.330909 -439.846671) (xy 42.373777 -439.882346) (xy 42.410994 -439.923883) (xy 42.441767 -439.970396)
			(xy 42.465439 -440.020893) (xy 42.481507 -440.0743) (xy 42.489627 -440.129476) (xy 42.490136 -440.157362)
			(xy 42.489627 -440.185248) (xy 42.481507 -440.240424) (xy 42.465439 -440.293831) (xy 42.441767 -440.344328)
			(xy 42.410994 -440.390841) (xy 42.373777 -440.432378) (xy 42.330909 -440.468053) (xy 42.283303 -440.497107)
			(xy 42.231974 -440.518919) (xy 42.178017 -440.533025) (xy 42.12258 -440.539125) (xy 42.066846 -440.537088)
			(xy 42.012003 -440.526958) (xy 41.959219 -440.508951) (xy 41.909619 -440.48345) (xy 41.864261 -440.450999)
			(xy 41.824112 -440.41229) (xy 41.790026 -440.368147) (xy 41.76273 -440.319512) (xy 41.742807 -440.267421)
			(xy 41.730681 -440.212984) (xy 41.72661 -440.157362) (xy 29.40431 -440.157362) (xy 29.40431 -440.75096)
			(xy 39.288464 -440.75096) (xy 39.292535 -440.695338) (xy 39.304661 -440.640901) (xy 39.324584 -440.58881)
			(xy 39.35188 -440.540175) (xy 39.385966 -440.496032) (xy 39.426115 -440.457323) (xy 39.471473 -440.424872)
			(xy 39.521073 -440.399371) (xy 39.573857 -440.381364) (xy 39.6287 -440.371234) (xy 39.684434 -440.369197)
			(xy 39.739871 -440.375297) (xy 39.793828 -440.389403) (xy 39.845157 -440.411215) (xy 39.892763 -440.440269)
			(xy 39.935631 -440.475944) (xy 39.972848 -440.517481) (xy 40.003621 -440.563994) (xy 40.027293 -440.614491)
			(xy 40.043361 -440.667898) (xy 40.051481 -440.723074) (xy 40.05199 -440.75096) (xy 40.051481 -440.778846)
			(xy 40.043361 -440.834022) (xy 40.027293 -440.887429) (xy 40.003621 -440.937926) (xy 39.991032 -440.956954)
			(xy 43.660058 -440.956954) (xy 43.664129 -440.901332) (xy 43.676255 -440.846895) (xy 43.696178 -440.794804)
			(xy 43.723474 -440.746169) (xy 43.75756 -440.702026) (xy 43.797709 -440.663317) (xy 43.843067 -440.630866)
			(xy 43.892667 -440.605365) (xy 43.945451 -440.587358) (xy 44.000294 -440.577228) (xy 44.056028 -440.575191)
			(xy 44.111465 -440.581291) (xy 44.165422 -440.595397) (xy 44.216751 -440.617209) (xy 44.264357 -440.646263)
			(xy 44.307225 -440.681938) (xy 44.344442 -440.723475) (xy 44.375215 -440.769988) (xy 44.398887 -440.820485)
			(xy 44.414955 -440.873892) (xy 44.423075 -440.929068) (xy 44.423584 -440.956954) (xy 44.423075 -440.98484)
			(xy 44.414955 -441.040016) (xy 44.398887 -441.093423) (xy 44.375215 -441.14392) (xy 44.344442 -441.190433)
			(xy 44.307225 -441.23197) (xy 44.264357 -441.267645) (xy 44.216751 -441.296699) (xy 44.165422 -441.318511)
			(xy 44.111465 -441.332617) (xy 44.056028 -441.338717) (xy 44.000294 -441.33668) (xy 43.945451 -441.32655)
			(xy 43.892667 -441.308543) (xy 43.843067 -441.283042) (xy 43.797709 -441.250591) (xy 43.75756 -441.211882)
			(xy 43.723474 -441.167739) (xy 43.696178 -441.119104) (xy 43.676255 -441.067013) (xy 43.664129 -441.012576)
			(xy 43.660058 -440.956954) (xy 39.991032 -440.956954) (xy 39.972848 -440.984439) (xy 39.935631 -441.025976)
			(xy 39.892763 -441.061651) (xy 39.845157 -441.090705) (xy 39.793828 -441.112517) (xy 39.739871 -441.126623)
			(xy 39.684434 -441.132723) (xy 39.6287 -441.130686) (xy 39.573857 -441.120556) (xy 39.521073 -441.102549)
			(xy 39.471473 -441.077048) (xy 39.426115 -441.044597) (xy 39.385966 -441.005888) (xy 39.35188 -440.961745)
			(xy 39.324584 -440.91311) (xy 39.304661 -440.861019) (xy 39.292535 -440.806582) (xy 39.288464 -440.75096)
			(xy 29.40431 -440.75096) (xy 29.40431 -441.09259) (xy 29.4005 -441.0964) (xy 29.4005 -441.200286)
			(xy 37.796468 -441.200286) (xy 37.800539 -441.144664) (xy 37.812665 -441.090227) (xy 37.832588 -441.038136)
			(xy 37.859884 -440.989501) (xy 37.89397 -440.945358) (xy 37.934119 -440.906649) (xy 37.979477 -440.874198)
			(xy 38.029077 -440.848697) (xy 38.081861 -440.83069) (xy 38.136704 -440.82056) (xy 38.192438 -440.818523)
			(xy 38.247875 -440.824623) (xy 38.301832 -440.838729) (xy 38.353161 -440.860541) (xy 38.400767 -440.889595)
			(xy 38.443635 -440.92527) (xy 38.480852 -440.966807) (xy 38.511625 -441.01332) (xy 38.535297 -441.063817)
			(xy 38.551365 -441.117224) (xy 38.559485 -441.1724) (xy 38.559994 -441.200286) (xy 38.559485 -441.228172)
			(xy 38.551365 -441.283348) (xy 38.535297 -441.336755) (xy 38.526638 -441.355226) (xy 41.08526 -441.355226)
			(xy 41.089331 -441.299604) (xy 41.101457 -441.245167) (xy 41.12138 -441.193076) (xy 41.148676 -441.144441)
			(xy 41.182762 -441.100298) (xy 41.222911 -441.061589) (xy 41.268269 -441.029138) (xy 41.317869 -441.003637)
			(xy 41.370653 -440.98563) (xy 41.425496 -440.9755) (xy 41.48123 -440.973463) (xy 41.536667 -440.979563)
			(xy 41.590624 -440.993669) (xy 41.641953 -441.015481) (xy 41.689559 -441.044535) (xy 41.732427 -441.08021)
			(xy 41.769644 -441.121747) (xy 41.800417 -441.16826) (xy 41.824089 -441.218757) (xy 41.840157 -441.272164)
			(xy 41.848277 -441.32734) (xy 41.848786 -441.355226) (xy 41.848277 -441.383112) (xy 41.840157 -441.438288)
			(xy 41.824089 -441.491695) (xy 41.800417 -441.542192) (xy 41.769644 -441.588705) (xy 41.732427 -441.630242)
			(xy 41.689559 -441.665917) (xy 41.641953 -441.694971) (xy 41.590624 -441.716783) (xy 41.536667 -441.730889)
			(xy 41.48123 -441.736989) (xy 41.425496 -441.734952) (xy 41.370653 -441.724822) (xy 41.317869 -441.706815)
			(xy 41.268269 -441.681314) (xy 41.222911 -441.648863) (xy 41.182762 -441.610154) (xy 41.148676 -441.566011)
			(xy 41.12138 -441.517376) (xy 41.101457 -441.465285) (xy 41.089331 -441.410848) (xy 41.08526 -441.355226)
			(xy 38.526638 -441.355226) (xy 38.511625 -441.387252) (xy 38.480852 -441.433765) (xy 38.443635 -441.475302)
			(xy 38.400767 -441.510977) (xy 38.353161 -441.540031) (xy 38.301832 -441.561843) (xy 38.247875 -441.575949)
			(xy 38.192438 -441.582049) (xy 38.136704 -441.580012) (xy 38.081861 -441.569882) (xy 38.029077 -441.551875)
			(xy 37.979477 -441.526374) (xy 37.934119 -441.493923) (xy 37.89397 -441.455214) (xy 37.859884 -441.411071)
			(xy 37.832588 -441.362436) (xy 37.812665 -441.310345) (xy 37.800539 -441.255908) (xy 37.796468 -441.200286)
			(xy 29.4005 -441.200286) (xy 29.4005 -441.201048) (xy 29.870146 -441.670694) (xy 36.416994 -441.670694)
			(xy 36.421065 -441.615072) (xy 36.433191 -441.560635) (xy 36.453114 -441.508544) (xy 36.48041 -441.459909)
			(xy 36.514496 -441.415766) (xy 36.554645 -441.377057) (xy 36.600003 -441.344606) (xy 36.649603 -441.319105)
			(xy 36.702387 -441.301098) (xy 36.75723 -441.290968) (xy 36.812964 -441.288931) (xy 36.868401 -441.295031)
			(xy 36.922358 -441.309137) (xy 36.973687 -441.330949) (xy 37.021293 -441.360003) (xy 37.064161 -441.395678)
			(xy 37.101378 -441.437215) (xy 37.132151 -441.483728) (xy 37.155823 -441.534225) (xy 37.171891 -441.587632)
			(xy 37.180011 -441.642808) (xy 37.18052 -441.670694) (xy 37.180011 -441.69858) (xy 37.171891 -441.753756)
			(xy 37.170364 -441.758832) (xy 42.328336 -441.758832) (xy 42.332407 -441.70321) (xy 42.344533 -441.648773)
			(xy 42.364456 -441.596682) (xy 42.391752 -441.548047) (xy 42.425838 -441.503904) (xy 42.465987 -441.465195)
			(xy 42.511345 -441.432744) (xy 42.560945 -441.407243) (xy 42.613729 -441.389236) (xy 42.668572 -441.379106)
			(xy 42.724306 -441.377069) (xy 42.779743 -441.383169) (xy 42.8337 -441.397275) (xy 42.885029 -441.419087)
			(xy 42.932635 -441.448141) (xy 42.975503 -441.483816) (xy 43.01272 -441.525353) (xy 43.043493 -441.571866)
			(xy 43.067165 -441.622363) (xy 43.083233 -441.67577) (xy 43.091353 -441.730946) (xy 43.091862 -441.758832)
			(xy 43.091353 -441.786718) (xy 43.083233 -441.841894) (xy 43.067165 -441.895301) (xy 43.043493 -441.945798)
			(xy 43.01272 -441.992311) (xy 42.975503 -442.033848) (xy 42.932635 -442.069523) (xy 42.885029 -442.098577)
			(xy 42.8337 -442.120389) (xy 42.779743 -442.134495) (xy 42.724306 -442.140595) (xy 42.668572 -442.138558)
			(xy 42.613729 -442.128428) (xy 42.560945 -442.110421) (xy 42.511345 -442.08492) (xy 42.465987 -442.052469)
			(xy 42.425838 -442.01376) (xy 42.391752 -441.969617) (xy 42.364456 -441.920982) (xy 42.344533 -441.868891)
			(xy 42.332407 -441.814454) (xy 42.328336 -441.758832) (xy 37.170364 -441.758832) (xy 37.155823 -441.807163)
			(xy 37.132151 -441.85766) (xy 37.101378 -441.904173) (xy 37.064161 -441.94571) (xy 37.021293 -441.981385)
			(xy 36.973687 -442.010439) (xy 36.922358 -442.032251) (xy 36.868401 -442.046357) (xy 36.812964 -442.052457)
			(xy 36.75723 -442.05042) (xy 36.702387 -442.04029) (xy 36.649603 -442.022283) (xy 36.600003 -441.996782)
			(xy 36.554645 -441.964331) (xy 36.514496 -441.925622) (xy 36.48041 -441.881479) (xy 36.453114 -441.832844)
			(xy 36.433191 -441.780753) (xy 36.421065 -441.726316) (xy 36.416994 -441.670694) (xy 29.870146 -441.670694)
			(xy 30.645862 -442.44641) (xy 69.266308 -442.44641) (xy 69.266308 -441.501784) (xy 69.26681 -441.469823)
			(xy 69.274821 -441.406405) (xy 69.290718 -441.344491) (xy 69.31425 -441.285058) (xy 69.345044 -441.229043)
			(xy 69.382617 -441.177328) (xy 69.426374 -441.130731) (xy 69.475627 -441.089986) (xy 69.529598 -441.055735)
			(xy 69.587437 -441.028518) (xy 69.64823 -441.008765) (xy 69.71102 -440.996787) (xy 69.774816 -440.992774)
			(xy 69.838612 -440.996787) (xy 69.901402 -441.008765) (xy 69.962195 -441.028518) (xy 70.020034 -441.055735)
			(xy 70.074005 -441.089986) (xy 70.123258 -441.130731) (xy 70.167015 -441.177328) (xy 70.204588 -441.229043)
			(xy 70.235382 -441.285058) (xy 70.258914 -441.344491) (xy 70.274811 -441.406405) (xy 70.282822 -441.469823)
			(xy 70.283324 -441.501784) (xy 70.283324 -441.57011) (xy 70.357492 -441.644278) (xy 70.410324 -441.644278)
			(xy 70.426351 -441.643722) (xy 70.45739 -441.635725) (xy 70.485455 -441.62024) (xy 70.508773 -441.598247)
			(xy 70.525871 -441.571135) (xy 70.535668 -441.540616) (xy 70.53707 -441.524644) (xy 70.53707 -441.52439)
			(xy 70.53936 -441.492975) (xy 70.550648 -441.431007) (xy 70.569507 -441.370908) (xy 70.595648 -441.3136)
			(xy 70.628669 -441.259961) (xy 70.668064 -441.210814) (xy 70.713231 -441.16691) (xy 70.763476 -441.128925)
			(xy 70.81803 -441.097438) (xy 70.876056 -441.072934) (xy 70.936666 -441.055787) (xy 70.998929 -441.046261)
			(xy 71.061893 -441.044501) (xy 71.124591 -441.050534) (xy 71.186064 -441.064269) (xy 71.245369 -441.085493)
			(xy 71.301596 -441.113883) (xy 71.353885 -441.149003) (xy 71.401433 -441.190315) (xy 71.443513 -441.237185)
			(xy 71.461884 -441.26277) (xy 71.474809 -441.280501) (xy 71.505678 -441.311676) (xy 71.541444 -441.337086)
			(xy 71.581042 -441.355975) (xy 71.623295 -441.367782) (xy 71.666949 -441.372156) (xy 71.710706 -441.368967)
			(xy 71.753264 -441.35831) (xy 71.79336 -441.340502) (xy 71.829801 -441.316071) (xy 71.861504 -441.285744)
			(xy 71.874888 -441.268358) (xy 71.893629 -441.243631) (xy 71.93627 -441.198554) (xy 71.984079 -441.159002)
			(xy 72.036345 -441.125561) (xy 72.092293 -441.098729) (xy 72.151089 -441.078904) (xy 72.211862 -441.066382)
			(xy 72.273706 -441.061348) (xy 72.335703 -441.063877) (xy 72.396932 -441.073931) (xy 72.456483 -441.091362)
			(xy 72.51347 -441.115909) (xy 72.567046 -441.147209) (xy 72.616415 -441.184795) (xy 72.660844 -441.22811)
			(xy 72.699671 -441.27651) (xy 72.71639 -441.302648) (xy 72.728491 -441.321296) (xy 72.758099 -441.35445)
			(xy 72.793022 -441.381947) (xy 72.832198 -441.402949) (xy 72.87443 -441.416815) (xy 72.91843 -441.423121)
			(xy 72.962856 -441.421676) (xy 73.006354 -441.412523) (xy 73.047595 -441.395942) (xy 73.085323 -441.372439)
			(xy 73.118386 -441.34273) (xy 73.132442 -441.325508) (xy 73.152167 -441.300951) (xy 73.196816 -441.256519)
			(xy 73.246614 -441.217945) (xy 73.300797 -441.185819) (xy 73.358534 -441.160635) (xy 73.41894 -441.142778)
			(xy 73.48109 -441.132522) (xy 73.54403 -441.130024) (xy 73.606798 -441.135322) (xy 73.668429 -441.148335)
			(xy 73.72798 -441.168864) (xy 73.784539 -441.196594) (xy 73.837237 -441.231101) (xy 73.885268 -441.271854)
			(xy 73.927895 -441.31823) (xy 73.964465 -441.369518) (xy 73.994417 -441.424931) (xy 74.017293 -441.483621)
			(xy 74.032742 -441.544687) (xy 74.040526 -441.607195) (xy 74.041 -441.63869) (xy 74.041 -442.44641)
			(xy 74.040511 -442.479137) (xy 74.032115 -442.544049) (xy 74.015462 -442.607349) (xy 73.990828 -442.66799)
			(xy 73.95862 -442.724971) (xy 73.9394 -442.751464) (xy 73.914 -442.785246) (xy 73.914 -442.802264)
			(xy 73.89876 -442.802264) (xy 73.862946 -442.832744) (xy 73.837769 -442.853597) (xy 73.783037 -442.889348)
			(xy 73.724172 -442.917787) (xy 73.662147 -442.938442) (xy 73.597985 -442.950973) (xy 73.532746 -442.955173)
			(xy 73.467507 -442.950973) (xy 73.403345 -442.938442) (xy 73.34132 -442.917787) (xy 73.282455 -442.889348)
			(xy 73.227723 -442.853597) (xy 73.202546 -442.832744) (xy 73.166732 -442.802264) (xy 73.151492 -442.802264)
			(xy 73.151492 -442.785246) (xy 73.126092 -442.751464) (xy 73.11644 -442.738256) (xy 73.103319 -442.720376)
			(xy 73.071952 -442.68903) (xy 73.035619 -442.663605) (xy 72.995426 -442.644872) (xy 72.95259 -442.6334)
			(xy 72.908414 -442.629537) (xy 72.864238 -442.6334) (xy 72.821402 -442.644872) (xy 72.781209 -442.663605)
			(xy 72.744876 -442.68903) (xy 72.713509 -442.720376) (xy 72.700388 -442.738256) (xy 72.690736 -442.751464)
			(xy 72.665336 -442.785246) (xy 72.665336 -442.802264) (xy 72.650096 -442.802264) (xy 72.614282 -442.832744)
			(xy 72.589105 -442.853597) (xy 72.534373 -442.889348) (xy 72.475508 -442.917787) (xy 72.413483 -442.938442)
			(xy 72.349321 -442.950973) (xy 72.284082 -442.955173) (xy 72.218843 -442.950973) (xy 72.154681 -442.938442)
			(xy 72.092656 -442.917787) (xy 72.033791 -442.889348) (xy 71.979059 -442.853597) (xy 71.953882 -442.832744)
			(xy 71.918068 -442.802264) (xy 71.902828 -442.802264) (xy 71.902828 -442.785246) (xy 71.877428 -442.751464)
			(xy 71.870824 -442.742574) (xy 71.857679 -442.725006) (xy 71.826393 -442.69425) (xy 71.790289 -442.669325)
			(xy 71.75044 -442.650973) (xy 71.708031 -442.639738) (xy 71.664322 -442.635956) (xy 71.620613 -442.639738)
			(xy 71.578204 -442.650973) (xy 71.538355 -442.669325) (xy 71.502251 -442.69425) (xy 71.470965 -442.725006)
			(xy 71.45782 -442.742574) (xy 71.451216 -442.751464) (xy 71.425816 -442.785246) (xy 71.425816 -442.802264)
			(xy 71.410576 -442.802264) (xy 71.374762 -442.832744) (xy 71.349585 -442.853597) (xy 71.294853 -442.889348)
			(xy 71.235988 -442.917787) (xy 71.173963 -442.938442) (xy 71.109801 -442.950973) (xy 71.044562 -442.955173)
			(xy 70.979323 -442.950973) (xy 70.915161 -442.938442) (xy 70.853136 -442.917787) (xy 70.794271 -442.889348)
			(xy 70.739539 -442.853597) (xy 70.714362 -442.832744) (xy 70.678548 -442.802264) (xy 70.663308 -442.802264)
			(xy 70.663308 -442.785246) (xy 70.637908 -442.751464) (xy 70.621144 -442.727842) (xy 70.608143 -442.709185)
			(xy 70.576642 -442.676397) (xy 70.539807 -442.649741) (xy 70.498815 -442.630068) (xy 70.454975 -442.618007)
			(xy 70.409689 -442.613943) (xy 70.364403 -442.618007) (xy 70.320563 -442.630068) (xy 70.279571 -442.649741)
			(xy 70.242736 -442.676397) (xy 70.211235 -442.709185) (xy 70.198234 -442.727842) (xy 70.18147 -442.751464)
			(xy 70.156324 -442.785246) (xy 70.156324 -442.802264) (xy 70.14083 -442.802264) (xy 70.105016 -442.832744)
			(xy 70.079839 -442.853597) (xy 70.025107 -442.889348) (xy 69.966242 -442.917787) (xy 69.904217 -442.938442)
			(xy 69.840055 -442.950973) (xy 69.774816 -442.955173) (xy 69.709577 -442.950973) (xy 69.645415 -442.938442)
			(xy 69.58339 -442.917787) (xy 69.524525 -442.889348) (xy 69.469793 -442.853597) (xy 69.444616 -442.832744)
			(xy 69.408802 -442.802264) (xy 69.393308 -442.802264) (xy 69.393308 -442.785246) (xy 69.368162 -442.751464)
			(xy 69.348897 -442.724993) (xy 69.316636 -442.668021) (xy 69.291954 -442.60738) (xy 69.27526 -442.544072)
			(xy 69.26683 -442.479146) (xy 69.266308 -442.44641) (xy 30.645862 -442.44641) (xy 31.79826 -443.598808)
			(xy 31.79826 -445.388746) (xy 78.748888 -445.388746) (xy 78.752959 -445.333124) (xy 78.765085 -445.278687)
			(xy 78.785008 -445.226596) (xy 78.812304 -445.177961) (xy 78.84639 -445.133818) (xy 78.886539 -445.095109)
			(xy 78.931897 -445.062658) (xy 78.981497 -445.037157) (xy 79.034281 -445.01915) (xy 79.089124 -445.00902)
			(xy 79.144858 -445.006983) (xy 79.200295 -445.013083) (xy 79.254252 -445.027189) (xy 79.305581 -445.049001)
			(xy 79.353187 -445.078055) (xy 79.396055 -445.11373) (xy 79.433272 -445.155267) (xy 79.464045 -445.20178)
			(xy 79.487717 -445.252277) (xy 79.503785 -445.305684) (xy 79.511905 -445.36086) (xy 79.512261 -445.380364)
			(xy 81.223864 -445.380364) (xy 81.227935 -445.324742) (xy 81.240061 -445.270305) (xy 81.259984 -445.218214)
			(xy 81.28728 -445.169579) (xy 81.321366 -445.125436) (xy 81.361515 -445.086727) (xy 81.406873 -445.054276)
			(xy 81.456473 -445.028775) (xy 81.509257 -445.010768) (xy 81.5641 -445.000638) (xy 81.619834 -444.998601)
			(xy 81.675271 -445.004701) (xy 81.729228 -445.018807) (xy 81.752212 -445.028574) (xy 83.40928 -445.028574)
			(xy 83.413351 -444.972952) (xy 83.425477 -444.918515) (xy 83.4454 -444.866424) (xy 83.472696 -444.817789)
			(xy 83.506782 -444.773646) (xy 83.546931 -444.734937) (xy 83.592289 -444.702486) (xy 83.641889 -444.676985)
			(xy 83.694673 -444.658978) (xy 83.749516 -444.648848) (xy 83.80525 -444.646811) (xy 83.860687 -444.652911)
			(xy 83.914644 -444.667017) (xy 83.965973 -444.688829) (xy 84.013579 -444.717883) (xy 84.056447 -444.753558)
			(xy 84.093664 -444.795095) (xy 84.124437 -444.841608) (xy 84.148109 -444.892105) (xy 84.164177 -444.945512)
			(xy 84.172297 -445.000688) (xy 84.172806 -445.028574) (xy 84.172297 -445.05646) (xy 84.164177 -445.111636)
			(xy 84.148109 -445.165043) (xy 84.124437 -445.21554) (xy 84.093664 -445.262053) (xy 84.056447 -445.30359)
			(xy 84.024015 -445.33058) (xy 84.893402 -445.33058) (xy 84.897473 -445.274958) (xy 84.909599 -445.220521)
			(xy 84.929522 -445.16843) (xy 84.956818 -445.119795) (xy 84.990904 -445.075652) (xy 85.031053 -445.036943)
			(xy 85.076411 -445.004492) (xy 85.126011 -444.978991) (xy 85.178795 -444.960984) (xy 85.233638 -444.950854)
			(xy 85.289372 -444.948817) (xy 85.344809 -444.954917) (xy 85.398766 -444.969023) (xy 85.450095 -444.990835)
			(xy 85.497701 -445.019889) (xy 85.540569 -445.055564) (xy 85.577786 -445.097101) (xy 85.608559 -445.143614)
			(xy 85.632231 -445.194111) (xy 85.648299 -445.247518) (xy 85.656419 -445.302694) (xy 85.656928 -445.33058)
			(xy 85.656419 -445.358466) (xy 85.648299 -445.413642) (xy 85.632231 -445.467049) (xy 85.608559 -445.517546)
			(xy 85.577786 -445.564059) (xy 85.540569 -445.605596) (xy 85.497701 -445.641271) (xy 85.450095 -445.670325)
			(xy 85.398766 -445.692137) (xy 85.344809 -445.706243) (xy 85.289372 -445.712343) (xy 85.233638 -445.710306)
			(xy 85.178795 -445.700176) (xy 85.126011 -445.682169) (xy 85.076411 -445.656668) (xy 85.031053 -445.624217)
			(xy 84.990904 -445.585508) (xy 84.956818 -445.541365) (xy 84.929522 -445.49273) (xy 84.909599 -445.440639)
			(xy 84.897473 -445.386202) (xy 84.893402 -445.33058) (xy 84.024015 -445.33058) (xy 84.013579 -445.339265)
			(xy 83.965973 -445.368319) (xy 83.914644 -445.390131) (xy 83.860687 -445.404237) (xy 83.80525 -445.410337)
			(xy 83.749516 -445.4083) (xy 83.694673 -445.39817) (xy 83.641889 -445.380163) (xy 83.592289 -445.354662)
			(xy 83.546931 -445.322211) (xy 83.506782 -445.283502) (xy 83.472696 -445.239359) (xy 83.4454 -445.190724)
			(xy 83.425477 -445.138633) (xy 83.413351 -445.084196) (xy 83.40928 -445.028574) (xy 81.752212 -445.028574)
			(xy 81.780557 -445.040619) (xy 81.828163 -445.069673) (xy 81.871031 -445.105348) (xy 81.908248 -445.146885)
			(xy 81.939021 -445.193398) (xy 81.962693 -445.243895) (xy 81.978761 -445.297302) (xy 81.986881 -445.352478)
			(xy 81.98739 -445.380364) (xy 81.986881 -445.40825) (xy 81.978761 -445.463426) (xy 81.962693 -445.516833)
			(xy 81.939021 -445.56733) (xy 81.908248 -445.613843) (xy 81.871031 -445.65538) (xy 81.828163 -445.691055)
			(xy 81.780557 -445.720109) (xy 81.729228 -445.741921) (xy 81.675271 -445.756027) (xy 81.619834 -445.762127)
			(xy 81.5641 -445.76009) (xy 81.509257 -445.74996) (xy 81.456473 -445.731953) (xy 81.406873 -445.706452)
			(xy 81.361515 -445.674001) (xy 81.321366 -445.635292) (xy 81.28728 -445.591149) (xy 81.259984 -445.542514)
			(xy 81.240061 -445.490423) (xy 81.227935 -445.435986) (xy 81.223864 -445.380364) (xy 79.512261 -445.380364)
			(xy 79.512414 -445.388746) (xy 79.511905 -445.416632) (xy 79.503785 -445.471808) (xy 79.487717 -445.525215)
			(xy 79.464045 -445.575712) (xy 79.433272 -445.622225) (xy 79.396055 -445.663762) (xy 79.353187 -445.699437)
			(xy 79.305581 -445.728491) (xy 79.254252 -445.750303) (xy 79.200295 -445.764409) (xy 79.144858 -445.770509)
			(xy 79.089124 -445.768472) (xy 79.034281 -445.758342) (xy 78.981497 -445.740335) (xy 78.931897 -445.714834)
			(xy 78.886539 -445.682383) (xy 78.84639 -445.643674) (xy 78.812304 -445.599531) (xy 78.785008 -445.550896)
			(xy 78.765085 -445.498805) (xy 78.752959 -445.444368) (xy 78.748888 -445.388746) (xy 31.79826 -445.388746)
			(xy 31.79826 -446.633362) (xy 34.599874 -446.633362) (xy 34.599874 -446.546462) (xy 34.607892 -446.459933)
			(xy 34.62386 -446.374513) (xy 34.647641 -446.290931) (xy 34.679033 -446.209899) (xy 34.717767 -446.13211)
			(xy 34.763514 -446.058226) (xy 34.815883 -445.988879) (xy 34.874427 -445.924659) (xy 34.938647 -445.866115)
			(xy 35.007994 -445.813746) (xy 35.081878 -445.767999) (xy 35.159667 -445.729265) (xy 35.240699 -445.697873)
			(xy 35.324281 -445.674092) (xy 35.409701 -445.658124) (xy 35.49623 -445.650106) (xy 35.58313 -445.650106)
			(xy 35.669659 -445.658124) (xy 35.755079 -445.674092) (xy 35.838661 -445.697873) (xy 35.919693 -445.729265)
			(xy 35.997482 -445.767999) (xy 36.071366 -445.813746) (xy 36.140713 -445.866115) (xy 36.204933 -445.924659)
			(xy 36.263477 -445.988879) (xy 36.315846 -446.058226) (xy 36.361593 -446.13211) (xy 36.400327 -446.209899)
			(xy 36.431719 -446.290931) (xy 36.4555 -446.374513) (xy 36.471468 -446.459933) (xy 36.479486 -446.546462)
			(xy 36.479988 -446.589912) (xy 36.479486 -446.633362) (xy 36.471468 -446.719891) (xy 36.4555 -446.805311)
			(xy 36.431719 -446.888893) (xy 36.400327 -446.969925) (xy 36.361593 -447.047714) (xy 36.315846 -447.121598)
			(xy 36.263477 -447.190945) (xy 36.204933 -447.255165) (xy 36.140713 -447.313709) (xy 36.071366 -447.366078)
			(xy 35.997482 -447.411825) (xy 35.919693 -447.450559) (xy 35.838661 -447.481951) (xy 35.755079 -447.505732)
			(xy 35.669659 -447.5217) (xy 35.58313 -447.529718) (xy 35.49623 -447.529718) (xy 35.409701 -447.5217)
			(xy 35.324281 -447.505732) (xy 35.240699 -447.481951) (xy 35.159667 -447.450559) (xy 35.081878 -447.411825)
			(xy 35.007994 -447.366078) (xy 34.938647 -447.313709) (xy 34.874427 -447.255165) (xy 34.815883 -447.190945)
			(xy 34.763514 -447.121598) (xy 34.717767 -447.047714) (xy 34.679033 -446.969925) (xy 34.647641 -446.888893)
			(xy 34.62386 -446.805311) (xy 34.607892 -446.719891) (xy 34.599874 -446.633362) (xy 31.79826 -446.633362)
			(xy 31.79826 -449.173362) (xy 34.599874 -449.173362) (xy 34.599874 -449.086462) (xy 34.607892 -448.999933)
			(xy 34.62386 -448.914513) (xy 34.647641 -448.830931) (xy 34.679033 -448.749899) (xy 34.717767 -448.67211)
			(xy 34.763514 -448.598226) (xy 34.815883 -448.528879) (xy 34.874427 -448.464659) (xy 34.938647 -448.406115)
			(xy 35.007994 -448.353746) (xy 35.081878 -448.307999) (xy 35.159667 -448.269265) (xy 35.240699 -448.237873)
			(xy 35.324281 -448.214092) (xy 35.409701 -448.198124) (xy 35.49623 -448.190106) (xy 35.58313 -448.190106)
			(xy 35.669659 -448.198124) (xy 35.755079 -448.214092) (xy 35.838661 -448.237873) (xy 35.919693 -448.269265)
			(xy 35.997482 -448.307999) (xy 36.071366 -448.353746) (xy 36.140713 -448.406115) (xy 36.204933 -448.464659)
			(xy 36.263477 -448.528879) (xy 36.315846 -448.598226) (xy 36.361593 -448.67211) (xy 36.400327 -448.749899)
			(xy 36.431719 -448.830931) (xy 36.4555 -448.914513) (xy 36.471468 -448.999933) (xy 36.479486 -449.086462)
			(xy 36.479988 -449.129912) (xy 36.479486 -449.173362) (xy 36.471468 -449.259891) (xy 36.4555 -449.345311)
			(xy 36.431719 -449.428893) (xy 36.400327 -449.509925) (xy 36.361593 -449.587714) (xy 36.315846 -449.661598)
			(xy 36.263477 -449.730945) (xy 36.204933 -449.795165) (xy 36.140713 -449.853709) (xy 36.071366 -449.906078)
			(xy 35.997482 -449.951825) (xy 35.919693 -449.990559) (xy 35.838661 -450.021951) (xy 35.755079 -450.045732)
			(xy 35.669659 -450.0617) (xy 35.58313 -450.069718) (xy 35.49623 -450.069718) (xy 35.409701 -450.0617)
			(xy 35.324281 -450.045732) (xy 35.240699 -450.021951) (xy 35.159667 -449.990559) (xy 35.081878 -449.951825)
			(xy 35.007994 -449.906078) (xy 34.938647 -449.853709) (xy 34.874427 -449.795165) (xy 34.815883 -449.730945)
			(xy 34.763514 -449.661598) (xy 34.717767 -449.587714) (xy 34.679033 -449.509925) (xy 34.647641 -449.428893)
			(xy 34.62386 -449.345311) (xy 34.607892 -449.259891) (xy 34.599874 -449.173362) (xy 31.79826 -449.173362)
			(xy 31.79826 -451.713362) (xy 34.599874 -451.713362) (xy 34.599874 -451.626462) (xy 34.607892 -451.539933)
			(xy 34.62386 -451.454513) (xy 34.647641 -451.370931) (xy 34.679033 -451.289899) (xy 34.717767 -451.21211)
			(xy 34.763514 -451.138226) (xy 34.815883 -451.068879) (xy 34.874427 -451.004659) (xy 34.938647 -450.946115)
			(xy 35.007994 -450.893746) (xy 35.081878 -450.847999) (xy 35.159667 -450.809265) (xy 35.240699 -450.777873)
			(xy 35.324281 -450.754092) (xy 35.409701 -450.738124) (xy 35.49623 -450.730106) (xy 35.58313 -450.730106)
			(xy 35.669659 -450.738124) (xy 35.755079 -450.754092) (xy 35.838661 -450.777873) (xy 35.919693 -450.809265)
			(xy 35.997482 -450.847999) (xy 36.071366 -450.893746) (xy 36.140713 -450.946115) (xy 36.204933 -451.004659)
			(xy 36.263477 -451.068879) (xy 36.315846 -451.138226) (xy 36.361593 -451.21211) (xy 36.400327 -451.289899)
			(xy 36.431719 -451.370931) (xy 36.442855 -451.41007) (xy 39.818063 -451.41007) (xy 39.82207 -451.294046)
			(xy 39.834072 -451.178574) (xy 39.854012 -451.064206) (xy 39.881795 -450.951486) (xy 39.917289 -450.840952)
			(xy 39.960324 -450.733129) (xy 40.010695 -450.628532) (xy 40.068162 -450.52766) (xy 40.132452 -450.430993)
			(xy 40.203257 -450.338992) (xy 40.280241 -450.252095) (xy 40.363037 -450.170716) (xy 40.45125 -450.095243)
			(xy 40.54446 -450.026036) (xy 40.642223 -449.963424) (xy 40.744072 -449.907707) (xy 40.849522 -449.859149)
			(xy 40.958071 -449.817981) (xy 41.069202 -449.784401) (xy 41.182385 -449.758568) (xy 41.29708 -449.740605)
			(xy 41.412742 -449.730597) (xy 41.528818 -449.728594) (xy 41.644756 -449.734603) (xy 41.760003 -449.748596)
			(xy 41.874009 -449.770507) (xy 41.986233 -449.800232) (xy 42.096139 -449.837628) (xy 42.203202 -449.882517)
			(xy 42.306914 -449.934686) (xy 42.406779 -449.993886) (xy 42.502322 -450.059835) (xy 42.502604 -450.06006)
			(xy 43.327577 -450.06006) (xy 43.331612 -449.984356) (xy 43.343671 -449.909511) (xy 43.363617 -449.83637)
			(xy 43.391224 -449.765765) (xy 43.42618 -449.698494) (xy 43.468088 -449.635319) (xy 43.516474 -449.576957)
			(xy 43.57079 -449.524069) (xy 43.630419 -449.477254) (xy 43.694687 -449.437042) (xy 43.762864 -449.40389)
			(xy 43.83418 -449.378172) (xy 43.907825 -449.36018) (xy 43.982965 -449.350118) (xy 44.058749 -449.348099)
			(xy 44.134319 -449.354148) (xy 44.208817 -449.368195) (xy 44.2814 -449.390081) (xy 44.351246 -449.419558)
			(xy 44.417563 -449.456293) (xy 44.479599 -449.499868) (xy 44.536652 -449.54979) (xy 44.588076 -449.605494)
			(xy 44.633287 -449.666349) (xy 44.671774 -449.731664) (xy 44.7031 -449.8007) (xy 44.72691 -449.872675)
			(xy 44.742935 -449.946773) (xy 44.750994 -450.022154) (xy 44.751498 -450.06006) (xy 45.867577 -450.06006)
			(xy 45.871612 -449.984356) (xy 45.883671 -449.909511) (xy 45.903617 -449.83637) (xy 45.931224 -449.765765)
			(xy 45.96618 -449.698494) (xy 46.008088 -449.635319) (xy 46.056474 -449.576957) (xy 46.11079 -449.524069)
			(xy 46.170419 -449.477254) (xy 46.234687 -449.437042) (xy 46.302864 -449.40389) (xy 46.37418 -449.378172)
			(xy 46.447825 -449.36018) (xy 46.522965 -449.350118) (xy 46.598749 -449.348099) (xy 46.674319 -449.354148)
			(xy 46.748817 -449.368195) (xy 46.8214 -449.390081) (xy 46.891246 -449.419558) (xy 46.957563 -449.456293)
			(xy 47.019599 -449.499868) (xy 47.076652 -449.54979) (xy 47.128076 -449.605494) (xy 47.173287 -449.666349)
			(xy 47.211774 -449.731664) (xy 47.2431 -449.8007) (xy 47.26691 -449.872675) (xy 47.282935 -449.946773)
			(xy 47.290994 -450.022154) (xy 47.291498 -450.06006) (xy 48.407577 -450.06006) (xy 48.411612 -449.984356)
			(xy 48.423671 -449.909511) (xy 48.443617 -449.83637) (xy 48.471224 -449.765765) (xy 48.50618 -449.698494)
			(xy 48.548088 -449.635319) (xy 48.596474 -449.576957) (xy 48.65079 -449.524069) (xy 48.710419 -449.477254)
			(xy 48.774687 -449.437042) (xy 48.842864 -449.40389) (xy 48.91418 -449.378172) (xy 48.987825 -449.36018)
			(xy 49.062965 -449.350118) (xy 49.138749 -449.348099) (xy 49.214319 -449.354148) (xy 49.288817 -449.368195)
			(xy 49.3614 -449.390081) (xy 49.431246 -449.419558) (xy 49.497563 -449.456293) (xy 49.559599 -449.499868)
			(xy 49.616652 -449.54979) (xy 49.668076 -449.605494) (xy 49.713287 -449.666349) (xy 49.751774 -449.731664)
			(xy 49.7831 -449.8007) (xy 49.80691 -449.872675) (xy 49.822935 -449.946773) (xy 49.830994 -450.022154)
			(xy 49.831498 -450.06006) (xy 50.947577 -450.06006) (xy 50.951612 -449.984356) (xy 50.963671 -449.909511)
			(xy 50.983617 -449.83637) (xy 51.011224 -449.765765) (xy 51.04618 -449.698494) (xy 51.088088 -449.635319)
			(xy 51.136474 -449.576957) (xy 51.19079 -449.524069) (xy 51.250419 -449.477254) (xy 51.314687 -449.437042)
			(xy 51.382864 -449.40389) (xy 51.45418 -449.378172) (xy 51.527825 -449.36018) (xy 51.602965 -449.350118)
			(xy 51.678749 -449.348099) (xy 51.754319 -449.354148) (xy 51.828817 -449.368195) (xy 51.9014 -449.390081)
			(xy 51.971246 -449.419558) (xy 52.037563 -449.456293) (xy 52.099599 -449.499868) (xy 52.156652 -449.54979)
			(xy 52.208076 -449.605494) (xy 52.253287 -449.666349) (xy 52.291774 -449.731664) (xy 52.3231 -449.8007)
			(xy 52.34691 -449.872675) (xy 52.362935 -449.946773) (xy 52.370994 -450.022154) (xy 52.371498 -450.06006)
			(xy 53.487577 -450.06006) (xy 53.491612 -449.984356) (xy 53.503671 -449.909511) (xy 53.523617 -449.83637)
			(xy 53.551224 -449.765765) (xy 53.58618 -449.698494) (xy 53.628088 -449.635319) (xy 53.676474 -449.576957)
			(xy 53.73079 -449.524069) (xy 53.790419 -449.477254) (xy 53.854687 -449.437042) (xy 53.922864 -449.40389)
			(xy 53.99418 -449.378172) (xy 54.067825 -449.36018) (xy 54.142965 -449.350118) (xy 54.218749 -449.348099)
			(xy 54.294319 -449.354148) (xy 54.368817 -449.368195) (xy 54.4414 -449.390081) (xy 54.511246 -449.419558)
			(xy 54.577563 -449.456293) (xy 54.639599 -449.499868) (xy 54.696652 -449.54979) (xy 54.748076 -449.605494)
			(xy 54.793287 -449.666349) (xy 54.831774 -449.731664) (xy 54.8631 -449.8007) (xy 54.88691 -449.872675)
			(xy 54.902935 -449.946773) (xy 54.910994 -450.022154) (xy 54.911498 -450.06006) (xy 56.027577 -450.06006)
			(xy 56.031612 -449.984356) (xy 56.043671 -449.909511) (xy 56.063617 -449.83637) (xy 56.091224 -449.765765)
			(xy 56.12618 -449.698494) (xy 56.168088 -449.635319) (xy 56.216474 -449.576957) (xy 56.27079 -449.524069)
			(xy 56.330419 -449.477254) (xy 56.394687 -449.437042) (xy 56.462864 -449.40389) (xy 56.53418 -449.378172)
			(xy 56.607825 -449.36018) (xy 56.682965 -449.350118) (xy 56.758749 -449.348099) (xy 56.834319 -449.354148)
			(xy 56.908817 -449.368195) (xy 56.9814 -449.390081) (xy 57.051246 -449.419558) (xy 57.117563 -449.456293)
			(xy 57.179599 -449.499868) (xy 57.236652 -449.54979) (xy 57.288076 -449.605494) (xy 57.333287 -449.666349)
			(xy 57.371774 -449.731664) (xy 57.4031 -449.8007) (xy 57.42691 -449.872675) (xy 57.442935 -449.946773)
			(xy 57.450994 -450.022154) (xy 57.451498 -450.06006) (xy 58.567577 -450.06006) (xy 58.571612 -449.984356)
			(xy 58.583671 -449.909511) (xy 58.603617 -449.83637) (xy 58.631224 -449.765765) (xy 58.66618 -449.698494)
			(xy 58.708088 -449.635319) (xy 58.756474 -449.576957) (xy 58.81079 -449.524069) (xy 58.870419 -449.477254)
			(xy 58.934687 -449.437042) (xy 59.002864 -449.40389) (xy 59.07418 -449.378172) (xy 59.147825 -449.36018)
			(xy 59.222965 -449.350118) (xy 59.298749 -449.348099) (xy 59.374319 -449.354148) (xy 59.448817 -449.368195)
			(xy 59.5214 -449.390081) (xy 59.591246 -449.419558) (xy 59.657563 -449.456293) (xy 59.719599 -449.499868)
			(xy 59.776652 -449.54979) (xy 59.828076 -449.605494) (xy 59.873287 -449.666349) (xy 59.911774 -449.731664)
			(xy 59.9431 -449.8007) (xy 59.96691 -449.872675) (xy 59.982935 -449.946773) (xy 59.990994 -450.022154)
			(xy 59.991498 -450.06006) (xy 61.107577 -450.06006) (xy 61.111612 -449.984356) (xy 61.123671 -449.909511)
			(xy 61.143617 -449.83637) (xy 61.171224 -449.765765) (xy 61.20618 -449.698494) (xy 61.248088 -449.635319)
			(xy 61.296474 -449.576957) (xy 61.35079 -449.524069) (xy 61.410419 -449.477254) (xy 61.474687 -449.437042)
			(xy 61.542864 -449.40389) (xy 61.61418 -449.378172) (xy 61.687825 -449.36018) (xy 61.762965 -449.350118)
			(xy 61.838749 -449.348099) (xy 61.914319 -449.354148) (xy 61.988817 -449.368195) (xy 62.0614 -449.390081)
			(xy 62.131246 -449.419558) (xy 62.197563 -449.456293) (xy 62.259599 -449.499868) (xy 62.265544 -449.50507)
			(xy 86.197697 -449.50507) (xy 86.201732 -449.429366) (xy 86.213791 -449.354521) (xy 86.233737 -449.28138)
			(xy 86.261344 -449.210775) (xy 86.2963 -449.143504) (xy 86.338208 -449.080329) (xy 86.386594 -449.021967)
			(xy 86.44091 -448.969079) (xy 86.500539 -448.922264) (xy 86.564807 -448.882052) (xy 86.632984 -448.8489)
			(xy 86.7043 -448.823182) (xy 86.777945 -448.80519) (xy 86.853085 -448.795128) (xy 86.928869 -448.793109)
			(xy 87.004439 -448.799158) (xy 87.078937 -448.813205) (xy 87.15152 -448.835091) (xy 87.221366 -448.864568)
			(xy 87.287683 -448.901303) (xy 87.349719 -448.944878) (xy 87.406772 -448.9948) (xy 87.458196 -449.050504)
			(xy 87.503407 -449.111359) (xy 87.541894 -449.176674) (xy 87.57322 -449.24571) (xy 87.59703 -449.317685)
			(xy 87.613055 -449.391783) (xy 87.621114 -449.467164) (xy 87.621618 -449.50507) (xy 88.737697 -449.50507)
			(xy 88.741732 -449.429366) (xy 88.753791 -449.354521) (xy 88.773737 -449.28138) (xy 88.801344 -449.210775)
			(xy 88.8363 -449.143504) (xy 88.878208 -449.080329) (xy 88.926594 -449.021967) (xy 88.98091 -448.969079)
			(xy 89.040539 -448.922264) (xy 89.104807 -448.882052) (xy 89.172984 -448.8489) (xy 89.2443 -448.823182)
			(xy 89.317945 -448.80519) (xy 89.393085 -448.795128) (xy 89.468869 -448.793109) (xy 89.544439 -448.799158)
			(xy 89.618937 -448.813205) (xy 89.69152 -448.835091) (xy 89.761366 -448.864568) (xy 89.827683 -448.901303)
			(xy 89.889719 -448.944878) (xy 89.946772 -448.9948) (xy 89.998196 -449.050504) (xy 90.043407 -449.111359)
			(xy 90.081894 -449.176674) (xy 90.11322 -449.24571) (xy 90.13703 -449.317685) (xy 90.153055 -449.391783)
			(xy 90.161114 -449.467164) (xy 90.161618 -449.50507) (xy 91.277697 -449.50507) (xy 91.281732 -449.429366)
			(xy 91.293791 -449.354521) (xy 91.313737 -449.28138) (xy 91.341344 -449.210775) (xy 91.3763 -449.143504)
			(xy 91.418208 -449.080329) (xy 91.466594 -449.021967) (xy 91.52091 -448.969079) (xy 91.580539 -448.922264)
			(xy 91.644807 -448.882052) (xy 91.712984 -448.8489) (xy 91.7843 -448.823182) (xy 91.857945 -448.80519)
			(xy 91.933085 -448.795128) (xy 92.008869 -448.793109) (xy 92.084439 -448.799158) (xy 92.158937 -448.813205)
			(xy 92.23152 -448.835091) (xy 92.301366 -448.864568) (xy 92.367683 -448.901303) (xy 92.429719 -448.944878)
			(xy 92.486772 -448.9948) (xy 92.538196 -449.050504) (xy 92.583407 -449.111359) (xy 92.621894 -449.176674)
			(xy 92.65322 -449.24571) (xy 92.67703 -449.317685) (xy 92.693055 -449.391783) (xy 92.701114 -449.467164)
			(xy 92.701618 -449.50507) (xy 92.701114 -449.542976) (xy 92.693055 -449.618357) (xy 92.67703 -449.692455)
			(xy 92.65322 -449.76443) (xy 92.621894 -449.833466) (xy 92.583407 -449.898781) (xy 92.538196 -449.959636)
			(xy 92.486772 -450.01534) (xy 92.429719 -450.065262) (xy 92.367683 -450.108837) (xy 92.301366 -450.145572)
			(xy 92.23152 -450.175049) (xy 92.158937 -450.196935) (xy 92.084439 -450.210982) (xy 92.008869 -450.217031)
			(xy 91.933085 -450.215012) (xy 91.857945 -450.20495) (xy 91.7843 -450.186958) (xy 91.712984 -450.16124)
			(xy 91.644807 -450.128088) (xy 91.580539 -450.087876) (xy 91.52091 -450.041061) (xy 91.466594 -449.988173)
			(xy 91.418208 -449.929811) (xy 91.3763 -449.866636) (xy 91.341344 -449.799365) (xy 91.313737 -449.72876)
			(xy 91.293791 -449.655619) (xy 91.281732 -449.580774) (xy 91.277697 -449.50507) (xy 90.161618 -449.50507)
			(xy 90.161114 -449.542976) (xy 90.153055 -449.618357) (xy 90.13703 -449.692455) (xy 90.11322 -449.76443)
			(xy 90.081894 -449.833466) (xy 90.043407 -449.898781) (xy 89.998196 -449.959636) (xy 89.946772 -450.01534)
			(xy 89.889719 -450.065262) (xy 89.827683 -450.108837) (xy 89.761366 -450.145572) (xy 89.69152 -450.175049)
			(xy 89.618937 -450.196935) (xy 89.544439 -450.210982) (xy 89.468869 -450.217031) (xy 89.393085 -450.215012)
			(xy 89.317945 -450.20495) (xy 89.2443 -450.186958) (xy 89.172984 -450.16124) (xy 89.104807 -450.128088)
			(xy 89.040539 -450.087876) (xy 88.98091 -450.041061) (xy 88.926594 -449.988173) (xy 88.878208 -449.929811)
			(xy 88.8363 -449.866636) (xy 88.801344 -449.799365) (xy 88.773737 -449.72876) (xy 88.753791 -449.655619)
			(xy 88.741732 -449.580774) (xy 88.737697 -449.50507) (xy 87.621618 -449.50507) (xy 87.621114 -449.542976)
			(xy 87.613055 -449.618357) (xy 87.59703 -449.692455) (xy 87.57322 -449.76443) (xy 87.541894 -449.833466)
			(xy 87.503407 -449.898781) (xy 87.458196 -449.959636) (xy 87.406772 -450.01534) (xy 87.349719 -450.065262)
			(xy 87.287683 -450.108837) (xy 87.221366 -450.145572) (xy 87.15152 -450.175049) (xy 87.078937 -450.196935)
			(xy 87.004439 -450.210982) (xy 86.928869 -450.217031) (xy 86.853085 -450.215012) (xy 86.777945 -450.20495)
			(xy 86.7043 -450.186958) (xy 86.632984 -450.16124) (xy 86.564807 -450.128088) (xy 86.500539 -450.087876)
			(xy 86.44091 -450.041061) (xy 86.386594 -449.988173) (xy 86.338208 -449.929811) (xy 86.2963 -449.866636)
			(xy 86.261344 -449.799365) (xy 86.233737 -449.72876) (xy 86.213791 -449.655619) (xy 86.201732 -449.580774)
			(xy 86.197697 -449.50507) (xy 62.265544 -449.50507) (xy 62.316652 -449.54979) (xy 62.368076 -449.605494)
			(xy 62.413287 -449.666349) (xy 62.451774 -449.731664) (xy 62.4831 -449.8007) (xy 62.50691 -449.872675)
			(xy 62.522935 -449.946773) (xy 62.530994 -450.022154) (xy 62.531498 -450.06006) (xy 62.530994 -450.097966)
			(xy 62.522935 -450.173347) (xy 62.50691 -450.247445) (xy 62.4831 -450.31942) (xy 62.451774 -450.388456)
			(xy 62.413287 -450.453771) (xy 62.368076 -450.514626) (xy 62.316652 -450.57033) (xy 62.259599 -450.620252)
			(xy 62.197563 -450.663827) (xy 62.131246 -450.700562) (xy 62.0614 -450.730039) (xy 61.988817 -450.751925)
			(xy 61.914319 -450.765972) (xy 61.838749 -450.772021) (xy 61.762965 -450.770002) (xy 61.687825 -450.75994)
			(xy 61.61418 -450.741948) (xy 61.542864 -450.71623) (xy 61.474687 -450.683078) (xy 61.410419 -450.642866)
			(xy 61.35079 -450.596051) (xy 61.296474 -450.543163) (xy 61.248088 -450.484801) (xy 61.20618 -450.421626)
			(xy 61.171224 -450.354355) (xy 61.143617 -450.28375) (xy 61.123671 -450.210609) (xy 61.111612 -450.135764)
			(xy 61.107577 -450.06006) (xy 59.991498 -450.06006) (xy 59.990994 -450.097966) (xy 59.982935 -450.173347)
			(xy 59.96691 -450.247445) (xy 59.9431 -450.31942) (xy 59.911774 -450.388456) (xy 59.873287 -450.453771)
			(xy 59.828076 -450.514626) (xy 59.776652 -450.57033) (xy 59.719599 -450.620252) (xy 59.657563 -450.663827)
			(xy 59.591246 -450.700562) (xy 59.5214 -450.730039) (xy 59.448817 -450.751925) (xy 59.374319 -450.765972)
			(xy 59.298749 -450.772021) (xy 59.222965 -450.770002) (xy 59.147825 -450.75994) (xy 59.07418 -450.741948)
			(xy 59.002864 -450.71623) (xy 58.934687 -450.683078) (xy 58.870419 -450.642866) (xy 58.81079 -450.596051)
			(xy 58.756474 -450.543163) (xy 58.708088 -450.484801) (xy 58.66618 -450.421626) (xy 58.631224 -450.354355)
			(xy 58.603617 -450.28375) (xy 58.583671 -450.210609) (xy 58.571612 -450.135764) (xy 58.567577 -450.06006)
			(xy 57.451498 -450.06006) (xy 57.450994 -450.097966) (xy 57.442935 -450.173347) (xy 57.42691 -450.247445)
			(xy 57.4031 -450.31942) (xy 57.371774 -450.388456) (xy 57.333287 -450.453771) (xy 57.288076 -450.514626)
			(xy 57.236652 -450.57033) (xy 57.179599 -450.620252) (xy 57.117563 -450.663827) (xy 57.051246 -450.700562)
			(xy 56.9814 -450.730039) (xy 56.908817 -450.751925) (xy 56.834319 -450.765972) (xy 56.758749 -450.772021)
			(xy 56.682965 -450.770002) (xy 56.607825 -450.75994) (xy 56.53418 -450.741948) (xy 56.462864 -450.71623)
			(xy 56.394687 -450.683078) (xy 56.330419 -450.642866) (xy 56.27079 -450.596051) (xy 56.216474 -450.543163)
			(xy 56.168088 -450.484801) (xy 56.12618 -450.421626) (xy 56.091224 -450.354355) (xy 56.063617 -450.28375)
			(xy 56.043671 -450.210609) (xy 56.031612 -450.135764) (xy 56.027577 -450.06006) (xy 54.911498 -450.06006)
			(xy 54.910994 -450.097966) (xy 54.902935 -450.173347) (xy 54.88691 -450.247445) (xy 54.8631 -450.31942)
			(xy 54.831774 -450.388456) (xy 54.793287 -450.453771) (xy 54.748076 -450.514626) (xy 54.696652 -450.57033)
			(xy 54.639599 -450.620252) (xy 54.577563 -450.663827) (xy 54.511246 -450.700562) (xy 54.4414 -450.730039)
			(xy 54.368817 -450.751925) (xy 54.294319 -450.765972) (xy 54.218749 -450.772021) (xy 54.142965 -450.770002)
			(xy 54.067825 -450.75994) (xy 53.99418 -450.741948) (xy 53.922864 -450.71623) (xy 53.854687 -450.683078)
			(xy 53.790419 -450.642866) (xy 53.73079 -450.596051) (xy 53.676474 -450.543163) (xy 53.628088 -450.484801)
			(xy 53.58618 -450.421626) (xy 53.551224 -450.354355) (xy 53.523617 -450.28375) (xy 53.503671 -450.210609)
			(xy 53.491612 -450.135764) (xy 53.487577 -450.06006) (xy 52.371498 -450.06006) (xy 52.370994 -450.097966)
			(xy 52.362935 -450.173347) (xy 52.34691 -450.247445) (xy 52.3231 -450.31942) (xy 52.291774 -450.388456)
			(xy 52.253287 -450.453771) (xy 52.208076 -450.514626) (xy 52.156652 -450.57033) (xy 52.099599 -450.620252)
			(xy 52.037563 -450.663827) (xy 51.971246 -450.700562) (xy 51.9014 -450.730039) (xy 51.828817 -450.751925)
			(xy 51.754319 -450.765972) (xy 51.678749 -450.772021) (xy 51.602965 -450.770002) (xy 51.527825 -450.75994)
			(xy 51.45418 -450.741948) (xy 51.382864 -450.71623) (xy 51.314687 -450.683078) (xy 51.250419 -450.642866)
			(xy 51.19079 -450.596051) (xy 51.136474 -450.543163) (xy 51.088088 -450.484801) (xy 51.04618 -450.421626)
			(xy 51.011224 -450.354355) (xy 50.983617 -450.28375) (xy 50.963671 -450.210609) (xy 50.951612 -450.135764)
			(xy 50.947577 -450.06006) (xy 49.831498 -450.06006) (xy 49.830994 -450.097966) (xy 49.822935 -450.173347)
			(xy 49.80691 -450.247445) (xy 49.7831 -450.31942) (xy 49.751774 -450.388456) (xy 49.713287 -450.453771)
			(xy 49.668076 -450.514626) (xy 49.616652 -450.57033) (xy 49.559599 -450.620252) (xy 49.497563 -450.663827)
			(xy 49.431246 -450.700562) (xy 49.3614 -450.730039) (xy 49.288817 -450.751925) (xy 49.214319 -450.765972)
			(xy 49.138749 -450.772021) (xy 49.062965 -450.770002) (xy 48.987825 -450.75994) (xy 48.91418 -450.741948)
			(xy 48.842864 -450.71623) (xy 48.774687 -450.683078) (xy 48.710419 -450.642866) (xy 48.65079 -450.596051)
			(xy 48.596474 -450.543163) (xy 48.548088 -450.484801) (xy 48.50618 -450.421626) (xy 48.471224 -450.354355)
			(xy 48.443617 -450.28375) (xy 48.423671 -450.210609) (xy 48.411612 -450.135764) (xy 48.407577 -450.06006)
			(xy 47.291498 -450.06006) (xy 47.290994 -450.097966) (xy 47.282935 -450.173347) (xy 47.26691 -450.247445)
			(xy 47.2431 -450.31942) (xy 47.211774 -450.388456) (xy 47.173287 -450.453771) (xy 47.128076 -450.514626)
			(xy 47.076652 -450.57033) (xy 47.019599 -450.620252) (xy 46.957563 -450.663827) (xy 46.891246 -450.700562)
			(xy 46.8214 -450.730039) (xy 46.748817 -450.751925) (xy 46.674319 -450.765972) (xy 46.598749 -450.772021)
			(xy 46.522965 -450.770002) (xy 46.447825 -450.75994) (xy 46.37418 -450.741948) (xy 46.302864 -450.71623)
			(xy 46.234687 -450.683078) (xy 46.170419 -450.642866) (xy 46.11079 -450.596051) (xy 46.056474 -450.543163)
			(xy 46.008088 -450.484801) (xy 45.96618 -450.421626) (xy 45.931224 -450.354355) (xy 45.903617 -450.28375)
			(xy 45.883671 -450.210609) (xy 45.871612 -450.135764) (xy 45.867577 -450.06006) (xy 44.751498 -450.06006)
			(xy 44.750994 -450.097966) (xy 44.742935 -450.173347) (xy 44.72691 -450.247445) (xy 44.7031 -450.31942)
			(xy 44.671774 -450.388456) (xy 44.633287 -450.453771) (xy 44.588076 -450.514626) (xy 44.536652 -450.57033)
			(xy 44.479599 -450.620252) (xy 44.417563 -450.663827) (xy 44.351246 -450.700562) (xy 44.2814 -450.730039)
			(xy 44.208817 -450.751925) (xy 44.134319 -450.765972) (xy 44.058749 -450.772021) (xy 43.982965 -450.770002)
			(xy 43.907825 -450.75994) (xy 43.83418 -450.741948) (xy 43.762864 -450.71623) (xy 43.694687 -450.683078)
			(xy 43.630419 -450.642866) (xy 43.57079 -450.596051) (xy 43.516474 -450.543163) (xy 43.468088 -450.484801)
			(xy 43.42618 -450.421626) (xy 43.391224 -450.354355) (xy 43.363617 -450.28375) (xy 43.343671 -450.210609)
			(xy 43.331612 -450.135764) (xy 43.327577 -450.06006) (xy 42.502604 -450.06006) (xy 42.593088 -450.132218)
			(xy 42.678643 -450.210691) (xy 42.758581 -450.294879) (xy 42.83252 -450.384381) (xy 42.900108 -450.478772)
			(xy 42.961022 -450.5776) (xy 43.014974 -450.680396) (xy 43.056604 -450.77507) (xy 84.927697 -450.77507)
			(xy 84.931732 -450.699366) (xy 84.943791 -450.624521) (xy 84.963737 -450.55138) (xy 84.991344 -450.480775)
			(xy 85.0263 -450.413504) (xy 85.068208 -450.350329) (xy 85.116594 -450.291967) (xy 85.17091 -450.239079)
			(xy 85.230539 -450.192264) (xy 85.294807 -450.152052) (xy 85.362984 -450.1189) (xy 85.4343 -450.093182)
			(xy 85.507945 -450.07519) (xy 85.583085 -450.065128) (xy 85.658869 -450.063109) (xy 85.734439 -450.069158)
			(xy 85.808937 -450.083205) (xy 85.88152 -450.105091) (xy 85.951366 -450.134568) (xy 86.017683 -450.171303)
			(xy 86.079719 -450.214878) (xy 86.136772 -450.2648) (xy 86.188196 -450.320504) (xy 86.233407 -450.381359)
			(xy 86.271894 -450.446674) (xy 86.30322 -450.51571) (xy 86.32703 -450.587685) (xy 86.343055 -450.661783)
			(xy 86.351114 -450.737164) (xy 86.351618 -450.77507) (xy 87.467697 -450.77507) (xy 87.471732 -450.699366)
			(xy 87.483791 -450.624521) (xy 87.503737 -450.55138) (xy 87.531344 -450.480775) (xy 87.5663 -450.413504)
			(xy 87.608208 -450.350329) (xy 87.656594 -450.291967) (xy 87.71091 -450.239079) (xy 87.770539 -450.192264)
			(xy 87.834807 -450.152052) (xy 87.902984 -450.1189) (xy 87.9743 -450.093182) (xy 88.047945 -450.07519)
			(xy 88.123085 -450.065128) (xy 88.198869 -450.063109) (xy 88.274439 -450.069158) (xy 88.348937 -450.083205)
			(xy 88.42152 -450.105091) (xy 88.491366 -450.134568) (xy 88.557683 -450.171303) (xy 88.619719 -450.214878)
			(xy 88.676772 -450.2648) (xy 88.728196 -450.320504) (xy 88.773407 -450.381359) (xy 88.811894 -450.446674)
			(xy 88.84322 -450.51571) (xy 88.86703 -450.587685) (xy 88.883055 -450.661783) (xy 88.891114 -450.737164)
			(xy 88.891618 -450.77507) (xy 90.007697 -450.77507) (xy 90.011732 -450.699366) (xy 90.023791 -450.624521)
			(xy 90.043737 -450.55138) (xy 90.071344 -450.480775) (xy 90.1063 -450.413504) (xy 90.148208 -450.350329)
			(xy 90.196594 -450.291967) (xy 90.25091 -450.239079) (xy 90.310539 -450.192264) (xy 90.374807 -450.152052)
			(xy 90.442984 -450.1189) (xy 90.5143 -450.093182) (xy 90.587945 -450.07519) (xy 90.663085 -450.065128)
			(xy 90.738869 -450.063109) (xy 90.814439 -450.069158) (xy 90.888937 -450.083205) (xy 90.96152 -450.105091)
			(xy 91.031366 -450.134568) (xy 91.097683 -450.171303) (xy 91.159719 -450.214878) (xy 91.216772 -450.2648)
			(xy 91.268196 -450.320504) (xy 91.313407 -450.381359) (xy 91.351894 -450.446674) (xy 91.38322 -450.51571)
			(xy 91.40703 -450.587685) (xy 91.423055 -450.661783) (xy 91.431114 -450.737164) (xy 91.431618 -450.77507)
			(xy 91.431114 -450.812976) (xy 91.423055 -450.888357) (xy 91.40703 -450.962455) (xy 91.38322 -451.03443)
			(xy 91.351894 -451.103466) (xy 91.313407 -451.168781) (xy 91.268196 -451.229636) (xy 91.216772 -451.28534)
			(xy 91.159719 -451.335262) (xy 91.097683 -451.378837) (xy 91.031366 -451.415572) (xy 90.96152 -451.445049)
			(xy 90.888937 -451.466935) (xy 90.814439 -451.480982) (xy 90.738869 -451.487031) (xy 90.663085 -451.485012)
			(xy 90.587945 -451.47495) (xy 90.5143 -451.456958) (xy 90.442984 -451.43124) (xy 90.374807 -451.398088)
			(xy 90.310539 -451.357876) (xy 90.25091 -451.311061) (xy 90.196594 -451.258173) (xy 90.148208 -451.199811)
			(xy 90.1063 -451.136636) (xy 90.071344 -451.069365) (xy 90.043737 -450.99876) (xy 90.023791 -450.925619)
			(xy 90.011732 -450.850774) (xy 90.007697 -450.77507) (xy 88.891618 -450.77507) (xy 88.891114 -450.812976)
			(xy 88.883055 -450.888357) (xy 88.86703 -450.962455) (xy 88.84322 -451.03443) (xy 88.811894 -451.103466)
			(xy 88.773407 -451.168781) (xy 88.728196 -451.229636) (xy 88.676772 -451.28534) (xy 88.619719 -451.335262)
			(xy 88.557683 -451.378837) (xy 88.491366 -451.415572) (xy 88.42152 -451.445049) (xy 88.348937 -451.466935)
			(xy 88.274439 -451.480982) (xy 88.198869 -451.487031) (xy 88.123085 -451.485012) (xy 88.047945 -451.47495)
			(xy 87.9743 -451.456958) (xy 87.902984 -451.43124) (xy 87.834807 -451.398088) (xy 87.770539 -451.357876)
			(xy 87.71091 -451.311061) (xy 87.656594 -451.258173) (xy 87.608208 -451.199811) (xy 87.5663 -451.136636)
			(xy 87.531344 -451.069365) (xy 87.503737 -450.99876) (xy 87.483791 -450.925619) (xy 87.471732 -450.850774)
			(xy 87.467697 -450.77507) (xy 86.351618 -450.77507) (xy 86.351114 -450.812976) (xy 86.343055 -450.888357)
			(xy 86.32703 -450.962455) (xy 86.30322 -451.03443) (xy 86.271894 -451.103466) (xy 86.233407 -451.168781)
			(xy 86.188196 -451.229636) (xy 86.136772 -451.28534) (xy 86.079719 -451.335262) (xy 86.017683 -451.378837)
			(xy 85.951366 -451.415572) (xy 85.88152 -451.445049) (xy 85.808937 -451.466935) (xy 85.734439 -451.480982)
			(xy 85.658869 -451.487031) (xy 85.583085 -451.485012) (xy 85.507945 -451.47495) (xy 85.4343 -451.456958)
			(xy 85.362984 -451.43124) (xy 85.294807 -451.398088) (xy 85.230539 -451.357876) (xy 85.17091 -451.311061)
			(xy 85.116594 -451.258173) (xy 85.068208 -451.199811) (xy 85.0263 -451.136636) (xy 84.991344 -451.069365)
			(xy 84.963737 -450.99876) (xy 84.943791 -450.925619) (xy 84.931732 -450.850774) (xy 84.927697 -450.77507)
			(xy 43.056604 -450.77507) (xy 43.061704 -450.786669) (xy 43.100992 -450.895913) (xy 43.132649 -451.007606)
			(xy 43.156525 -451.121218) (xy 43.172506 -451.236206) (xy 43.180515 -451.352023) (xy 43.181016 -451.41007)
			(xy 43.180515 -451.468117) (xy 43.172506 -451.583934) (xy 43.156525 -451.698922) (xy 43.132649 -451.812534)
			(xy 43.100992 -451.924227) (xy 43.061704 -452.033471) (xy 43.056604 -452.04507) (xy 86.197697 -452.04507)
			(xy 86.201732 -451.969366) (xy 86.213791 -451.894521) (xy 86.233737 -451.82138) (xy 86.261344 -451.750775)
			(xy 86.2963 -451.683504) (xy 86.338208 -451.620329) (xy 86.386594 -451.561967) (xy 86.44091 -451.509079)
			(xy 86.500539 -451.462264) (xy 86.564807 -451.422052) (xy 86.632984 -451.3889) (xy 86.7043 -451.363182)
			(xy 86.777945 -451.34519) (xy 86.853085 -451.335128) (xy 86.928869 -451.333109) (xy 87.004439 -451.339158)
			(xy 87.078937 -451.353205) (xy 87.15152 -451.375091) (xy 87.221366 -451.404568) (xy 87.287683 -451.441303)
			(xy 87.349719 -451.484878) (xy 87.406772 -451.5348) (xy 87.458196 -451.590504) (xy 87.503407 -451.651359)
			(xy 87.541894 -451.716674) (xy 87.57322 -451.78571) (xy 87.59703 -451.857685) (xy 87.613055 -451.931783)
			(xy 87.621114 -452.007164) (xy 87.621618 -452.04507) (xy 88.737697 -452.04507) (xy 88.741732 -451.969366)
			(xy 88.753791 -451.894521) (xy 88.773737 -451.82138) (xy 88.801344 -451.750775) (xy 88.8363 -451.683504)
			(xy 88.878208 -451.620329) (xy 88.926594 -451.561967) (xy 88.98091 -451.509079) (xy 89.040539 -451.462264)
			(xy 89.104807 -451.422052) (xy 89.172984 -451.3889) (xy 89.2443 -451.363182) (xy 89.317945 -451.34519)
			(xy 89.393085 -451.335128) (xy 89.468869 -451.333109) (xy 89.544439 -451.339158) (xy 89.618937 -451.353205)
			(xy 89.69152 -451.375091) (xy 89.761366 -451.404568) (xy 89.827683 -451.441303) (xy 89.889719 -451.484878)
			(xy 89.946772 -451.5348) (xy 89.998196 -451.590504) (xy 90.043407 -451.651359) (xy 90.081894 -451.716674)
			(xy 90.11322 -451.78571) (xy 90.13703 -451.857685) (xy 90.153055 -451.931783) (xy 90.161114 -452.007164)
			(xy 90.161618 -452.04507) (xy 91.277697 -452.04507) (xy 91.281732 -451.969366) (xy 91.293791 -451.894521)
			(xy 91.313737 -451.82138) (xy 91.341344 -451.750775) (xy 91.3763 -451.683504) (xy 91.418208 -451.620329)
			(xy 91.466594 -451.561967) (xy 91.52091 -451.509079) (xy 91.580539 -451.462264) (xy 91.644807 -451.422052)
			(xy 91.712984 -451.3889) (xy 91.7843 -451.363182) (xy 91.857945 -451.34519) (xy 91.933085 -451.335128)
			(xy 92.008869 -451.333109) (xy 92.084439 -451.339158) (xy 92.158937 -451.353205) (xy 92.23152 -451.375091)
			(xy 92.301366 -451.404568) (xy 92.367683 -451.441303) (xy 92.429719 -451.484878) (xy 92.486772 -451.5348)
			(xy 92.538196 -451.590504) (xy 92.583407 -451.651359) (xy 92.621894 -451.716674) (xy 92.65322 -451.78571)
			(xy 92.67703 -451.857685) (xy 92.693055 -451.931783) (xy 92.701114 -452.007164) (xy 92.701618 -452.04507)
			(xy 92.701114 -452.082976) (xy 92.693055 -452.158357) (xy 92.67703 -452.232455) (xy 92.65322 -452.30443)
			(xy 92.621894 -452.373466) (xy 92.583407 -452.438781) (xy 92.538196 -452.499636) (xy 92.486772 -452.55534)
			(xy 92.429719 -452.605262) (xy 92.367683 -452.648837) (xy 92.301366 -452.685572) (xy 92.23152 -452.715049)
			(xy 92.158937 -452.736935) (xy 92.084439 -452.750982) (xy 92.008869 -452.757031) (xy 91.933085 -452.755012)
			(xy 91.857945 -452.74495) (xy 91.7843 -452.726958) (xy 91.712984 -452.70124) (xy 91.644807 -452.668088)
			(xy 91.580539 -452.627876) (xy 91.52091 -452.581061) (xy 91.466594 -452.528173) (xy 91.418208 -452.469811)
			(xy 91.3763 -452.406636) (xy 91.341344 -452.339365) (xy 91.313737 -452.26876) (xy 91.293791 -452.195619)
			(xy 91.281732 -452.120774) (xy 91.277697 -452.04507) (xy 90.161618 -452.04507) (xy 90.161114 -452.082976)
			(xy 90.153055 -452.158357) (xy 90.13703 -452.232455) (xy 90.11322 -452.30443) (xy 90.081894 -452.373466)
			(xy 90.043407 -452.438781) (xy 89.998196 -452.499636) (xy 89.946772 -452.55534) (xy 89.889719 -452.605262)
			(xy 89.827683 -452.648837) (xy 89.761366 -452.685572) (xy 89.69152 -452.715049) (xy 89.618937 -452.736935)
			(xy 89.544439 -452.750982) (xy 89.468869 -452.757031) (xy 89.393085 -452.755012) (xy 89.317945 -452.74495)
			(xy 89.2443 -452.726958) (xy 89.172984 -452.70124) (xy 89.104807 -452.668088) (xy 89.040539 -452.627876)
			(xy 88.98091 -452.581061) (xy 88.926594 -452.528173) (xy 88.878208 -452.469811) (xy 88.8363 -452.406636)
			(xy 88.801344 -452.339365) (xy 88.773737 -452.26876) (xy 88.753791 -452.195619) (xy 88.741732 -452.120774)
			(xy 88.737697 -452.04507) (xy 87.621618 -452.04507) (xy 87.621114 -452.082976) (xy 87.613055 -452.158357)
			(xy 87.59703 -452.232455) (xy 87.57322 -452.30443) (xy 87.541894 -452.373466) (xy 87.503407 -452.438781)
			(xy 87.458196 -452.499636) (xy 87.406772 -452.55534) (xy 87.349719 -452.605262) (xy 87.287683 -452.648837)
			(xy 87.221366 -452.685572) (xy 87.15152 -452.715049) (xy 87.078937 -452.736935) (xy 87.004439 -452.750982)
			(xy 86.928869 -452.757031) (xy 86.853085 -452.755012) (xy 86.777945 -452.74495) (xy 86.7043 -452.726958)
			(xy 86.632984 -452.70124) (xy 86.564807 -452.668088) (xy 86.500539 -452.627876) (xy 86.44091 -452.581061)
			(xy 86.386594 -452.528173) (xy 86.338208 -452.469811) (xy 86.2963 -452.406636) (xy 86.261344 -452.339365)
			(xy 86.233737 -452.26876) (xy 86.213791 -452.195619) (xy 86.201732 -452.120774) (xy 86.197697 -452.04507)
			(xy 43.056604 -452.04507) (xy 43.055152 -452.048372) (xy 43.328336 -452.048372) (xy 44.751244 -452.048372)
			(xy 44.751244 -452.76008) (xy 45.867577 -452.76008) (xy 45.871612 -452.684376) (xy 45.883671 -452.609531)
			(xy 45.903617 -452.53639) (xy 45.931224 -452.465785) (xy 45.96618 -452.398514) (xy 46.008088 -452.335339)
			(xy 46.056474 -452.276977) (xy 46.11079 -452.224089) (xy 46.170419 -452.177274) (xy 46.234687 -452.137062)
			(xy 46.302864 -452.10391) (xy 46.37418 -452.078192) (xy 46.447825 -452.0602) (xy 46.522965 -452.050138)
			(xy 46.598749 -452.048119) (xy 46.674319 -452.054168) (xy 46.748817 -452.068215) (xy 46.8214 -452.090101)
			(xy 46.891246 -452.119578) (xy 46.957563 -452.156313) (xy 47.019599 -452.199888) (xy 47.076652 -452.24981)
			(xy 47.128076 -452.305514) (xy 47.173287 -452.366369) (xy 47.211774 -452.431684) (xy 47.2431 -452.50072)
			(xy 47.26691 -452.572695) (xy 47.282935 -452.646793) (xy 47.290994 -452.722174) (xy 47.291498 -452.76008)
			(xy 48.407577 -452.76008) (xy 48.411612 -452.684376) (xy 48.423671 -452.609531) (xy 48.443617 -452.53639)
			(xy 48.471224 -452.465785) (xy 48.50618 -452.398514) (xy 48.548088 -452.335339) (xy 48.596474 -452.276977)
			(xy 48.65079 -452.224089) (xy 48.710419 -452.177274) (xy 48.774687 -452.137062) (xy 48.842864 -452.10391)
			(xy 48.91418 -452.078192) (xy 48.987825 -452.0602) (xy 49.062965 -452.050138) (xy 49.138749 -452.048119)
			(xy 49.214319 -452.054168) (xy 49.288817 -452.068215) (xy 49.3614 -452.090101) (xy 49.431246 -452.119578)
			(xy 49.497563 -452.156313) (xy 49.559599 -452.199888) (xy 49.616652 -452.24981) (xy 49.668076 -452.305514)
			(xy 49.713287 -452.366369) (xy 49.751774 -452.431684) (xy 49.7831 -452.50072) (xy 49.80691 -452.572695)
			(xy 49.822935 -452.646793) (xy 49.830994 -452.722174) (xy 49.831498 -452.76008) (xy 50.947577 -452.76008)
			(xy 50.951612 -452.684376) (xy 50.963671 -452.609531) (xy 50.983617 -452.53639) (xy 51.011224 -452.465785)
			(xy 51.04618 -452.398514) (xy 51.088088 -452.335339) (xy 51.136474 -452.276977) (xy 51.19079 -452.224089)
			(xy 51.250419 -452.177274) (xy 51.314687 -452.137062) (xy 51.382864 -452.10391) (xy 51.45418 -452.078192)
			(xy 51.527825 -452.0602) (xy 51.602965 -452.050138) (xy 51.678749 -452.048119) (xy 51.754319 -452.054168)
			(xy 51.828817 -452.068215) (xy 51.9014 -452.090101) (xy 51.971246 -452.119578) (xy 52.037563 -452.156313)
			(xy 52.099599 -452.199888) (xy 52.156652 -452.24981) (xy 52.208076 -452.305514) (xy 52.253287 -452.366369)
			(xy 52.291774 -452.431684) (xy 52.3231 -452.50072) (xy 52.34691 -452.572695) (xy 52.362935 -452.646793)
			(xy 52.370994 -452.722174) (xy 52.371498 -452.76008) (xy 53.487577 -452.76008) (xy 53.491612 -452.684376)
			(xy 53.503671 -452.609531) (xy 53.523617 -452.53639) (xy 53.551224 -452.465785) (xy 53.58618 -452.398514)
			(xy 53.628088 -452.335339) (xy 53.676474 -452.276977) (xy 53.73079 -452.224089) (xy 53.790419 -452.177274)
			(xy 53.854687 -452.137062) (xy 53.922864 -452.10391) (xy 53.99418 -452.078192) (xy 54.067825 -452.0602)
			(xy 54.142965 -452.050138) (xy 54.218749 -452.048119) (xy 54.294319 -452.054168) (xy 54.368817 -452.068215)
			(xy 54.4414 -452.090101) (xy 54.511246 -452.119578) (xy 54.577563 -452.156313) (xy 54.639599 -452.199888)
			(xy 54.696652 -452.24981) (xy 54.748076 -452.305514) (xy 54.793287 -452.366369) (xy 54.831774 -452.431684)
			(xy 54.8631 -452.50072) (xy 54.88691 -452.572695) (xy 54.902935 -452.646793) (xy 54.910994 -452.722174)
			(xy 54.911498 -452.76008) (xy 56.027577 -452.76008) (xy 56.031612 -452.684376) (xy 56.043671 -452.609531)
			(xy 56.063617 -452.53639) (xy 56.091224 -452.465785) (xy 56.12618 -452.398514) (xy 56.168088 -452.335339)
			(xy 56.216474 -452.276977) (xy 56.27079 -452.224089) (xy 56.330419 -452.177274) (xy 56.394687 -452.137062)
			(xy 56.462864 -452.10391) (xy 56.53418 -452.078192) (xy 56.607825 -452.0602) (xy 56.682965 -452.050138)
			(xy 56.758749 -452.048119) (xy 56.834319 -452.054168) (xy 56.908817 -452.068215) (xy 56.9814 -452.090101)
			(xy 57.051246 -452.119578) (xy 57.117563 -452.156313) (xy 57.179599 -452.199888) (xy 57.236652 -452.24981)
			(xy 57.288076 -452.305514) (xy 57.333287 -452.366369) (xy 57.371774 -452.431684) (xy 57.4031 -452.50072)
			(xy 57.42691 -452.572695) (xy 57.442935 -452.646793) (xy 57.450994 -452.722174) (xy 57.451498 -452.76008)
			(xy 58.567577 -452.76008) (xy 58.571612 -452.684376) (xy 58.583671 -452.609531) (xy 58.603617 -452.53639)
			(xy 58.631224 -452.465785) (xy 58.66618 -452.398514) (xy 58.708088 -452.335339) (xy 58.756474 -452.276977)
			(xy 58.81079 -452.224089) (xy 58.870419 -452.177274) (xy 58.934687 -452.137062) (xy 59.002864 -452.10391)
			(xy 59.07418 -452.078192) (xy 59.147825 -452.0602) (xy 59.222965 -452.050138) (xy 59.298749 -452.048119)
			(xy 59.374319 -452.054168) (xy 59.448817 -452.068215) (xy 59.5214 -452.090101) (xy 59.591246 -452.119578)
			(xy 59.657563 -452.156313) (xy 59.719599 -452.199888) (xy 59.776652 -452.24981) (xy 59.828076 -452.305514)
			(xy 59.873287 -452.366369) (xy 59.911774 -452.431684) (xy 59.9431 -452.50072) (xy 59.96691 -452.572695)
			(xy 59.982935 -452.646793) (xy 59.990994 -452.722174) (xy 59.991498 -452.76008) (xy 61.107577 -452.76008)
			(xy 61.111612 -452.684376) (xy 61.123671 -452.609531) (xy 61.143617 -452.53639) (xy 61.171224 -452.465785)
			(xy 61.20618 -452.398514) (xy 61.248088 -452.335339) (xy 61.296474 -452.276977) (xy 61.35079 -452.224089)
			(xy 61.410419 -452.177274) (xy 61.474687 -452.137062) (xy 61.542864 -452.10391) (xy 61.61418 -452.078192)
			(xy 61.687825 -452.0602) (xy 61.762965 -452.050138) (xy 61.838749 -452.048119) (xy 61.914319 -452.054168)
			(xy 61.988817 -452.068215) (xy 62.0614 -452.090101) (xy 62.131246 -452.119578) (xy 62.197563 -452.156313)
			(xy 62.259599 -452.199888) (xy 62.316652 -452.24981) (xy 62.368076 -452.305514) (xy 62.413287 -452.366369)
			(xy 62.451774 -452.431684) (xy 62.4831 -452.50072) (xy 62.50691 -452.572695) (xy 62.522935 -452.646793)
			(xy 62.530994 -452.722174) (xy 62.531498 -452.76008) (xy 62.530994 -452.797986) (xy 62.522935 -452.873367)
			(xy 62.50691 -452.947465) (xy 62.4831 -453.01944) (xy 62.451774 -453.088476) (xy 62.413287 -453.153791)
			(xy 62.368076 -453.214646) (xy 62.316652 -453.27035) (xy 62.265544 -453.31507) (xy 84.927697 -453.31507)
			(xy 84.931732 -453.239366) (xy 84.943791 -453.164521) (xy 84.963737 -453.09138) (xy 84.991344 -453.020775)
			(xy 85.0263 -452.953504) (xy 85.068208 -452.890329) (xy 85.116594 -452.831967) (xy 85.17091 -452.779079)
			(xy 85.230539 -452.732264) (xy 85.294807 -452.692052) (xy 85.362984 -452.6589) (xy 85.4343 -452.633182)
			(xy 85.507945 -452.61519) (xy 85.583085 -452.605128) (xy 85.658869 -452.603109) (xy 85.734439 -452.609158)
			(xy 85.808937 -452.623205) (xy 85.88152 -452.645091) (xy 85.951366 -452.674568) (xy 86.017683 -452.711303)
			(xy 86.079719 -452.754878) (xy 86.136772 -452.8048) (xy 86.188196 -452.860504) (xy 86.233407 -452.921359)
			(xy 86.271894 -452.986674) (xy 86.30322 -453.05571) (xy 86.32703 -453.127685) (xy 86.343055 -453.201783)
			(xy 86.351114 -453.277164) (xy 86.351618 -453.31507) (xy 87.467697 -453.31507) (xy 87.471732 -453.239366)
			(xy 87.483791 -453.164521) (xy 87.503737 -453.09138) (xy 87.531344 -453.020775) (xy 87.5663 -452.953504)
			(xy 87.608208 -452.890329) (xy 87.656594 -452.831967) (xy 87.71091 -452.779079) (xy 87.770539 -452.732264)
			(xy 87.834807 -452.692052) (xy 87.902984 -452.6589) (xy 87.9743 -452.633182) (xy 88.047945 -452.61519)
			(xy 88.123085 -452.605128) (xy 88.198869 -452.603109) (xy 88.274439 -452.609158) (xy 88.348937 -452.623205)
			(xy 88.42152 -452.645091) (xy 88.491366 -452.674568) (xy 88.557683 -452.711303) (xy 88.619719 -452.754878)
			(xy 88.676772 -452.8048) (xy 88.728196 -452.860504) (xy 88.773407 -452.921359) (xy 88.811894 -452.986674)
			(xy 88.84322 -453.05571) (xy 88.86703 -453.127685) (xy 88.883055 -453.201783) (xy 88.891114 -453.277164)
			(xy 88.891618 -453.31507) (xy 90.007697 -453.31507) (xy 90.011732 -453.239366) (xy 90.023791 -453.164521)
			(xy 90.043737 -453.09138) (xy 90.071344 -453.020775) (xy 90.1063 -452.953504) (xy 90.148208 -452.890329)
			(xy 90.196594 -452.831967) (xy 90.25091 -452.779079) (xy 90.310539 -452.732264) (xy 90.374807 -452.692052)
			(xy 90.442984 -452.6589) (xy 90.5143 -452.633182) (xy 90.587945 -452.61519) (xy 90.663085 -452.605128)
			(xy 90.738869 -452.603109) (xy 90.814439 -452.609158) (xy 90.888937 -452.623205) (xy 90.96152 -452.645091)
			(xy 91.031366 -452.674568) (xy 91.097683 -452.711303) (xy 91.159719 -452.754878) (xy 91.165664 -452.76008)
			(xy 93.154506 -452.76008) (xy 93.158522 -452.64381) (xy 93.170549 -452.528095) (xy 93.190531 -452.413485)
			(xy 93.218373 -452.300526) (xy 93.253942 -452.189758) (xy 93.297068 -452.081707) (xy 93.347545 -451.976889)
			(xy 93.405134 -451.875804) (xy 93.46956 -451.778932) (xy 93.540515 -451.686736) (xy 93.617662 -451.599655)
			(xy 93.700633 -451.518104) (xy 93.789033 -451.442472) (xy 93.88244 -451.373118) (xy 93.980409 -451.310375)
			(xy 94.082473 -451.254539) (xy 94.188147 -451.205878) (xy 94.296926 -451.164624) (xy 94.408291 -451.130973)
			(xy 94.521714 -451.105085) (xy 94.636651 -451.087084) (xy 94.752557 -451.077055) (xy 94.868879 -451.075047)
			(xy 94.985062 -451.081069) (xy 95.100553 -451.095092) (xy 95.214801 -451.11705) (xy 95.327262 -451.146837)
			(xy 95.4374 -451.184312) (xy 95.54469 -451.229297) (xy 95.648621 -451.281576) (xy 95.748697 -451.340901)
			(xy 95.844443 -451.406989) (xy 95.9354 -451.479525) (xy 96.021136 -451.558164) (xy 96.101243 -451.64253)
			(xy 96.175339 -451.732222) (xy 96.243069 -451.826812) (xy 96.304113 -451.92585) (xy 96.358178 -452.028863)
			(xy 96.405008 -452.13536) (xy 96.444379 -452.244835) (xy 96.476103 -452.356765) (xy 96.500029 -452.470617)
			(xy 96.516043 -452.585849) (xy 96.52407 -452.701911) (xy 96.524572 -452.76008) (xy 96.52407 -452.818249)
			(xy 96.516043 -452.934311) (xy 96.500029 -453.049543) (xy 96.476103 -453.163395) (xy 96.444379 -453.275325)
			(xy 96.405008 -453.3848) (xy 96.358178 -453.491297) (xy 96.304113 -453.59431) (xy 96.243069 -453.693348)
			(xy 96.175339 -453.787938) (xy 96.101243 -453.87763) (xy 96.021136 -453.961996) (xy 95.9354 -454.040635)
			(xy 95.844443 -454.113171) (xy 95.748697 -454.179259) (xy 95.648621 -454.238584) (xy 95.54469 -454.290863)
			(xy 95.4374 -454.335848) (xy 95.327262 -454.373323) (xy 95.214801 -454.40311) (xy 95.100553 -454.425068)
			(xy 94.985062 -454.439091) (xy 94.868879 -454.445113) (xy 94.752557 -454.443105) (xy 94.636651 -454.433076)
			(xy 94.521714 -454.415075) (xy 94.408291 -454.389187) (xy 94.296926 -454.355536) (xy 94.188147 -454.314282)
			(xy 94.082473 -454.265621) (xy 93.980409 -454.209785) (xy 93.88244 -454.147042) (xy 93.789033 -454.077688)
			(xy 93.700633 -454.002056) (xy 93.617662 -453.920505) (xy 93.540515 -453.833424) (xy 93.46956 -453.741228)
			(xy 93.405134 -453.644356) (xy 93.347545 -453.543271) (xy 93.297068 -453.438453) (xy 93.253942 -453.330402)
			(xy 93.218373 -453.219634) (xy 93.190531 -453.106675) (xy 93.170549 -452.992065) (xy 93.158522 -452.87635)
			(xy 93.154506 -452.76008) (xy 91.165664 -452.76008) (xy 91.216772 -452.8048) (xy 91.268196 -452.860504)
			(xy 91.313407 -452.921359) (xy 91.351894 -452.986674) (xy 91.38322 -453.05571) (xy 91.40703 -453.127685)
			(xy 91.423055 -453.201783) (xy 91.431114 -453.277164) (xy 91.431618 -453.31507) (xy 91.431114 -453.352976)
			(xy 91.423055 -453.428357) (xy 91.40703 -453.502455) (xy 91.38322 -453.57443) (xy 91.351894 -453.643466)
			(xy 91.313407 -453.708781) (xy 91.268196 -453.769636) (xy 91.216772 -453.82534) (xy 91.159719 -453.875262)
			(xy 91.097683 -453.918837) (xy 91.031366 -453.955572) (xy 90.96152 -453.985049) (xy 90.888937 -454.006935)
			(xy 90.814439 -454.020982) (xy 90.738869 -454.027031) (xy 90.663085 -454.025012) (xy 90.587945 -454.01495)
			(xy 90.5143 -453.996958) (xy 90.442984 -453.97124) (xy 90.374807 -453.938088) (xy 90.310539 -453.897876)
			(xy 90.25091 -453.851061) (xy 90.196594 -453.798173) (xy 90.148208 -453.739811) (xy 90.1063 -453.676636)
			(xy 90.071344 -453.609365) (xy 90.043737 -453.53876) (xy 90.023791 -453.465619) (xy 90.011732 -453.390774)
			(xy 90.007697 -453.31507) (xy 88.891618 -453.31507) (xy 88.891114 -453.352976) (xy 88.883055 -453.428357)
			(xy 88.86703 -453.502455) (xy 88.84322 -453.57443) (xy 88.811894 -453.643466) (xy 88.773407 -453.708781)
			(xy 88.728196 -453.769636) (xy 88.676772 -453.82534) (xy 88.619719 -453.875262) (xy 88.557683 -453.918837)
			(xy 88.491366 -453.955572) (xy 88.42152 -453.985049) (xy 88.348937 -454.006935) (xy 88.274439 -454.020982)
			(xy 88.198869 -454.027031) (xy 88.123085 -454.025012) (xy 88.047945 -454.01495) (xy 87.9743 -453.996958)
			(xy 87.902984 -453.97124) (xy 87.834807 -453.938088) (xy 87.770539 -453.897876) (xy 87.71091 -453.851061)
			(xy 87.656594 -453.798173) (xy 87.608208 -453.739811) (xy 87.5663 -453.676636) (xy 87.531344 -453.609365)
			(xy 87.503737 -453.53876) (xy 87.483791 -453.465619) (xy 87.471732 -453.390774) (xy 87.467697 -453.31507)
			(xy 86.351618 -453.31507) (xy 86.351114 -453.352976) (xy 86.343055 -453.428357) (xy 86.32703 -453.502455)
			(xy 86.30322 -453.57443) (xy 86.271894 -453.643466) (xy 86.233407 -453.708781) (xy 86.188196 -453.769636)
			(xy 86.136772 -453.82534) (xy 86.079719 -453.875262) (xy 86.017683 -453.918837) (xy 85.951366 -453.955572)
			(xy 85.88152 -453.985049) (xy 85.808937 -454.006935) (xy 85.734439 -454.020982) (xy 85.658869 -454.027031)
			(xy 85.583085 -454.025012) (xy 85.507945 -454.01495) (xy 85.4343 -453.996958) (xy 85.362984 -453.97124)
			(xy 85.294807 -453.938088) (xy 85.230539 -453.897876) (xy 85.17091 -453.851061) (xy 85.116594 -453.798173)
			(xy 85.068208 -453.739811) (xy 85.0263 -453.676636) (xy 84.991344 -453.609365) (xy 84.963737 -453.53876)
			(xy 84.943791 -453.465619) (xy 84.931732 -453.390774) (xy 84.927697 -453.31507) (xy 62.265544 -453.31507)
			(xy 62.259599 -453.320272) (xy 62.197563 -453.363847) (xy 62.131246 -453.400582) (xy 62.0614 -453.430059)
			(xy 61.988817 -453.451945) (xy 61.914319 -453.465992) (xy 61.838749 -453.472041) (xy 61.762965 -453.470022)
			(xy 61.687825 -453.45996) (xy 61.61418 -453.441968) (xy 61.542864 -453.41625) (xy 61.474687 -453.383098)
			(xy 61.410419 -453.342886) (xy 61.35079 -453.296071) (xy 61.296474 -453.243183) (xy 61.248088 -453.184821)
			(xy 61.20618 -453.121646) (xy 61.171224 -453.054375) (xy 61.143617 -452.98377) (xy 61.123671 -452.910629)
			(xy 61.111612 -452.835784) (xy 61.107577 -452.76008) (xy 59.991498 -452.76008) (xy 59.990994 -452.797986)
			(xy 59.982935 -452.873367) (xy 59.96691 -452.947465) (xy 59.9431 -453.01944) (xy 59.911774 -453.088476)
			(xy 59.873287 -453.153791) (xy 59.828076 -453.214646) (xy 59.776652 -453.27035) (xy 59.719599 -453.320272)
			(xy 59.657563 -453.363847) (xy 59.591246 -453.400582) (xy 59.5214 -453.430059) (xy 59.448817 -453.451945)
			(xy 59.374319 -453.465992) (xy 59.298749 -453.472041) (xy 59.222965 -453.470022) (xy 59.147825 -453.45996)
			(xy 59.07418 -453.441968) (xy 59.002864 -453.41625) (xy 58.934687 -453.383098) (xy 58.870419 -453.342886)
			(xy 58.81079 -453.296071) (xy 58.756474 -453.243183) (xy 58.708088 -453.184821) (xy 58.66618 -453.121646)
			(xy 58.631224 -453.054375) (xy 58.603617 -452.98377) (xy 58.583671 -452.910629) (xy 58.571612 -452.835784)
			(xy 58.567577 -452.76008) (xy 57.451498 -452.76008) (xy 57.450994 -452.797986) (xy 57.442935 -452.873367)
			(xy 57.42691 -452.947465) (xy 57.4031 -453.01944) (xy 57.371774 -453.088476) (xy 57.333287 -453.153791)
			(xy 57.288076 -453.214646) (xy 57.236652 -453.27035) (xy 57.179599 -453.320272) (xy 57.117563 -453.363847)
			(xy 57.051246 -453.400582) (xy 56.9814 -453.430059) (xy 56.908817 -453.451945) (xy 56.834319 -453.465992)
			(xy 56.758749 -453.472041) (xy 56.682965 -453.470022) (xy 56.607825 -453.45996) (xy 56.53418 -453.441968)
			(xy 56.462864 -453.41625) (xy 56.394687 -453.383098) (xy 56.330419 -453.342886) (xy 56.27079 -453.296071)
			(xy 56.216474 -453.243183) (xy 56.168088 -453.184821) (xy 56.12618 -453.121646) (xy 56.091224 -453.054375)
			(xy 56.063617 -452.98377) (xy 56.043671 -452.910629) (xy 56.031612 -452.835784) (xy 56.027577 -452.76008)
			(xy 54.911498 -452.76008) (xy 54.910994 -452.797986) (xy 54.902935 -452.873367) (xy 54.88691 -452.947465)
			(xy 54.8631 -453.01944) (xy 54.831774 -453.088476) (xy 54.793287 -453.153791) (xy 54.748076 -453.214646)
			(xy 54.696652 -453.27035) (xy 54.639599 -453.320272) (xy 54.577563 -453.363847) (xy 54.511246 -453.400582)
			(xy 54.4414 -453.430059) (xy 54.368817 -453.451945) (xy 54.294319 -453.465992) (xy 54.218749 -453.472041)
			(xy 54.142965 -453.470022) (xy 54.067825 -453.45996) (xy 53.99418 -453.441968) (xy 53.922864 -453.41625)
			(xy 53.854687 -453.383098) (xy 53.790419 -453.342886) (xy 53.73079 -453.296071) (xy 53.676474 -453.243183)
			(xy 53.628088 -453.184821) (xy 53.58618 -453.121646) (xy 53.551224 -453.054375) (xy 53.523617 -452.98377)
			(xy 53.503671 -452.910629) (xy 53.491612 -452.835784) (xy 53.487577 -452.76008) (xy 52.371498 -452.76008)
			(xy 52.370994 -452.797986) (xy 52.362935 -452.873367) (xy 52.34691 -452.947465) (xy 52.3231 -453.01944)
			(xy 52.291774 -453.088476) (xy 52.253287 -453.153791) (xy 52.208076 -453.214646) (xy 52.156652 -453.27035)
			(xy 52.099599 -453.320272) (xy 52.037563 -453.363847) (xy 51.971246 -453.400582) (xy 51.9014 -453.430059)
			(xy 51.828817 -453.451945) (xy 51.754319 -453.465992) (xy 51.678749 -453.472041) (xy 51.602965 -453.470022)
			(xy 51.527825 -453.45996) (xy 51.45418 -453.441968) (xy 51.382864 -453.41625) (xy 51.314687 -453.383098)
			(xy 51.250419 -453.342886) (xy 51.19079 -453.296071) (xy 51.136474 -453.243183) (xy 51.088088 -453.184821)
			(xy 51.04618 -453.121646) (xy 51.011224 -453.054375) (xy 50.983617 -452.98377) (xy 50.963671 -452.910629)
			(xy 50.951612 -452.835784) (xy 50.947577 -452.76008) (xy 49.831498 -452.76008) (xy 49.830994 -452.797986)
			(xy 49.822935 -452.873367) (xy 49.80691 -452.947465) (xy 49.7831 -453.01944) (xy 49.751774 -453.088476)
			(xy 49.713287 -453.153791) (xy 49.668076 -453.214646) (xy 49.616652 -453.27035) (xy 49.559599 -453.320272)
			(xy 49.497563 -453.363847) (xy 49.431246 -453.400582) (xy 49.3614 -453.430059) (xy 49.288817 -453.451945)
			(xy 49.214319 -453.465992) (xy 49.138749 -453.472041) (xy 49.062965 -453.470022) (xy 48.987825 -453.45996)
			(xy 48.91418 -453.441968) (xy 48.842864 -453.41625) (xy 48.774687 -453.383098) (xy 48.710419 -453.342886)
			(xy 48.65079 -453.296071) (xy 48.596474 -453.243183) (xy 48.548088 -453.184821) (xy 48.50618 -453.121646)
			(xy 48.471224 -453.054375) (xy 48.443617 -452.98377) (xy 48.423671 -452.910629) (xy 48.411612 -452.835784)
			(xy 48.407577 -452.76008) (xy 47.291498 -452.76008) (xy 47.290994 -452.797986) (xy 47.282935 -452.873367)
			(xy 47.26691 -452.947465) (xy 47.2431 -453.01944) (xy 47.211774 -453.088476) (xy 47.173287 -453.153791)
			(xy 47.128076 -453.214646) (xy 47.076652 -453.27035) (xy 47.019599 -453.320272) (xy 46.957563 -453.363847)
			(xy 46.891246 -453.400582) (xy 46.8214 -453.430059) (xy 46.748817 -453.451945) (xy 46.674319 -453.465992)
			(xy 46.598749 -453.472041) (xy 46.522965 -453.470022) (xy 46.447825 -453.45996) (xy 46.37418 -453.441968)
			(xy 46.302864 -453.41625) (xy 46.234687 -453.383098) (xy 46.170419 -453.342886) (xy 46.11079 -453.296071)
			(xy 46.056474 -453.243183) (xy 46.008088 -453.184821) (xy 45.96618 -453.121646) (xy 45.931224 -453.054375)
			(xy 45.903617 -452.98377) (xy 45.883671 -452.910629) (xy 45.871612 -452.835784) (xy 45.867577 -452.76008)
			(xy 44.751244 -452.76008) (xy 44.751244 -453.471788) (xy 43.328336 -453.471788) (xy 43.328336 -452.048372)
			(xy 43.055152 -452.048372) (xy 43.014974 -452.139744) (xy 42.961022 -452.24254) (xy 42.900108 -452.341368)
			(xy 42.83252 -452.435759) (xy 42.758581 -452.525261) (xy 42.678643 -452.609449) (xy 42.593088 -452.687922)
			(xy 42.502322 -452.760305) (xy 42.406779 -452.826254) (xy 42.306914 -452.885454) (xy 42.203202 -452.937623)
			(xy 42.096139 -452.982512) (xy 41.986233 -453.019908) (xy 41.874009 -453.049633) (xy 41.760003 -453.071544)
			(xy 41.644756 -453.085537) (xy 41.528818 -453.091546) (xy 41.412742 -453.089543) (xy 41.29708 -453.079535)
			(xy 41.182385 -453.061572) (xy 41.069202 -453.035739) (xy 40.958071 -453.002159) (xy 40.849522 -452.960991)
			(xy 40.744072 -452.912433) (xy 40.642223 -452.856716) (xy 40.54446 -452.794104) (xy 40.45125 -452.724897)
			(xy 40.363037 -452.649424) (xy 40.280241 -452.568045) (xy 40.203257 -452.481148) (xy 40.132452 -452.389147)
			(xy 40.068162 -452.29248) (xy 40.010695 -452.191608) (xy 39.960324 -452.087011) (xy 39.917289 -451.979188)
			(xy 39.881795 -451.868654) (xy 39.854012 -451.755934) (xy 39.834072 -451.641566) (xy 39.82207 -451.526094)
			(xy 39.818063 -451.41007) (xy 36.442855 -451.41007) (xy 36.4555 -451.454513) (xy 36.471468 -451.539933)
			(xy 36.479486 -451.626462) (xy 36.479988 -451.669912) (xy 36.479486 -451.713362) (xy 36.471468 -451.799891)
			(xy 36.4555 -451.885311) (xy 36.431719 -451.968893) (xy 36.400327 -452.049925) (xy 36.361593 -452.127714)
			(xy 36.315846 -452.201598) (xy 36.263477 -452.270945) (xy 36.204933 -452.335165) (xy 36.140713 -452.393709)
			(xy 36.071366 -452.446078) (xy 35.997482 -452.491825) (xy 35.919693 -452.530559) (xy 35.838661 -452.561951)
			(xy 35.755079 -452.585732) (xy 35.669659 -452.6017) (xy 35.58313 -452.609718) (xy 35.49623 -452.609718)
			(xy 35.409701 -452.6017) (xy 35.324281 -452.585732) (xy 35.240699 -452.561951) (xy 35.159667 -452.530559)
			(xy 35.081878 -452.491825) (xy 35.007994 -452.446078) (xy 34.938647 -452.393709) (xy 34.874427 -452.335165)
			(xy 34.815883 -452.270945) (xy 34.763514 -452.201598) (xy 34.717767 -452.127714) (xy 34.679033 -452.049925)
			(xy 34.647641 -451.968893) (xy 34.62386 -451.885311) (xy 34.607892 -451.799891) (xy 34.599874 -451.713362)
			(xy 31.79826 -451.713362) (xy 31.79826 -454.209889) (xy 34.598818 -454.209889) (xy 34.602752 -454.123939)
			(xy 34.614523 -454.038708) (xy 34.634029 -453.954909) (xy 34.661109 -453.873242) (xy 34.695537 -453.79439)
			(xy 34.737023 -453.719013) (xy 34.785222 -453.647741) (xy 34.83973 -453.58117) (xy 34.900091 -453.519856)
			(xy 34.965801 -453.464313) (xy 35.03631 -453.415005) (xy 35.111029 -453.372343) (xy 35.189332 -453.336686)
			(xy 35.270565 -453.308331) (xy 35.354049 -453.287515) (xy 35.439085 -453.274413) (xy 35.524963 -453.269133)
			(xy 35.610964 -453.27172) (xy 35.696369 -453.282153) (xy 35.780464 -453.300344) (xy 35.862545 -453.32614)
			(xy 35.941927 -453.359328) (xy 36.017945 -453.399627) (xy 36.089964 -453.446703) (xy 36.157381 -453.500161)
			(xy 36.219634 -453.559554) (xy 36.2762 -453.624385) (xy 36.326607 -453.694113) (xy 36.370434 -453.768153)
			(xy 36.38931 -453.806814) (xy 36.405058 -453.839834) (xy 36.467034 -453.879204) (xy 37.323776 -453.879204)
			(xy 40.069516 -456.624944) (xy 40.069516 -457.216002) (xy 40.082216 -457.242164) (xy 40.09429 -457.268214)
			(xy 40.111295 -457.323054) (xy 40.119892 -457.379823) (xy 40.119888 -457.437239) (xy 40.111281 -457.494006)
			(xy 40.094268 -457.548843) (xy 40.082216 -457.574904) (xy 40.069516 -457.601066) (xy 40.069516 -458.40396)
			(xy 40.070009 -458.426526) (xy 40.078023 -458.470942) (xy 40.093753 -458.513245) (xy 40.116706 -458.552107)
			(xy 40.146159 -458.586305) (xy 40.181188 -458.614765) (xy 40.220692 -458.636594) (xy 40.263429 -458.651105)
			(xy 40.308056 -458.657842) (xy 40.330628 -458.657706) (xy 40.34536 -458.657452) (xy 41.18356 -458.657452)
			(xy 41.215521 -458.65801) (xy 41.278941 -458.666018) (xy 41.340857 -458.68191) (xy 41.400292 -458.705438)
			(xy 41.45631 -458.736231) (xy 41.508026 -458.773801) (xy 41.554626 -458.817557) (xy 41.595373 -458.866809)
			(xy 41.629626 -458.92078) (xy 41.656845 -458.978619) (xy 41.676599 -459.039413) (xy 41.688578 -459.102203)
			(xy 41.692592 -459.166) (xy 41.688578 -459.229797) (xy 41.676599 -459.292587) (xy 41.656845 -459.353381)
			(xy 41.629626 -459.41122) (xy 41.595373 -459.465191) (xy 41.554626 -459.514443) (xy 41.508026 -459.558199)
			(xy 41.45631 -459.595769) (xy 41.400292 -459.626562) (xy 41.340857 -459.65009) (xy 41.278941 -459.665982)
			(xy 41.215521 -459.67399) (xy 41.18356 -459.674468) (xy 40.34536 -459.674468) (xy 40.312658 -459.673968)
			(xy 40.247794 -459.66557) (xy 40.184544 -459.648918) (xy 40.123955 -459.624286) (xy 40.067027 -459.592083)
			(xy 40.04056 -459.572868) (xy 40.006778 -459.547468) (xy 39.189152 -459.547468) (xy 39.189152 -458.784452)
			(xy 39.214552 -458.784452) (xy 39.214552 -458.571854) (xy 39.4081 -458.378306) (xy 39.4081 -457.601066)
			(xy 39.3954 -457.574904) (xy 39.383375 -457.548832) (xy 39.366362 -457.493999) (xy 39.357756 -457.437236)
			(xy 39.357752 -457.379825) (xy 39.366349 -457.32306) (xy 39.383353 -457.268225) (xy 39.3954 -457.242164)
			(xy 39.4081 -457.216002) (xy 39.4081 -456.898756) (xy 37.049964 -454.54062) (xy 36.467034 -454.54062)
			(xy 36.405058 -454.57999) (xy 36.38931 -454.61301) (xy 36.370424 -454.651666) (xy 36.326595 -454.725706)
			(xy 36.276186 -454.795432) (xy 36.219619 -454.860262) (xy 36.157365 -454.919653) (xy 36.089946 -454.97311)
			(xy 36.017926 -455.020184) (xy 35.941907 -455.060482) (xy 35.862525 -455.093667) (xy 35.780443 -455.119462)
			(xy 35.696347 -455.137651) (xy 35.610942 -455.148081) (xy 35.524941 -455.150667) (xy 35.439064 -455.145385)
			(xy 35.354028 -455.13228) (xy 35.270545 -455.111463) (xy 35.189312 -455.083106) (xy 35.11101 -455.047447)
			(xy 35.036292 -455.004784) (xy 34.965784 -454.955474) (xy 34.900075 -454.899929) (xy 34.839715 -454.838614)
			(xy 34.785209 -454.772042) (xy 34.737012 -454.700768) (xy 34.695527 -454.62539) (xy 34.661102 -454.546538)
			(xy 34.634023 -454.46487) (xy 34.614519 -454.38107) (xy 34.602751 -454.295839) (xy 34.598818 -454.209889)
			(xy 31.79826 -454.209889) (xy 31.79826 -456.793362) (xy 34.599874 -456.793362) (xy 34.599874 -456.706462)
			(xy 34.607892 -456.619933) (xy 34.62386 -456.534513) (xy 34.647641 -456.450931) (xy 34.679033 -456.369899)
			(xy 34.717767 -456.29211) (xy 34.763514 -456.218226) (xy 34.815883 -456.148879) (xy 34.874427 -456.084659)
			(xy 34.938647 -456.026115) (xy 35.007994 -455.973746) (xy 35.081878 -455.927999) (xy 35.159667 -455.889265)
			(xy 35.240699 -455.857873) (xy 35.324281 -455.834092) (xy 35.409701 -455.818124) (xy 35.49623 -455.810106)
			(xy 35.58313 -455.810106) (xy 35.669659 -455.818124) (xy 35.755079 -455.834092) (xy 35.838661 -455.857873)
			(xy 35.919693 -455.889265) (xy 35.997482 -455.927999) (xy 36.071366 -455.973746) (xy 36.140713 -456.026115)
			(xy 36.204933 -456.084659) (xy 36.263477 -456.148879) (xy 36.315846 -456.218226) (xy 36.361593 -456.29211)
			(xy 36.400327 -456.369899) (xy 36.431719 -456.450931) (xy 36.4555 -456.534513) (xy 36.471468 -456.619933)
			(xy 36.479486 -456.706462) (xy 36.479988 -456.749912) (xy 36.479486 -456.793362) (xy 36.471468 -456.879891)
			(xy 36.4555 -456.965311) (xy 36.431719 -457.048893) (xy 36.400327 -457.129925) (xy 36.361593 -457.207714)
			(xy 36.315846 -457.281598) (xy 36.263477 -457.350945) (xy 36.204933 -457.415165) (xy 36.140713 -457.473709)
			(xy 36.071366 -457.526078) (xy 35.997482 -457.571825) (xy 35.919693 -457.610559) (xy 35.838661 -457.641951)
			(xy 35.755079 -457.665732) (xy 35.669659 -457.6817) (xy 35.58313 -457.689718) (xy 35.49623 -457.689718)
			(xy 35.409701 -457.6817) (xy 35.324281 -457.665732) (xy 35.240699 -457.641951) (xy 35.159667 -457.610559)
			(xy 35.081878 -457.571825) (xy 35.007994 -457.526078) (xy 34.938647 -457.473709) (xy 34.874427 -457.415165)
			(xy 34.815883 -457.350945) (xy 34.763514 -457.281598) (xy 34.717767 -457.207714) (xy 34.679033 -457.129925)
			(xy 34.647641 -457.048893) (xy 34.62386 -456.965311) (xy 34.607892 -456.879891) (xy 34.599874 -456.793362)
			(xy 31.79826 -456.793362) (xy 31.79826 -456.91679) (xy 32.313626 -457.432156) (xy 34.182304 -459.30058)
			(xy 34.199227 -459.316118) (xy 34.237561 -459.341431) (xy 34.27982 -459.359442) (xy 34.324628 -459.369566)
			(xy 34.370525 -459.371473) (xy 34.416018 -459.3651) (xy 34.459626 -459.350656) (xy 34.499927 -459.32861)
			(xy 34.535611 -459.29968) (xy 34.565514 -459.264809) (xy 34.588664 -459.225131) (xy 34.604307 -459.181939)
			(xy 34.608516 -459.159356) (xy 34.615592 -459.113076) (xy 34.637729 -459.022102) (xy 34.652712 -458.977746)
			(xy 34.666308 -458.940347) (xy 34.698964 -458.867771) (xy 34.737638 -458.798216) (xy 34.782052 -458.732178)
			(xy 34.806636 -458.700886) (xy 34.833601 -458.668084) (xy 34.892548 -458.606956) (xy 34.956765 -458.551391)
			(xy 35.025729 -458.501841) (xy 35.09888 -458.458709) (xy 35.175621 -458.422348) (xy 35.255327 -458.393052)
			(xy 35.337349 -458.37106) (xy 35.421021 -458.356552) (xy 35.505659 -458.349645) (xy 35.590575 -458.350396)
			(xy 35.675078 -458.358799) (xy 35.758479 -458.374786) (xy 35.8401 -458.398225) (xy 35.919275 -458.428927)
			(xy 35.995361 -458.466641) (xy 36.067737 -458.51106) (xy 36.135814 -458.561822) (xy 36.199038 -458.618515)
			(xy 36.256894 -458.680676) (xy 36.308911 -458.7478) (xy 36.354665 -458.819339) (xy 36.374578 -458.856842)
			(xy 36.390326 -458.887068) (xy 36.503864 -458.959204) (xy 38.188392 -458.959204) (xy 39.805356 -460.576168)
			(xy 39.805356 -460.635096) (xy 39.805899 -460.651747) (xy 39.814515 -460.683914) (xy 39.831162 -460.712757)
			(xy 39.854705 -460.736309) (xy 39.883541 -460.752967) (xy 39.915705 -460.761595) (xy 39.932356 -460.762096)
			(xy 39.969694 -460.762096) (xy 40.000936 -460.74203) (xy 40.010672 -460.735858) (xy 40.030619 -460.724297)
			(xy 40.040814 -460.718916) (xy 40.06827 -460.705221) (xy 40.125757 -460.683777) (xy 40.185407 -460.669409)
			(xy 40.246354 -460.662327) (xy 40.277034 -460.66202) (xy 40.89527 -460.664306) (xy 41.397174 -460.666338)
			(xy 41.404794 -460.665322) (xy 41.434365 -460.662205) (xy 41.493828 -460.662076) (xy 41.523412 -460.665068)
			(xy 41.556635 -460.669435) (xy 41.621619 -460.685784) (xy 41.683892 -460.710527) (xy 41.742376 -460.743235)
			(xy 41.769538 -460.762858) (xy 41.796283 -460.783494) (xy 41.844609 -460.830694) (xy 41.886258 -460.883879)
			(xy 41.920498 -460.942111) (xy 41.946724 -461.004365) (xy 41.964474 -461.069543) (xy 41.973437 -461.136498)
			(xy 41.974008 -461.170274) (xy 41.974008 -461.1751) (xy 41.973463 -461.208758) (xy 41.96458 -461.275484)
			(xy 41.946968 -461.340455) (xy 41.920937 -461.402534) (xy 41.886941 -461.460634) (xy 41.845575 -461.51374)
			(xy 41.797562 -461.560922) (xy 41.743743 -461.601356) (xy 41.714674 -461.61833) (xy 41.690596 -461.631411)
			(xy 41.640194 -461.652921) (xy 41.61409 -461.661256) (xy 41.57733 -461.671752) (xy 41.501694 -461.682845)
			(xy 41.463468 -461.683354) (xy 40.88384 -461.681068) (xy 40.732202 -461.68056) (xy 40.715476 -461.680958)
			(xy 40.683123 -461.689443) (xy 40.654085 -461.706041) (xy 40.630356 -461.729613) (xy 40.613565 -461.758541)
			(xy 40.604866 -461.790837) (xy 40.60444 -461.80756) (xy 40.60444 -461.91043) (xy 40.630094 -461.936084)
			(xy 40.630094 -462.170526) (xy 70.882256 -462.170526) (xy 70.882256 -460.977234) (xy 70.882946 -460.941168)
			(xy 70.893269 -460.869777) (xy 70.90283 -460.834994) (xy 70.907656 -460.817468) (xy 70.907656 -460.44358)
			(xy 71.873872 -460.44358) (xy 71.873872 -460.817468) (xy 71.878698 -460.834994) (xy 71.884895 -460.8576)
			(xy 72.293988 -460.8576) (xy 72.293988 -460.132684) (xy 72.294476 -460.099957) (xy 72.302873 -460.035045)
			(xy 72.319526 -459.971745) (xy 72.34416 -459.911104) (xy 72.376368 -459.854123) (xy 72.395588 -459.82763)
			(xy 72.420988 -459.793848) (xy 72.420988 -459.776576) (xy 72.436228 -459.776576) (xy 72.472042 -459.74635)
			(xy 72.497219 -459.725497) (xy 72.551951 -459.689746) (xy 72.610816 -459.661307) (xy 72.672841 -459.640652)
			(xy 72.737003 -459.628121) (xy 72.802242 -459.623921) (xy 72.867481 -459.628121) (xy 72.931643 -459.640652)
			(xy 72.993668 -459.661307) (xy 73.052533 -459.689746) (xy 73.107265 -459.725497) (xy 73.132442 -459.74635)
			(xy 73.168256 -459.776576) (xy 73.183496 -459.776576) (xy 73.183496 -459.793848) (xy 73.208896 -459.82763)
			(xy 73.219564 -459.842362) (xy 73.232666 -459.860324) (xy 73.264069 -459.891793) (xy 73.300465 -459.917322)
			(xy 73.340746 -459.936133) (xy 73.383684 -459.947655) (xy 73.427971 -459.951534) (xy 73.472258 -459.947655)
			(xy 73.515196 -459.936133) (xy 73.555477 -459.917322) (xy 73.591873 -459.891793) (xy 73.623276 -459.860324)
			(xy 73.636378 -459.842362) (xy 73.647046 -459.82763) (xy 73.672192 -459.793848) (xy 73.672192 -459.776576)
			(xy 73.687686 -459.776576) (xy 73.7235 -459.74635) (xy 73.748677 -459.725497) (xy 73.803409 -459.689746)
			(xy 73.862274 -459.661307) (xy 73.924299 -459.640652) (xy 73.988461 -459.628121) (xy 74.0537 -459.623921)
			(xy 74.118939 -459.628121) (xy 74.183101 -459.640652) (xy 74.245126 -459.661307) (xy 74.303991 -459.689746)
			(xy 74.358723 -459.725497) (xy 74.3839 -459.74635) (xy 74.419714 -459.776576) (xy 74.435208 -459.776576)
			(xy 74.435208 -459.793848) (xy 74.460354 -459.82763) (xy 74.479619 -459.854101) (xy 74.511879 -459.911073)
			(xy 74.536561 -459.971714) (xy 74.553255 -460.035022) (xy 74.561686 -460.099948) (xy 74.562208 -460.132684)
			(xy 74.562208 -460.970884) (xy 74.561773 -461.002731) (xy 74.553807 -461.065924) (xy 74.538011 -461.127628)
			(xy 74.514633 -461.186876) (xy 74.484038 -461.24274) (xy 74.446705 -461.294345) (xy 74.403219 -461.340884)
			(xy 74.354261 -461.381627) (xy 74.300598 -461.415936) (xy 74.24307 -461.443275) (xy 74.182579 -461.463214)
			(xy 74.12007 -461.475442) (xy 74.056523 -461.479768) (xy 73.992934 -461.476123) (xy 73.930298 -461.464564)
			(xy 73.869597 -461.445273) (xy 73.811779 -461.418552) (xy 73.757752 -461.384819) (xy 73.708361 -461.344602)
			(xy 73.66438 -461.298531) (xy 73.626497 -461.247328) (xy 73.61047 -461.219804) (xy 73.599156 -461.200488)
			(xy 73.57073 -461.165907) (xy 73.536683 -461.136845) (xy 73.498068 -461.114201) (xy 73.456082 -461.098677)
			(xy 73.412025 -461.090753) (xy 73.367261 -461.090674) (xy 73.323176 -461.098444) (xy 73.281136 -461.113822)
			(xy 73.242443 -461.13633) (xy 73.208294 -461.165274) (xy 73.193656 -461.182212) (xy 73.173353 -461.205827)
			(xy 73.128043 -461.24855) (xy 73.077853 -461.285418) (xy 73.023536 -461.315878) (xy 72.965903 -461.339474)
			(xy 72.90582 -461.355853) (xy 72.844186 -461.364768) (xy 72.781924 -461.366087) (xy 72.719968 -461.359789)
			(xy 72.659245 -461.34597) (xy 72.600665 -461.324836) (xy 72.545106 -461.296703) (xy 72.4934 -461.261993)
			(xy 72.446322 -461.221227) (xy 72.404577 -461.175015) (xy 72.36879 -461.124048) (xy 72.339498 -461.069092)
			(xy 72.317139 -461.010968) (xy 72.302049 -460.950549) (xy 72.294453 -460.888738) (xy 72.293988 -460.8576)
			(xy 71.884895 -460.8576) (xy 71.888234 -460.869782) (xy 71.898565 -460.94117) (xy 71.899272 -460.977234)
			(xy 71.899272 -462.170526) (xy 71.89877 -462.202487) (xy 71.890759 -462.265905) (xy 71.874862 -462.327819)
			(xy 71.85133 -462.387252) (xy 71.820536 -462.443267) (xy 71.782963 -462.494982) (xy 71.739206 -462.541579)
			(xy 71.689953 -462.582324) (xy 71.635982 -462.616575) (xy 71.578143 -462.643792) (xy 71.51735 -462.663545)
			(xy 71.45456 -462.675523) (xy 71.390764 -462.679537) (xy 71.326968 -462.675523) (xy 71.264178 -462.663545)
			(xy 71.203385 -462.643792) (xy 71.145546 -462.616575) (xy 71.091575 -462.582324) (xy 71.042322 -462.541579)
			(xy 70.998565 -462.494982) (xy 70.960992 -462.443267) (xy 70.930198 -462.387252) (xy 70.906666 -462.327819)
			(xy 70.890769 -462.265905) (xy 70.882758 -462.202487) (xy 70.882256 -462.170526) (xy 40.630094 -462.170526)
			(xy 40.630094 -462.752948) (xy 40.08374 -462.752948) (xy 40.067084 -462.753438) (xy 40.034906 -462.762053)
			(xy 40.006056 -462.778707) (xy 39.982502 -462.802262) (xy 39.96585 -462.831113) (xy 39.957237 -462.863292)
			(xy 39.95674 -462.879948) (xy 39.95674 -462.903824) (xy 39.943532 -462.96961) (xy 39.960804 -463.010758)
			(xy 39.966919 -463.024406) (xy 39.984505 -463.048585) (xy 40.007243 -463.067998) (xy 40.03388 -463.081576)
			(xy 40.062949 -463.088569) (xy 40.077898 -463.08899) (xy 40.40505 -463.08899) (xy 40.43668 -463.089482)
			(xy 40.499399 -463.097735) (xy 40.560504 -463.114108) (xy 40.618948 -463.138318) (xy 40.62223 -463.140213)
			(xy 47.82311 -463.140213) (xy 47.82311 -463.059103) (xy 47.83106 -462.978384) (xy 47.846883 -462.898833)
			(xy 47.870428 -462.821217) (xy 47.901467 -462.746281) (xy 47.939702 -462.674749) (xy 47.984764 -462.607309)
			(xy 48.036219 -462.54461) (xy 48.093572 -462.487257) (xy 48.156271 -462.435802) (xy 48.223711 -462.39074)
			(xy 48.295243 -462.352505) (xy 48.370179 -462.321466) (xy 48.447795 -462.297921) (xy 48.527346 -462.282098)
			(xy 48.608065 -462.274148) (xy 48.689175 -462.274148) (xy 48.769894 -462.282098) (xy 48.849445 -462.297921)
			(xy 48.927061 -462.321466) (xy 49.001997 -462.352505) (xy 49.073529 -462.39074) (xy 49.140969 -462.435802)
			(xy 49.203668 -462.487257) (xy 49.261021 -462.54461) (xy 49.312476 -462.607309) (xy 49.357538 -462.674749)
			(xy 49.395773 -462.746281) (xy 49.426812 -462.821217) (xy 49.450357 -462.898833) (xy 49.46618 -462.978384)
			(xy 49.47413 -463.059103) (xy 49.474628 -463.099658) (xy 49.47413 -463.140213) (xy 49.46618 -463.220932)
			(xy 49.450357 -463.300483) (xy 49.426812 -463.378099) (xy 49.395773 -463.453035) (xy 49.357538 -463.524567)
			(xy 49.312476 -463.592007) (xy 49.261021 -463.654706) (xy 49.203668 -463.712059) (xy 49.140969 -463.763514)
			(xy 49.073529 -463.808576) (xy 49.001997 -463.846811) (xy 48.927061 -463.87785) (xy 48.849445 -463.901395)
			(xy 48.769894 -463.917218) (xy 48.689175 -463.925168) (xy 48.608065 -463.925168) (xy 48.527346 -463.917218)
			(xy 48.447795 -463.901395) (xy 48.370179 -463.87785) (xy 48.295243 -463.846811) (xy 48.223711 -463.808576)
			(xy 48.156271 -463.763514) (xy 48.093572 -463.712059) (xy 48.036219 -463.654706) (xy 47.984764 -463.592007)
			(xy 47.939702 -463.524567) (xy 47.901467 -463.453035) (xy 47.870428 -463.378099) (xy 47.846883 -463.300483)
			(xy 47.83106 -463.220932) (xy 47.82311 -463.140213) (xy 40.62223 -463.140213) (xy 40.67373 -463.169952)
			(xy 40.723913 -463.208468) (xy 40.768637 -463.253207) (xy 40.807137 -463.303403) (xy 40.823388 -463.330544)
			(xy 40.838729 -463.358189) (xy 40.86289 -463.416616) (xy 40.879222 -463.477695) (xy 40.887446 -463.540382)
			(xy 40.88742 -463.603607) (xy 40.879146 -463.666289) (xy 40.862765 -463.727354) (xy 40.838557 -463.785761)
			(xy 40.806935 -463.84051) (xy 40.768441 -463.890666) (xy 40.723732 -463.935371) (xy 40.673573 -463.97386)
			(xy 40.618821 -464.005477) (xy 40.560412 -464.029679) (xy 40.499344 -464.046055) (xy 40.436662 -464.054323)
			(xy 40.40505 -464.054952) (xy 40.285416 -464.054952) (xy 40.263034 -464.056447) (xy 40.219277 -464.066311)
			(xy 40.177927 -464.083692) (xy 40.140263 -464.108051) (xy 40.107451 -464.138635) (xy 40.080508 -464.174495)
			(xy 40.060267 -464.214524) (xy 40.047355 -464.25748) (xy 40.042172 -464.302034) (xy 40.0431 -464.324446)
			(xy 40.044878 -464.357466) (xy 40.045096 -464.373174) (xy 40.043825 -464.404565) (xy 40.042338 -464.420204)
			(xy 40.041628 -464.443137) (xy 40.047492 -464.488639) (xy 40.054342 -464.51012) (xy 86.39887 -464.51012)
			(xy 86.402874 -464.310022) (xy 86.414881 -464.110244) (xy 86.434872 -463.911107) (xy 86.462814 -463.712929)
			(xy 86.498662 -463.516027) (xy 86.54236 -463.320718) (xy 86.593837 -463.127313) (xy 86.653011 -462.936123)
			(xy 86.719787 -462.747453) (xy 86.794059 -462.561606) (xy 86.875706 -462.378879) (xy 86.964599 -462.199566)
			(xy 87.060595 -462.023952) (xy 87.16354 -461.85232) (xy 87.27327 -461.684944) (xy 87.389608 -461.522093)
			(xy 87.512369 -461.364026) (xy 87.641356 -461.210998) (xy 87.776363 -461.063253) (xy 87.917172 -460.921027)
			(xy 88.063559 -460.78455) (xy 88.215289 -460.654038) (xy 88.37212 -460.529702) (xy 88.533799 -460.41174)
			(xy 88.700069 -460.300341) (xy 88.870662 -460.195684) (xy 89.045306 -460.097936) (xy 89.223722 -460.007253)
			(xy 89.405622 -459.923782) (xy 89.590717 -459.847655) (xy 89.778709 -459.778995) (xy 89.969298 -459.717911)
			(xy 90.162178 -459.664501) (xy 90.35704 -459.618852) (xy 90.553573 -459.581035) (xy 90.751462 -459.551111)
			(xy 90.950389 -459.529129) (xy 91.150037 -459.515124) (xy 91.350085 -459.509118) (xy 91.550213 -459.51112)
			(xy 91.750101 -459.521128) (xy 91.949428 -459.539125) (xy 92.147876 -459.565083) (xy 92.345126 -459.59896)
			(xy 92.540863 -459.640702) (xy 92.734773 -459.690241) (xy 92.926546 -459.747499) (xy 93.115875 -459.812384)
			(xy 93.302455 -459.884792) (xy 93.48599 -459.964608) (xy 93.666184 -460.051702) (xy 93.842749 -460.145936)
			(xy 94.015402 -460.247159) (xy 94.183867 -460.355209) (xy 94.347875 -460.469912) (xy 94.507162 -460.591086)
			(xy 94.661473 -460.718535) (xy 94.810561 -460.852056) (xy 94.954188 -460.991436) (xy 95.092124 -461.13645)
			(xy 95.224147 -461.286867) (xy 95.350046 -461.442445) (xy 95.46962 -461.602937) (xy 95.582676 -461.768083)
			(xy 95.689035 -461.937621) (xy 95.788526 -462.111279) (xy 95.880989 -462.288778) (xy 95.966276 -462.469834)
			(xy 96.044251 -462.654158) (xy 96.114788 -462.841454) (xy 96.177776 -463.031422) (xy 96.233113 -463.223758)
			(xy 96.28071 -463.418154) (xy 96.320491 -463.614299) (xy 96.352393 -463.811878) (xy 96.376364 -464.010575)
			(xy 96.392366 -464.210073) (xy 96.400373 -464.410051) (xy 96.400874 -464.51012) (xy 96.400373 -464.610189)
			(xy 96.392366 -464.810167) (xy 96.376364 -465.009665) (xy 96.352393 -465.208362) (xy 96.320491 -465.405941)
			(xy 96.28071 -465.602086) (xy 96.233113 -465.796482) (xy 96.177776 -465.988818) (xy 96.114788 -466.178786)
			(xy 96.044251 -466.366082) (xy 95.966276 -466.550406) (xy 95.880989 -466.731462) (xy 95.788526 -466.908961)
			(xy 95.689035 -467.082619) (xy 95.582676 -467.252157) (xy 95.46962 -467.417303) (xy 95.350046 -467.577795)
			(xy 95.224147 -467.733373) (xy 95.092124 -467.88379) (xy 94.954188 -468.028804) (xy 94.810561 -468.168184)
			(xy 94.661473 -468.301705) (xy 94.507162 -468.429154) (xy 94.347875 -468.550328) (xy 94.183867 -468.665031)
			(xy 94.015402 -468.773081) (xy 93.842749 -468.874304) (xy 93.666184 -468.968538) (xy 93.48599 -469.055632)
			(xy 93.302455 -469.135448) (xy 93.115875 -469.207856) (xy 92.926546 -469.272741) (xy 92.734773 -469.329999)
			(xy 92.540863 -469.379538) (xy 92.345126 -469.42128) (xy 92.147876 -469.455157) (xy 91.949428 -469.481115)
			(xy 91.750101 -469.499112) (xy 91.550213 -469.50912) (xy 91.350085 -469.511122) (xy 91.150037 -469.505116)
			(xy 90.950389 -469.491111) (xy 90.751462 -469.469129) (xy 90.553573 -469.439205) (xy 90.35704 -469.401388)
			(xy 90.162178 -469.355739) (xy 89.969298 -469.302329) (xy 89.778709 -469.241245) (xy 89.590717 -469.172585)
			(xy 89.405622 -469.096458) (xy 89.223722 -469.012987) (xy 89.045306 -468.922304) (xy 88.870662 -468.824556)
			(xy 88.700069 -468.719899) (xy 88.533799 -468.6085) (xy 88.37212 -468.490538) (xy 88.215289 -468.366202)
			(xy 88.063559 -468.23569) (xy 87.917172 -468.099213) (xy 87.776363 -467.956987) (xy 87.641356 -467.809242)
			(xy 87.512369 -467.656214) (xy 87.389608 -467.498147) (xy 87.27327 -467.335296) (xy 87.16354 -467.16792)
			(xy 87.060595 -466.996288) (xy 86.964599 -466.820674) (xy 86.875706 -466.641361) (xy 86.794059 -466.458634)
			(xy 86.719787 -466.272787) (xy 86.653011 -466.084117) (xy 86.593837 -465.892927) (xy 86.54236 -465.699522)
			(xy 86.498662 -465.504213) (xy 86.462814 -465.307311) (xy 86.434872 -465.109133) (xy 86.414881 -464.909996)
			(xy 86.402874 -464.710218) (xy 86.39887 -464.51012) (xy 40.054342 -464.51012) (xy 40.061431 -464.532349)
			(xy 40.082992 -464.572845) (xy 40.111474 -464.608811) (xy 40.145952 -464.639078) (xy 40.185304 -464.662663)
			(xy 40.228251 -464.678797) (xy 40.273398 -464.686957) (xy 40.296338 -464.687412) (xy 40.594788 -464.687412)
			(xy 40.626419 -464.687906) (xy 40.689141 -464.696162) (xy 40.750248 -464.712535) (xy 40.808696 -464.736743)
			(xy 40.863483 -464.768373) (xy 40.913674 -464.806885) (xy 40.958408 -464.851617) (xy 40.99692 -464.901807)
			(xy 41.028552 -464.956593) (xy 41.052762 -465.01504) (xy 41.069135 -465.076147) (xy 41.077393 -465.138869)
			(xy 41.077393 -465.202131) (xy 41.069135 -465.264853) (xy 41.052762 -465.32596) (xy 41.028552 -465.384407)
			(xy 40.99692 -465.439193) (xy 40.958408 -465.489383) (xy 40.913674 -465.534115) (xy 40.863483 -465.572627)
			(xy 40.808696 -465.604257) (xy 40.750248 -465.628465) (xy 40.689141 -465.644838) (xy 40.626419 -465.653094)
			(xy 40.594788 -465.653628) (xy 39.51478 -465.653628) (xy 39.484902 -465.653185) (xy 39.425603 -465.64582)
			(xy 39.367666 -465.631191) (xy 39.311978 -465.609524) (xy 39.25939 -465.581148) (xy 39.210706 -465.546499)
			(xy 39.18839 -465.526628) (xy 39.133272 -465.526628) (xy 39.133272 -465.469224) (xy 39.11219 -465.43722)
			(xy 39.096125 -465.412157) (xy 39.069576 -465.358871) (xy 39.049774 -465.302728) (xy 39.037017 -465.244578)
			(xy 39.031501 -465.185301) (xy 39.031926 -465.155534) (xy 39.032434 -465.145374) (xy 39.033107 -465.122474)
			(xy 39.027192 -465.077047) (xy 39.013233 -465.033415) (xy 38.991681 -464.992991) (xy 38.963233 -464.957084)
			(xy 38.928812 -464.926855) (xy 38.889531 -464.903284) (xy 38.846662 -464.887134) (xy 38.801593 -464.878927)
			(xy 38.778688 -464.87842) (xy 36.397184 -464.87842) (xy 36.2966 -464.928966) (xy 36.279074 -464.951318)
			(xy 36.251834 -464.98517) (xy 36.19207 -465.048248) (xy 36.12674 -465.105544) (xy 36.056403 -465.156568)
			(xy 35.981659 -465.200886) (xy 35.903145 -465.238118) (xy 35.82153 -465.267948) (xy 35.737512 -465.290121)
			(xy 35.651806 -465.304448) (xy 35.565144 -465.310807) (xy 35.478265 -465.309143) (xy 35.39191 -465.299471)
			(xy 35.306816 -465.281873) (xy 35.223708 -465.256499) (xy 35.143295 -465.223566) (xy 35.066264 -465.183355)
			(xy 34.993272 -465.136209) (xy 34.92494 -465.082529) (xy 34.861852 -465.022774) (xy 34.804546 -464.957453)
			(xy 34.753511 -464.887124) (xy 34.709182 -464.812387) (xy 34.671938 -464.733878) (xy 34.642095 -464.652268)
			(xy 34.619909 -464.568253) (xy 34.605569 -464.48255) (xy 34.601912 -464.439254) (xy 34.600558 -464.419599)
			(xy 34.599288 -464.380216) (xy 34.599372 -464.360514) (xy 34.6004 -464.313966) (xy 34.610522 -464.221406)
			(xy 34.629748 -464.130301) (xy 34.657888 -464.041543) (xy 34.694667 -463.956003) (xy 34.71672 -463.914998)
			(xy 34.726683 -463.893731) (xy 34.739495 -463.848555) (xy 34.74379 -463.801794) (xy 34.739419 -463.75504)
			(xy 34.726534 -463.709885) (xy 34.705571 -463.667866) (xy 34.677244 -463.630414) (xy 34.642519 -463.598803)
			(xy 34.602578 -463.574112) (xy 34.558779 -463.557178) (xy 34.512615 -463.548581) (xy 34.489136 -463.547968)
			(xy 34.284158 -463.547968) (xy 31.73857 -461.002126) (xy 31.726435 -460.990668) (xy 31.697556 -460.973962)
			(xy 31.665335 -460.965306) (xy 31.648654 -460.964788) (xy 31.477966 -460.964788) (xy 31.455983 -460.965935)
			(xy 31.41288 -460.974852) (xy 31.371958 -460.991061) (xy 31.334441 -461.014079) (xy 31.30145 -461.043216)
			(xy 31.273973 -461.077602) (xy 31.252831 -461.116207) (xy 31.238656 -461.157878) (xy 31.231873 -461.201367)
			(xy 31.232684 -461.245375) (xy 31.241065 -461.288586) (xy 31.256765 -461.329706) (xy 31.267654 -461.348836)
			(xy 31.292309 -461.391549) (xy 31.333541 -461.481144) (xy 31.34995 -461.527652) (xy 31.363418 -461.568873)
			(xy 31.383615 -461.653214) (xy 31.395959 -461.739056) (xy 31.400346 -461.82567) (xy 31.396738 -461.91232)
			(xy 31.385166 -461.99827) (xy 31.365728 -462.082789) (xy 31.33859 -462.165158) (xy 31.303981 -462.244679)
			(xy 31.262197 -462.320675) (xy 31.213592 -462.392499) (xy 31.158579 -462.459543) (xy 31.097626 -462.521235)
			(xy 31.03125 -462.577053) (xy 30.960017 -462.626521) (xy 30.884531 -462.669218) (xy 30.805433 -462.704783)
			(xy 30.723397 -462.732913) (xy 30.639118 -462.753369) (xy 30.553315 -462.765976) (xy 30.466714 -462.770629)
			(xy 30.380053 -462.767287) (xy 30.294069 -462.755978) (xy 30.209491 -462.736799) (xy 30.127038 -462.709914)
			(xy 30.047412 -462.675549) (xy 29.971289 -462.633998) (xy 29.899315 -462.585613) (xy 29.832103 -462.530806)
			(xy 29.770224 -462.470042) (xy 29.741876 -462.437226) (xy 29.704538 -462.390236) (xy 29.687266 -462.366868)
			(xy 29.583888 -462.31302) (xy 28.37434 -462.31302) (xy 28.350958 -462.313549) (xy 28.304982 -462.322101)
			(xy 28.261349 -462.338923) (xy 28.221531 -462.363447) (xy 28.186874 -462.394844) (xy 28.158549 -462.432055)
			(xy 28.137514 -462.47382) (xy 28.124477 -462.518731) (xy 28.119881 -462.565269) (xy 28.121356 -462.58861)
			(xy 28.122626 -462.609184) (xy 28.12288 -462.61655) (xy 28.12288 -463.41538) (xy 28.122363 -463.446994)
			(xy 28.11411 -463.509681) (xy 28.097746 -463.570755) (xy 28.073549 -463.62917) (xy 28.041935 -463.683927)
			(xy 28.003444 -463.734089) (xy 27.958735 -463.778798) (xy 27.908573 -463.817289) (xy 27.853816 -463.848903)
			(xy 27.795401 -463.8731) (xy 27.734327 -463.889464) (xy 27.67164 -463.897717) (xy 27.608412 -463.897717)
			(xy 27.545725 -463.889464) (xy 27.484651 -463.8731) (xy 27.426236 -463.848903) (xy 27.371479 -463.817289)
			(xy 27.321317 -463.778798) (xy 27.276608 -463.734089) (xy 27.238117 -463.683927) (xy 27.206503 -463.62917)
			(xy 27.182306 -463.570755) (xy 27.165942 -463.509681) (xy 27.157689 -463.446994) (xy 27.157172 -463.41538)
			(xy 27.157172 -462.630012) (xy 27.157426 -462.612994) (xy 27.157934 -462.599024) (xy 27.15895 -462.586578)
			(xy 27.160468 -462.564399) (xy 27.156655 -462.520112) (xy 27.145194 -462.477163) (xy 27.126433 -462.436865)
			(xy 27.100947 -462.400446) (xy 27.069511 -462.369017) (xy 27.033086 -462.343538) (xy 26.992784 -462.324787)
			(xy 26.949833 -462.313335) (xy 26.905544 -462.309532) (xy 26.88336 -462.310988) (xy 26.866314 -462.312368)
			(xy 26.832119 -462.313002) (xy 26.815034 -462.312258) (xy 26.782886 -462.310045) (xy 26.71955 -462.298167)
			(xy 26.658352 -462.277987) (xy 26.600374 -462.249861) (xy 26.573226 -462.232502) (xy 26.541222 -462.21142)
			(xy 26.483818 -462.21142) (xy 26.483818 -462.159096) (xy 26.457402 -462.124806) (xy 26.450544 -462.115662)
			(xy 26.432843 -462.090718) (xy 26.403198 -462.037215) (xy 26.380545 -461.980398) (xy 26.365247 -461.921175)
			(xy 26.357548 -461.860495) (xy 26.357072 -461.829912) (xy 26.357072 -461.067658) (xy 26.357634 -461.034353)
			(xy 26.366796 -460.968376) (xy 26.384941 -460.904285) (xy 26.411723 -460.843297) (xy 26.446634 -460.786569)
			(xy 26.489013 -460.735179) (xy 26.538053 -460.690101) (xy 26.565098 -460.670656) (xy 26.57832 -460.661607)
			(xy 26.605775 -460.645083) (xy 26.619962 -460.637636) (xy 26.650254 -460.622749) (xy 26.714027 -460.600643)
			(xy 26.780259 -460.587639) (xy 26.847656 -460.583993) (xy 26.881328 -460.586328) (xy 26.904073 -460.58781)
			(xy 26.949456 -460.583626) (xy 26.993364 -460.571411) (xy 27.034388 -460.551559) (xy 27.071212 -460.524705)
			(xy 27.102653 -460.491713) (xy 27.127704 -460.453639) (xy 27.14556 -460.411707) (xy 27.155647 -460.367263)
			(xy 27.157172 -460.34452) (xy 27.157172 -460.277972) (xy 27.158188 -460.243174) (xy 27.160474 -460.219806)
			(xy 27.161744 -460.210916) (xy 27.162252 -460.206852) (xy 27.164538 -460.19212) (xy 27.164538 -460.18196)
			(xy 27.164052 -460.165768) (xy 27.155901 -460.134426) (xy 27.140133 -460.106139) (xy 27.117761 -460.082725)
			(xy 27.090221 -460.065686) (xy 27.059282 -460.056118) (xy 27.043126 -460.05496) (xy 25.224232 -460.05496)
			(xy 24.51608 -459.346808) (xy 23.109428 -457.94041) (xy 23.109428 -450.069458) (xy 23.085801 -450.04016)
			(xy 23.043798 -449.977698) (xy 23.008156 -449.9114) (xy 22.979221 -449.841913) (xy 22.957277 -449.769912)
			(xy 22.942535 -449.696098) (xy 22.93514 -449.621192) (xy 22.934676 -449.583556) (xy 22.934676 -445.406272)
			(xy 27.939746 -440.401202) (xy 27.939746 -380.331472) (xy 26.19629 -378.588016) (xy 26.19629 -373.393462)
			(xy 22.540214 -369.737386) (xy 22.540214 -362.914438) (xy 22.543516 -362.914438) (xy 22.543516 -355.258116)
			(xy 22.53869 -355.253544) (xy 22.53869 -347.079824) (xy 21.253196 -345.79433) (xy 12.28725 -345.79433)
			(xy 11.611356 -346.470224) (xy 11.611356 -351.237804) (xy 8.836152 -354.013008) (xy 6.905498 -354.013008)
			(xy 4.770628 -356.147878) (xy 4.770628 -372.011956) (xy 4.770628 -372.780052) (xy 4.81649 -372.794418)
			(xy 4.905844 -372.829828) (xy 4.991912 -372.872611) (xy 5.074085 -372.922466) (xy 5.151785 -372.979041)
			(xy 5.224463 -373.041937) (xy 5.291607 -373.110709) (xy 5.352743 -373.184874) (xy 5.407439 -373.263908)
			(xy 5.45531 -373.347252) (xy 5.496018 -373.43432) (xy 5.529277 -373.524497) (xy 5.55485 -373.617147)
			(xy 5.572558 -373.711616) (xy 5.582276 -373.807238) (xy 5.583936 -373.903338) (xy 5.577525 -373.999239)
			(xy 5.56309 -374.094263) (xy 5.54073 -374.18774) (xy 5.510606 -374.279012) (xy 5.472928 -374.367434)
			(xy 5.427963 -374.452382) (xy 5.376029 -374.533257) (xy 5.31749 -374.609488) (xy 5.252761 -374.680538)
			(xy 5.182298 -374.745906) (xy 5.106598 -374.80513) (xy 5.026195 -374.857793) (xy 4.941656 -374.903522)
			(xy 4.853578 -374.941996) (xy 4.762582 -374.972943) (xy 4.66931 -374.996145) (xy 4.57442 -375.011438)
			(xy 4.478582 -375.018714) (xy 4.430522 -375.018808) (xy 3.583686 -375.018808) (xy 1.857248 -375.018808)
			(xy 1.857248 -379.681232) (xy 4.426458 -379.681232) (xy 4.474105 -379.681161) (xy 4.569149 -379.687971)
			(xy 4.663298 -379.702664) (xy 4.755897 -379.72514) (xy 4.846306 -379.755241) (xy 4.933897 -379.792759)
			(xy 5.018063 -379.837435) (xy 5.09822 -379.888959) (xy 5.173813 -379.946972) (xy 5.244317 -380.011073)
			(xy 5.309244 -380.080818) (xy 5.368143 -380.155723) (xy 5.420606 -380.235268) (xy 5.466269 -380.318903)
			(xy 5.504816 -380.406046) (xy 5.535979 -380.496094) (xy 5.559543 -380.588423) (xy 5.575343 -380.682392)
			(xy 5.583271 -380.77735) (xy 5.583271 -380.872638) (xy 5.575343 -380.967596) (xy 5.559543 -381.061565)
			(xy 5.535979 -381.153894) (xy 5.504816 -381.243942) (xy 5.466269 -381.331085) (xy 5.420606 -381.41472)
			(xy 5.368143 -381.494265) (xy 5.309244 -381.56917) (xy 5.244317 -381.638915) (xy 5.173813 -381.703016)
			(xy 5.09822 -381.761029) (xy 5.018063 -381.812553) (xy 4.933897 -381.857229) (xy 4.846306 -381.894747)
			(xy 4.755897 -381.924848) (xy 4.663298 -381.947324) (xy 4.569149 -381.962017) (xy 4.474105 -381.968827)
			(xy 4.426458 -381.968756) (xy 1.296162 -381.968756) (xy 1.27 -381.994918) (xy 1.27 -384.79984) (xy 8.597656 -384.79984)
			(xy 8.601644 -384.54722) (xy 8.613605 -384.294852) (xy 8.633527 -384.042988) (xy 8.661391 -383.791878)
			(xy 8.697167 -383.541772) (xy 8.740821 -383.292921) (xy 8.79231 -383.045572) (xy 8.851581 -382.799971)
			(xy 8.918576 -382.556364) (xy 8.993227 -382.314994) (xy 9.075462 -382.0761) (xy 9.165196 -381.839922)
			(xy 9.262342 -381.606694) (xy 9.366802 -381.376648) (xy 9.478473 -381.150016) (xy 9.597242 -380.927021)
			(xy 9.722991 -380.707887) (xy 9.855596 -380.492832) (xy 9.994923 -380.28207) (xy 10.140835 -380.075812)
			(xy 10.293185 -379.874263) (xy 10.451821 -379.677623) (xy 10.616586 -379.48609) (xy 10.787316 -379.299853)
			(xy 10.96384 -379.119099) (xy 11.145982 -378.944008) (xy 11.33356 -378.774754) (xy 11.526388 -378.611505)
			(xy 11.724273 -378.454426) (xy 11.927019 -378.303671) (xy 12.134423 -378.159393) (xy 12.346278 -378.021733)
			(xy 12.562373 -377.89083) (xy 12.782493 -377.766814) (xy 13.006418 -377.649809) (xy 13.233925 -377.539931)
			(xy 13.464787 -377.43729) (xy 13.698775 -377.341988) (xy 13.935654 -377.254121) (xy 14.17519 -377.173774)
			(xy 14.417142 -377.10103) (xy 14.66127 -377.03596) (xy 14.907331 -376.97863) (xy 15.155079 -376.929096)
			(xy 15.404267 -376.887407) (xy 15.654647 -376.853606) (xy 15.905969 -376.827725) (xy 16.157983 -376.809792)
			(xy 16.410437 -376.799823) (xy 16.663081 -376.797829) (xy 16.915661 -376.803811) (xy 17.167927 -376.817764)
			(xy 17.419626 -376.839674) (xy 17.670509 -376.869518) (xy 17.920324 -376.907268) (xy 18.168823 -376.952885)
			(xy 18.415758 -377.006324) (xy 18.660883 -377.067532) (xy 18.903953 -377.136447) (xy 19.144727 -377.213002)
			(xy 19.382964 -377.297119) (xy 19.618427 -377.388716) (xy 19.850881 -377.4877) (xy 20.080095 -377.593972)
			(xy 20.305839 -377.707428) (xy 20.527889 -377.827953) (xy 20.746023 -377.955429) (xy 20.960025 -378.089727)
			(xy 21.169681 -378.230713) (xy 21.374781 -378.378248) (xy 21.575121 -378.532184) (xy 21.770502 -378.692368)
			(xy 21.960729 -378.85864) (xy 22.145612 -379.030835) (xy 22.324968 -379.208779) (xy 22.498616 -379.392298)
			(xy 22.666384 -379.581206) (xy 22.828105 -379.775317) (xy 22.983618 -379.974436) (xy 23.132767 -380.178365)
			(xy 23.275404 -380.386901) (xy 23.411387 -380.599836) (xy 23.54058 -380.816958) (xy 23.662855 -381.03805)
			(xy 23.778089 -381.262891) (xy 23.886168 -381.491259) (xy 23.986983 -381.722924) (xy 24.080435 -381.957657)
			(xy 24.16643 -382.195222) (xy 24.244883 -382.435384) (xy 24.315715 -382.677903) (xy 24.378856 -382.922538)
			(xy 24.434243 -383.169043) (xy 24.48182 -383.417174) (xy 24.52154 -383.666684) (xy 24.553364 -383.917323)
			(xy 24.57726 -384.168841) (xy 24.593204 -384.420989) (xy 24.601179 -384.673514) (xy 24.601678 -384.79984)
			(xy 24.601179 -384.926166) (xy 24.593204 -385.178691) (xy 24.57726 -385.430839) (xy 24.553364 -385.682357)
			(xy 24.52154 -385.932996) (xy 24.48182 -386.182506) (xy 24.434243 -386.430637) (xy 24.378856 -386.677142)
			(xy 24.315715 -386.921777) (xy 24.244883 -387.164296) (xy 24.16643 -387.404458) (xy 24.080435 -387.642023)
			(xy 23.986983 -387.876756) (xy 23.886168 -388.108421) (xy 23.778089 -388.336789) (xy 23.662855 -388.56163)
			(xy 23.54058 -388.782722) (xy 23.411387 -388.999844) (xy 23.275404 -389.212779) (xy 23.132767 -389.421315)
			(xy 22.983618 -389.625244) (xy 22.828105 -389.824363) (xy 22.666384 -390.018474) (xy 22.498616 -390.207382)
			(xy 22.324968 -390.390901) (xy 22.145612 -390.568845) (xy 21.960729 -390.74104) (xy 21.770502 -390.907312)
			(xy 21.575121 -391.067496) (xy 21.374781 -391.221432) (xy 21.169681 -391.368967) (xy 20.960025 -391.509953)
			(xy 20.746023 -391.644251) (xy 20.527889 -391.771727) (xy 20.305839 -391.892252) (xy 20.080095 -392.005708)
			(xy 19.850881 -392.11198) (xy 19.618427 -392.210964) (xy 19.382964 -392.302561) (xy 19.144727 -392.386678)
			(xy 18.903953 -392.463233) (xy 18.660883 -392.532148) (xy 18.415758 -392.593356) (xy 18.168823 -392.646795)
			(xy 17.920324 -392.692412) (xy 17.670509 -392.730162) (xy 17.419626 -392.760006) (xy 17.167927 -392.781916)
			(xy 16.915661 -392.795869) (xy 16.663081 -392.801851) (xy 16.410437 -392.799857) (xy 16.157983 -392.789888)
			(xy 15.905969 -392.771955) (xy 15.654647 -392.746074) (xy 15.404267 -392.712273) (xy 15.155079 -392.670584)
			(xy 14.907331 -392.62105) (xy 14.66127 -392.56372) (xy 14.417142 -392.49865) (xy 14.17519 -392.425906)
			(xy 13.935654 -392.345559) (xy 13.698775 -392.257692) (xy 13.464787 -392.16239) (xy 13.233925 -392.059749)
			(xy 13.006418 -391.949871) (xy 12.782493 -391.832866) (xy 12.562373 -391.70885) (xy 12.346278 -391.577947)
			(xy 12.134423 -391.440287) (xy 11.927019 -391.296009) (xy 11.724273 -391.145254) (xy 11.526388 -390.988175)
			(xy 11.33356 -390.824926) (xy 11.145982 -390.655672) (xy 10.96384 -390.480581) (xy 10.787316 -390.299827)
			(xy 10.616586 -390.11359) (xy 10.451821 -389.922057) (xy 10.293185 -389.725417) (xy 10.140835 -389.523868)
			(xy 9.994923 -389.31761) (xy 9.855596 -389.106848) (xy 9.722991 -388.891793) (xy 9.597242 -388.672659)
			(xy 9.478473 -388.449664) (xy 9.366802 -388.223032) (xy 9.262342 -387.992986) (xy 9.165196 -387.759758)
			(xy 9.075462 -387.52358) (xy 8.993227 -387.284686) (xy 8.918576 -387.043316) (xy 8.851581 -386.799709)
			(xy 8.79231 -386.554108) (xy 8.740821 -386.306759) (xy 8.697167 -386.057908) (xy 8.661391 -385.807802)
			(xy 8.633527 -385.556692) (xy 8.613605 -385.304828) (xy 8.601644 -385.05246) (xy 8.597656 -384.79984)
			(xy 1.27 -384.79984) (xy 1.27 -399.247963) (xy 2.181485 -399.247963) (xy 2.184676 -399.168685) (xy 2.195821 -399.090129)
			(xy 2.214805 -399.013091) (xy 2.241437 -398.938352) (xy 2.275447 -398.866668) (xy 2.31649 -398.798766)
			(xy 2.364151 -398.735334) (xy 2.417946 -398.677014) (xy 2.477332 -398.624396) (xy 2.541705 -398.578015)
			(xy 2.575814 -398.55775) (xy 2.576068 -398.55775) (xy 2.590126 -398.548946) (xy 2.613478 -398.525403)
			(xy 2.629982 -398.496642) (xy 2.638525 -398.464602) (xy 2.63906 -398.448022) (xy 2.63906 -397.725138)
			(xy 2.485136 -397.57096) (xy 2.485136 -396.251176) (xy 2.434082 -396.200122) (xy 2.434082 -395.382496)
			(xy 2.408682 -395.348714) (xy 2.389495 -395.322238) (xy 2.357353 -395.265297) (xy 2.332779 -395.204703)
			(xy 2.316178 -395.141459) (xy 2.307825 -395.076608) (xy 2.307336 -395.043914) (xy 2.307336 -394.357606)
			(xy 2.307837 -394.325661) (xy 2.315845 -394.262275) (xy 2.331734 -394.200392) (xy 2.355253 -394.140988)
			(xy 2.386033 -394.085001) (xy 2.423586 -394.033312) (xy 2.467322 -393.986738) (xy 2.51655 -393.946013)
			(xy 2.570495 -393.911779) (xy 2.628304 -393.884576) (xy 2.689067 -393.864833) (xy 2.751826 -393.852861)
			(xy 2.81559 -393.84885) (xy 2.879354 -393.852861) (xy 2.942113 -393.864833) (xy 3.002876 -393.884576)
			(xy 3.060685 -393.911779) (xy 3.11463 -393.946013) (xy 3.163858 -393.986738) (xy 3.207594 -394.033312)
			(xy 3.245147 -394.085001) (xy 3.275927 -394.140988) (xy 3.299446 -394.200392) (xy 3.315335 -394.262275)
			(xy 3.323343 -394.325661) (xy 3.323844 -394.357606) (xy 3.323844 -395.010386) (xy 3.678428 -395.010386)
			(xy 3.678428 -394.248386) (xy 3.67893 -394.216425) (xy 3.686941 -394.153007) (xy 3.702838 -394.091093)
			(xy 3.72637 -394.03166) (xy 3.757164 -393.975645) (xy 3.794737 -393.92393) (xy 3.838494 -393.877333)
			(xy 3.887747 -393.836588) (xy 3.941718 -393.802337) (xy 3.999557 -393.77512) (xy 4.06035 -393.755367)
			(xy 4.12314 -393.743389) (xy 4.186936 -393.739376) (xy 4.250732 -393.743389) (xy 4.313522 -393.755367)
			(xy 4.374315 -393.77512) (xy 4.432154 -393.802337) (xy 4.486125 -393.836588) (xy 4.535378 -393.877333)
			(xy 4.579135 -393.92393) (xy 4.616708 -393.975645) (xy 4.647502 -394.03166) (xy 4.671034 -394.091093)
			(xy 4.686931 -394.153007) (xy 4.694942 -394.216425) (xy 4.695444 -394.248386) (xy 4.695444 -395.010386)
			(xy 4.69492 -395.043088) (xy 4.686528 -395.107951) (xy 4.669882 -395.1712) (xy 4.645256 -395.23179)
			(xy 4.613057 -395.288719) (xy 4.593844 -395.315186) (xy 4.568444 -395.348968) (xy 4.568444 -396.02105)
			(xy 13.2344 -396.02105) (xy 13.238414 -395.957252) (xy 13.250393 -395.894459) (xy 13.270147 -395.833663)
			(xy 13.297364 -395.775823) (xy 13.331617 -395.721849) (xy 13.372364 -395.672595) (xy 13.418963 -395.628835)
			(xy 13.470679 -395.591261) (xy 13.526697 -395.560466) (xy 13.586133 -395.536934) (xy 13.648049 -395.521036)
			(xy 13.71147 -395.513025) (xy 13.743432 -395.512544) (xy 14.76502 -395.512544) (xy 14.797722 -395.513052)
			(xy 14.862586 -395.521448) (xy 14.925835 -395.538098) (xy 14.986425 -395.562728) (xy 15.043353 -395.59493)
			(xy 15.06982 -395.614144) (xy 15.103602 -395.639544) (xy 15.921228 -395.639544) (xy 15.921228 -396.40256)
			(xy 15.895828 -396.40256) (xy 15.895828 -398.445228) (xy 15.896308 -398.461952) (xy 15.905025 -398.494244)
			(xy 15.921828 -398.523165) (xy 15.945565 -398.546731) (xy 15.959836 -398.555464) (xy 15.994059 -398.575538)
			(xy 16.058697 -398.621556) (xy 16.118381 -398.673838) (xy 16.172509 -398.731854) (xy 16.220531 -398.795017)
			(xy 16.261961 -398.862688) (xy 16.296379 -398.934179) (xy 16.323437 -399.008769) (xy 16.342861 -399.0857)
			(xy 16.354454 -399.164194) (xy 16.358099 -399.243455) (xy 16.353758 -399.322682) (xy 16.341475 -399.401071)
			(xy 16.321376 -399.477828) (xy 16.293663 -399.552177) (xy 16.258617 -399.623363) (xy 16.216594 -399.690667)
			(xy 16.168019 -399.753405) (xy 16.113383 -399.810943) (xy 16.053241 -399.862699) (xy 15.988201 -399.908147)
			(xy 15.918923 -399.946827) (xy 15.846107 -399.978348) (xy 15.770492 -400.002391) (xy 15.692843 -400.018711)
			(xy 15.613947 -400.027144) (xy 15.534603 -400.027604) (xy 15.455615 -400.020087) (xy 15.377782 -400.004668)
			(xy 15.301893 -399.981504) (xy 15.228717 -399.950829) (xy 15.158994 -399.912955) (xy 15.093432 -399.868264)
			(xy 15.032694 -399.817209) (xy 14.977395 -399.760308) (xy 14.928095 -399.698137) (xy 14.885294 -399.631326)
			(xy 14.849426 -399.560551) (xy 14.820853 -399.486528) (xy 14.799865 -399.410009) (xy 14.786674 -399.331768)
			(xy 14.781415 -399.252597) (xy 14.78414 -399.173298) (xy 14.794822 -399.094675) (xy 14.813352 -399.017524)
			(xy 14.839543 -398.942626) (xy 14.87313 -398.87074) (xy 14.913773 -398.802594) (xy 14.961059 -398.738878)
			(xy 15.014511 -398.680238) (xy 15.073585 -398.627268) (xy 15.137685 -398.580503) (xy 15.171674 -398.560036)
			(xy 15.185672 -398.551224) (xy 15.208944 -398.527735) (xy 15.225384 -398.499047) (xy 15.233886 -398.467095)
			(xy 15.234412 -398.450562) (xy 15.234412 -396.752318) (xy 15.233936 -396.728723) (xy 15.225195 -396.682349)
			(xy 15.208047 -396.638384) (xy 15.183082 -396.598338) (xy 15.151156 -396.563587) (xy 15.113366 -396.535323)
			(xy 15.071009 -396.514517) (xy 15.025541 -396.501885) (xy 14.978522 -396.497859) (xy 14.931568 -396.502578)
			(xy 14.908784 -396.508732) (xy 14.873642 -396.518462) (xy 14.801478 -396.528916) (xy 14.76502 -396.52956)
			(xy 13.743432 -396.52956) (xy 13.71147 -396.529075) (xy 13.648049 -396.521064) (xy 13.586133 -396.505166)
			(xy 13.526697 -396.481634) (xy 13.470679 -396.450839) (xy 13.418963 -396.413265) (xy 13.372364 -396.369505)
			(xy 13.331617 -396.320251) (xy 13.297364 -396.266277) (xy 13.270147 -396.208437) (xy 13.250393 -396.147641)
			(xy 13.238414 -396.084848) (xy 13.2344 -396.02105) (xy 4.568444 -396.02105) (xy 4.568444 -396.166594)
			(xy 4.517644 -396.217394) (xy 4.517644 -397.830294) (xy 5.13334 -398.44599) (xy 5.145497 -398.45733)
			(xy 5.174256 -398.473979) (xy 5.206337 -398.482643) (xy 5.239567 -398.482734) (xy 5.255768 -398.47901)
			(xy 5.256022 -398.47901) (xy 5.294466 -398.469226) (xy 5.372774 -398.456518) (xy 5.451964 -398.451746)
			(xy 5.531232 -398.454957) (xy 5.609775 -398.466119) (xy 5.686799 -398.48512) (xy 5.761523 -398.511766)
			(xy 5.833191 -398.545788) (xy 5.901076 -398.586841) (xy 5.96449 -398.63451) (xy 6.022793 -398.688311)
			(xy 6.075392 -398.747699) (xy 6.121755 -398.812074) (xy 6.161414 -398.880783) (xy 6.193965 -398.953131)
			(xy 6.21908 -399.028383) (xy 6.236503 -399.105779) (xy 6.24606 -399.184534) (xy 6.247651 -399.263851)
			(xy 6.246352 -399.279927) (xy 12.292327 -399.279927) (xy 12.292327 -399.200061) (xy 12.300407 -399.120606)
			(xy 12.316484 -399.042376) (xy 12.340393 -398.966174) (xy 12.371888 -398.892781) (xy 12.410647 -398.822951)
			(xy 12.456271 -398.757401) (xy 12.508293 -398.696802) (xy 12.566178 -398.641778) (xy 12.629334 -398.592892)
			(xy 12.697111 -398.550646) (xy 12.768814 -398.515474) (xy 12.843708 -398.487737) (xy 12.921023 -398.467718)
			(xy 12.999967 -398.455625) (xy 13.07973 -398.45158) (xy 13.159493 -398.455625) (xy 13.238437 -398.467718)
			(xy 13.315752 -398.487737) (xy 13.390646 -398.515474) (xy 13.462349 -398.550646) (xy 13.530126 -398.592892)
			(xy 13.593282 -398.641778) (xy 13.651167 -398.696802) (xy 13.703189 -398.757401) (xy 13.748813 -398.822951)
			(xy 13.787572 -398.892781) (xy 13.819067 -398.966174) (xy 13.842976 -399.042376) (xy 13.859053 -399.120606)
			(xy 13.867133 -399.200061) (xy 13.867638 -399.239994) (xy 13.867133 -399.279927) (xy 13.859053 -399.359382)
			(xy 13.842976 -399.437612) (xy 13.819067 -399.513814) (xy 13.787572 -399.587207) (xy 13.748813 -399.657037)
			(xy 13.703189 -399.722587) (xy 13.651167 -399.783186) (xy 13.593282 -399.83821) (xy 13.530126 -399.887096)
			(xy 13.462349 -399.929342) (xy 13.390646 -399.964514) (xy 13.315752 -399.992251) (xy 13.238437 -400.01227)
			(xy 13.159493 -400.024363) (xy 13.07973 -400.028409) (xy 12.999967 -400.024363) (xy 12.921023 -400.01227)
			(xy 12.843708 -399.992251) (xy 12.768814 -399.964514) (xy 12.697111 -399.929342) (xy 12.629334 -399.887096)
			(xy 12.566178 -399.83821) (xy 12.508293 -399.783186) (xy 12.456271 -399.722587) (xy 12.410647 -399.657037)
			(xy 12.371888 -399.587207) (xy 12.340393 -399.513814) (xy 12.316484 -399.437612) (xy 12.300407 -399.359382)
			(xy 12.292327 -399.279927) (xy 6.246352 -399.279927) (xy 6.241263 -399.342927) (xy 6.226958 -399.420959)
			(xy 6.204883 -399.497159) (xy 6.175261 -399.570754) (xy 6.138391 -399.640999) (xy 6.094648 -399.707182)
			(xy 6.044474 -399.768634) (xy 5.988377 -399.824731) (xy 5.926926 -399.874905) (xy 5.860743 -399.918649)
			(xy 5.790499 -399.955519) (xy 5.716904 -399.985142) (xy 5.640704 -400.007217) (xy 5.562672 -400.021522)
			(xy 5.483596 -400.027911) (xy 5.404279 -400.02632) (xy 5.325524 -400.016764) (xy 5.248128 -399.999341)
			(xy 5.172875 -399.974227) (xy 5.100528 -399.941676) (xy 5.031818 -399.902018) (xy 4.967443 -399.855655)
			(xy 4.908054 -399.803056) (xy 4.854253 -399.744754) (xy 4.806584 -399.68134) (xy 4.76553 -399.613455)
			(xy 4.731508 -399.541788) (xy 4.704861 -399.467064) (xy 4.68586 -399.39004) (xy 4.674697 -399.311496)
			(xy 4.671486 -399.232229) (xy 4.676258 -399.153039) (xy 4.688965 -399.074731) (xy 4.698746 -399.036286)
			(xy 4.698746 -399.036032) (xy 4.702559 -399.019837) (xy 4.702509 -398.986576) (xy 4.693845 -398.954464)
			(xy 4.67716 -398.92569) (xy 4.665726 -398.913604) (xy 3.856228 -398.104106) (xy 3.856228 -396.217394)
			(xy 3.805428 -396.166594) (xy 3.805428 -395.348968) (xy 3.780028 -395.315186) (xy 3.76083 -395.28871)
			(xy 3.728651 -395.231774) (xy 3.704031 -395.171185) (xy 3.687374 -395.107942) (xy 3.678954 -395.043086)
			(xy 3.678428 -395.010386) (xy 3.323844 -395.010386) (xy 3.323844 -395.043914) (xy 3.323339 -395.076607)
			(xy 3.31499 -395.141457) (xy 3.298392 -395.204701) (xy 3.273821 -395.265295) (xy 3.241681 -395.322236)
			(xy 3.222498 -395.348714) (xy 3.197098 -395.382496) (xy 3.197098 -396.200122) (xy 3.146044 -396.251176)
			(xy 3.146044 -397.24457) (xy 3.146587 -397.261206) (xy 3.15528 -397.293325) (xy 3.171979 -397.322106)
			(xy 3.183382 -397.334232) (xy 3.300476 -397.451326) (xy 3.300476 -398.448022) (xy 3.300998 -398.464603)
			(xy 3.309532 -398.496648) (xy 3.326043 -398.525408) (xy 3.349414 -398.548936) (xy 3.363468 -398.55775)
			(xy 3.363722 -398.55775) (xy 3.397831 -398.578015) (xy 3.462204 -398.624396) (xy 3.52159 -398.677014)
			(xy 3.575385 -398.735334) (xy 3.623046 -398.798766) (xy 3.664089 -398.866668) (xy 3.698099 -398.938352)
			(xy 3.724731 -399.013091) (xy 3.743715 -399.090129) (xy 3.75486 -399.168685) (xy 3.758051 -399.247963)
			(xy 3.753258 -399.32716) (xy 3.740528 -399.405475) (xy 3.71999 -399.482113) (xy 3.691852 -399.556299)
			(xy 3.6564 -399.62728) (xy 3.613993 -399.694338) (xy 3.565059 -399.756794) (xy 3.510096 -399.814015)
			(xy 3.449659 -399.865421) (xy 3.38436 -399.910492) (xy 3.314863 -399.94877) (xy 3.241869 -399.979869)
			(xy 3.166119 -400.003473) (xy 3.08838 -400.019343) (xy 3.009439 -400.027319) (xy 2.930097 -400.027319)
			(xy 2.851156 -400.019343) (xy 2.773417 -400.003473) (xy 2.697667 -399.979869) (xy 2.624673 -399.94877)
			(xy 2.555176 -399.910492) (xy 2.489877 -399.865421) (xy 2.42944 -399.814015) (xy 2.374477 -399.756794)
			(xy 2.325543 -399.694338) (xy 2.283136 -399.62728) (xy 2.247684 -399.556299) (xy 2.219546 -399.482113)
			(xy 2.199008 -399.405475) (xy 2.186278 -399.32716) (xy 2.181485 -399.247963) (xy 1.27 -399.247963)
			(xy 1.27 -403.413036) (xy 1.547863 -403.413036) (xy 1.547863 -403.2869) (xy 1.555783 -403.161012)
			(xy 1.571593 -403.03587) (xy 1.595228 -402.911967) (xy 1.626597 -402.789794) (xy 1.665575 -402.669831)
			(xy 1.712009 -402.552552) (xy 1.765716 -402.43842) (xy 1.826483 -402.327885) (xy 1.89407 -402.221385)
			(xy 1.968211 -402.119338) (xy 2.048614 -402.022148) (xy 2.13496 -401.930198) (xy 2.22691 -401.843852)
			(xy 2.3241 -401.763449) (xy 2.426147 -401.689308) (xy 2.532647 -401.621721) (xy 2.643182 -401.560954)
			(xy 2.757314 -401.507247) (xy 2.874593 -401.460813) (xy 2.994556 -401.421835) (xy 3.116729 -401.390466)
			(xy 3.240632 -401.366831) (xy 3.365774 -401.351021) (xy 3.491662 -401.343101) (xy 3.617798 -401.343101)
			(xy 3.743686 -401.351021) (xy 3.868828 -401.366831) (xy 3.992731 -401.390466) (xy 4.114904 -401.421835)
			(xy 4.234867 -401.460813) (xy 4.352146 -401.507247) (xy 4.466278 -401.560954) (xy 4.576813 -401.621721)
			(xy 4.683313 -401.689308) (xy 4.78536 -401.763449) (xy 4.88255 -401.843852) (xy 4.9745 -401.930198)
			(xy 5.060846 -402.022148) (xy 5.141249 -402.119338) (xy 5.21539 -402.221385) (xy 5.282977 -402.327885)
			(xy 5.343744 -402.43842) (xy 5.397451 -402.552552) (xy 5.443885 -402.669831) (xy 5.482863 -402.789794)
			(xy 5.514232 -402.911967) (xy 5.537867 -403.03587) (xy 5.553677 -403.161012) (xy 5.561597 -403.2869)
			(xy 5.562092 -403.349968) (xy 5.561597 -403.413036) (xy 12.977863 -403.413036) (xy 12.977863 -403.2869)
			(xy 12.985783 -403.161012) (xy 13.001593 -403.03587) (xy 13.025228 -402.911967) (xy 13.056597 -402.789794)
			(xy 13.095575 -402.669831) (xy 13.142009 -402.552552) (xy 13.195716 -402.43842) (xy 13.256483 -402.327885)
			(xy 13.32407 -402.221385) (xy 13.398211 -402.119338) (xy 13.478614 -402.022148) (xy 13.56496 -401.930198)
			(xy 13.65691 -401.843852) (xy 13.7541 -401.763449) (xy 13.856147 -401.689308) (xy 13.962647 -401.621721)
			(xy 14.073182 -401.560954) (xy 14.187314 -401.507247) (xy 14.304593 -401.460813) (xy 14.424556 -401.421835)
			(xy 14.546729 -401.390466) (xy 14.670632 -401.366831) (xy 14.795774 -401.351021) (xy 14.921662 -401.343101)
			(xy 15.047798 -401.343101) (xy 15.173686 -401.351021) (xy 15.298828 -401.366831) (xy 15.422731 -401.390466)
			(xy 15.544904 -401.421835) (xy 15.664867 -401.460813) (xy 15.782146 -401.507247) (xy 15.896278 -401.560954)
			(xy 16.006813 -401.621721) (xy 16.113313 -401.689308) (xy 16.21536 -401.763449) (xy 16.31255 -401.843852)
			(xy 16.4045 -401.930198) (xy 16.490846 -402.022148) (xy 16.571249 -402.119338) (xy 16.64539 -402.221385)
			(xy 16.712977 -402.327885) (xy 16.773744 -402.43842) (xy 16.827451 -402.552552) (xy 16.873885 -402.669831)
			(xy 16.912863 -402.789794) (xy 16.944232 -402.911967) (xy 16.967867 -403.03587) (xy 16.983677 -403.161012)
			(xy 16.991597 -403.2869) (xy 16.992092 -403.349968) (xy 16.991597 -403.413036) (xy 16.983677 -403.538924)
			(xy 16.967867 -403.664066) (xy 16.944232 -403.787969) (xy 16.912863 -403.910142) (xy 16.873885 -404.030105)
			(xy 16.827451 -404.147384) (xy 16.773744 -404.261516) (xy 16.712977 -404.372051) (xy 16.64539 -404.478551)
			(xy 16.571249 -404.580598) (xy 16.490846 -404.677788) (xy 16.4045 -404.769738) (xy 16.31255 -404.856084)
			(xy 16.21536 -404.936487) (xy 16.113313 -405.010628) (xy 16.006813 -405.078215) (xy 15.896278 -405.138982)
			(xy 15.782146 -405.192689) (xy 15.664867 -405.239123) (xy 15.544904 -405.278101) (xy 15.422731 -405.30947)
			(xy 15.298828 -405.333105) (xy 15.173686 -405.348915) (xy 15.047798 -405.356835) (xy 14.921662 -405.356835)
			(xy 14.795774 -405.348915) (xy 14.670632 -405.333105) (xy 14.546729 -405.30947) (xy 14.424556 -405.278101)
			(xy 14.304593 -405.239123) (xy 14.187314 -405.192689) (xy 14.073182 -405.138982) (xy 13.962647 -405.078215)
			(xy 13.856147 -405.010628) (xy 13.7541 -404.936487) (xy 13.65691 -404.856084) (xy 13.56496 -404.769738)
			(xy 13.478614 -404.677788) (xy 13.398211 -404.580598) (xy 13.32407 -404.478551) (xy 13.256483 -404.372051)
			(xy 13.195716 -404.261516) (xy 13.142009 -404.147384) (xy 13.095575 -404.030105) (xy 13.056597 -403.910142)
			(xy 13.025228 -403.787969) (xy 13.001593 -403.664066) (xy 12.985783 -403.538924) (xy 12.977863 -403.413036)
			(xy 5.561597 -403.413036) (xy 5.553677 -403.538924) (xy 5.537867 -403.664066) (xy 5.514232 -403.787969)
			(xy 5.482863 -403.910142) (xy 5.443885 -404.030105) (xy 5.397451 -404.147384) (xy 5.343744 -404.261516)
			(xy 5.282977 -404.372051) (xy 5.21539 -404.478551) (xy 5.141249 -404.580598) (xy 5.060846 -404.677788)
			(xy 4.9745 -404.769738) (xy 4.88255 -404.856084) (xy 4.78536 -404.936487) (xy 4.683313 -405.010628)
			(xy 4.576813 -405.078215) (xy 4.466278 -405.138982) (xy 4.352146 -405.192689) (xy 4.234867 -405.239123)
			(xy 4.114904 -405.278101) (xy 3.992731 -405.30947) (xy 3.868828 -405.333105) (xy 3.743686 -405.348915)
			(xy 3.617798 -405.356835) (xy 3.491662 -405.356835) (xy 3.365774 -405.348915) (xy 3.240632 -405.333105)
			(xy 3.116729 -405.30947) (xy 2.994556 -405.278101) (xy 2.874593 -405.239123) (xy 2.757314 -405.192689)
			(xy 2.643182 -405.138982) (xy 2.532647 -405.078215) (xy 2.426147 -405.010628) (xy 2.3241 -404.936487)
			(xy 2.22691 -404.856084) (xy 2.13496 -404.769738) (xy 2.048614 -404.677788) (xy 1.968211 -404.580598)
			(xy 1.89407 -404.478551) (xy 1.826483 -404.372051) (xy 1.765716 -404.261516) (xy 1.712009 -404.147384)
			(xy 1.665575 -404.030105) (xy 1.626597 -403.910142) (xy 1.595228 -403.787969) (xy 1.571593 -403.664066)
			(xy 1.555783 -403.538924) (xy 1.547863 -403.413036) (xy 1.27 -403.413036) (xy 1.27 -405.764238) (xy 1.39573 -405.890222)
			(xy 1.445514 -405.892254) (xy 1.496866 -405.894742) (xy 1.598977 -405.906784) (xy 1.699829 -405.926804)
			(xy 1.798798 -405.954676) (xy 1.895275 -405.99023) (xy 1.988663 -406.033246) (xy 2.078388 -406.083458)
			(xy 2.163895 -406.140557) (xy 2.244657 -406.204191) (xy 2.320176 -406.273967) (xy 2.389986 -406.349454)
			(xy 2.453656 -406.430188) (xy 2.510794 -406.515669) (xy 2.561047 -406.605371) (xy 2.604104 -406.69874)
			(xy 2.639702 -406.795201) (xy 2.667619 -406.894158) (xy 2.687684 -406.995) (xy 2.699772 -407.097106)
			(xy 2.70381 -407.199846) (xy 2.70179 -407.251242) (xy 15.836642 -407.251242) (xy 15.836642 -407.14845)
			(xy 15.844707 -407.045976) (xy 15.860787 -406.944451) (xy 15.884783 -406.8445) (xy 15.916548 -406.74674)
			(xy 15.955884 -406.651773) (xy 16.00255 -406.560186) (xy 16.056258 -406.472542) (xy 16.116677 -406.389382)
			(xy 16.183435 -406.311219) (xy 16.256119 -406.238535) (xy 16.334282 -406.171777) (xy 16.417442 -406.111358)
			(xy 16.505086 -406.05765) (xy 16.596673 -406.010984) (xy 16.69164 -405.971648) (xy 16.7894 -405.939883)
			(xy 16.889351 -405.915887) (xy 16.990876 -405.899807) (xy 17.09335 -405.891742) (xy 17.196142 -405.891742)
			(xy 17.298616 -405.899807) (xy 17.400141 -405.915887) (xy 17.500092 -405.939883) (xy 17.597852 -405.971648)
			(xy 17.692819 -406.010984) (xy 17.784406 -406.05765) (xy 17.87205 -406.111358) (xy 17.95521 -406.171777)
			(xy 18.033373 -406.238535) (xy 18.106057 -406.311219) (xy 18.172815 -406.389382) (xy 18.233234 -406.472542)
			(xy 18.286942 -406.560186) (xy 18.333608 -406.651773) (xy 18.372944 -406.74674) (xy 18.404709 -406.8445)
			(xy 18.428705 -406.944451) (xy 18.444785 -407.045976) (xy 18.45285 -407.14845) (xy 18.453354 -407.199846)
			(xy 18.45285 -407.251242) (xy 18.444785 -407.353716) (xy 18.428705 -407.455241) (xy 18.404709 -407.555192)
			(xy 18.372944 -407.652952) (xy 18.333608 -407.747919) (xy 18.286942 -407.839506) (xy 18.233234 -407.92715)
			(xy 18.172815 -408.01031) (xy 18.106057 -408.088473) (xy 18.033373 -408.161157) (xy 17.95521 -408.227915)
			(xy 17.87205 -408.288334) (xy 17.784406 -408.342042) (xy 17.692819 -408.388708) (xy 17.597852 -408.428044)
			(xy 17.500092 -408.459809) (xy 17.400141 -408.483805) (xy 17.298616 -408.499885) (xy 17.196142 -408.50795)
			(xy 17.09335 -408.50795) (xy 16.990876 -408.499885) (xy 16.889351 -408.483805) (xy 16.7894 -408.459809)
			(xy 16.69164 -408.428044) (xy 16.596673 -408.388708) (xy 16.505086 -408.342042) (xy 16.417442 -408.288334)
			(xy 16.334282 -408.227915) (xy 16.256119 -408.161157) (xy 16.183435 -408.088473) (xy 16.116677 -408.01031)
			(xy 16.056258 -407.92715) (xy 16.00255 -407.839506) (xy 15.955884 -407.747919) (xy 15.916548 -407.652952)
			(xy 15.884783 -407.555192) (xy 15.860787 -407.455241) (xy 15.844707 -407.353716) (xy 15.836642 -407.251242)
			(xy 2.70179 -407.251242) (xy 2.699772 -407.302586) (xy 2.687684 -407.404692) (xy 2.667619 -407.505534)
			(xy 2.639702 -407.604491) (xy 2.604104 -407.700952) (xy 2.561047 -407.794321) (xy 2.510794 -407.884023)
			(xy 2.453656 -407.969504) (xy 2.389986 -408.050238) (xy 2.320176 -408.125725) (xy 2.244657 -408.195501)
			(xy 2.163895 -408.259135) (xy 2.078388 -408.316234) (xy 1.988663 -408.366446) (xy 1.895275 -408.409462)
			(xy 1.798798 -408.445016) (xy 1.699829 -408.472888) (xy 1.598977 -408.492908) (xy 1.496866 -408.50495)
			(xy 1.445514 -408.507438) (xy 1.39573 -408.50947) (xy 1.27 -408.635454) (xy 1.27 -408.91206) (xy 4.037076 -408.91206)
			(xy 5.612384 -408.91206) (xy 5.612384 -409.739901) (xy 6.577327 -409.739901) (xy 6.577327 -409.660035)
			(xy 6.585407 -409.58058) (xy 6.601484 -409.50235) (xy 6.625393 -409.426148) (xy 6.656888 -409.352755)
			(xy 6.695647 -409.282925) (xy 6.741271 -409.217375) (xy 6.793293 -409.156776) (xy 6.851178 -409.101752)
			(xy 6.914334 -409.052866) (xy 6.982111 -409.01062) (xy 7.053814 -408.975448) (xy 7.128708 -408.947711)
			(xy 7.206023 -408.927692) (xy 7.284967 -408.915599) (xy 7.36473 -408.911554) (xy 7.444493 -408.915599)
			(xy 7.523437 -408.927692) (xy 7.600752 -408.947711) (xy 7.675646 -408.975448) (xy 7.747349 -409.01062)
			(xy 7.815126 -409.052866) (xy 7.878282 -409.101752) (xy 7.936167 -409.156776) (xy 7.988189 -409.217375)
			(xy 8.033813 -409.282925) (xy 8.072572 -409.352755) (xy 8.104067 -409.426148) (xy 8.127976 -409.50235)
			(xy 8.144053 -409.58058) (xy 8.152133 -409.660035) (xy 8.152638 -409.699968) (xy 8.152133 -409.739901)
			(xy 9.117327 -409.739901) (xy 9.117327 -409.660035) (xy 9.125407 -409.58058) (xy 9.141484 -409.50235)
			(xy 9.165393 -409.426148) (xy 9.196888 -409.352755) (xy 9.235647 -409.282925) (xy 9.281271 -409.217375)
			(xy 9.333293 -409.156776) (xy 9.391178 -409.101752) (xy 9.454334 -409.052866) (xy 9.522111 -409.01062)
			(xy 9.593814 -408.975448) (xy 9.668708 -408.947711) (xy 9.746023 -408.927692) (xy 9.824967 -408.915599)
			(xy 9.90473 -408.911554) (xy 9.984493 -408.915599) (xy 10.063437 -408.927692) (xy 10.140752 -408.947711)
			(xy 10.215646 -408.975448) (xy 10.287349 -409.01062) (xy 10.355126 -409.052866) (xy 10.418282 -409.101752)
			(xy 10.476167 -409.156776) (xy 10.528189 -409.217375) (xy 10.573813 -409.282925) (xy 10.612572 -409.352755)
			(xy 10.644067 -409.426148) (xy 10.667976 -409.50235) (xy 10.684053 -409.58058) (xy 10.692133 -409.660035)
			(xy 10.692638 -409.699968) (xy 10.692133 -409.739901) (xy 11.657327 -409.739901) (xy 11.657327 -409.660035)
			(xy 11.665407 -409.58058) (xy 11.681484 -409.50235) (xy 11.705393 -409.426148) (xy 11.736888 -409.352755)
			(xy 11.775647 -409.282925) (xy 11.821271 -409.217375) (xy 11.873293 -409.156776) (xy 11.931178 -409.101752)
			(xy 11.994334 -409.052866) (xy 12.062111 -409.01062) (xy 12.133814 -408.975448) (xy 12.208708 -408.947711)
			(xy 12.286023 -408.927692) (xy 12.364967 -408.915599) (xy 12.44473 -408.911554) (xy 12.524493 -408.915599)
			(xy 12.603437 -408.927692) (xy 12.680752 -408.947711) (xy 12.755646 -408.975448) (xy 12.827349 -409.01062)
			(xy 12.895126 -409.052866) (xy 12.958282 -409.101752) (xy 13.016167 -409.156776) (xy 13.068189 -409.217375)
			(xy 13.113813 -409.282925) (xy 13.152572 -409.352755) (xy 13.184067 -409.426148) (xy 13.207976 -409.50235)
			(xy 13.224053 -409.58058) (xy 13.232133 -409.660035) (xy 13.232638 -409.699968) (xy 13.232133 -409.739901)
			(xy 13.224053 -409.819356) (xy 13.207976 -409.897586) (xy 13.184067 -409.973788) (xy 13.152572 -410.047181)
			(xy 13.113813 -410.117011) (xy 13.068189 -410.182561) (xy 13.016167 -410.24316) (xy 12.958282 -410.298184)
			(xy 12.895126 -410.34707) (xy 12.827349 -410.389316) (xy 12.755646 -410.424488) (xy 12.680752 -410.452225)
			(xy 12.603437 -410.472244) (xy 12.524493 -410.484337) (xy 12.44473 -410.488383) (xy 12.364967 -410.484337)
			(xy 12.286023 -410.472244) (xy 12.208708 -410.452225) (xy 12.133814 -410.424488) (xy 12.062111 -410.389316)
			(xy 11.994334 -410.34707) (xy 11.931178 -410.298184) (xy 11.873293 -410.24316) (xy 11.821271 -410.182561)
			(xy 11.775647 -410.117011) (xy 11.736888 -410.047181) (xy 11.705393 -409.973788) (xy 11.681484 -409.897586)
			(xy 11.665407 -409.819356) (xy 11.657327 -409.739901) (xy 10.692133 -409.739901) (xy 10.684053 -409.819356)
			(xy 10.667976 -409.897586) (xy 10.644067 -409.973788) (xy 10.612572 -410.047181) (xy 10.573813 -410.117011)
			(xy 10.528189 -410.182561) (xy 10.476167 -410.24316) (xy 10.418282 -410.298184) (xy 10.355126 -410.34707)
			(xy 10.287349 -410.389316) (xy 10.215646 -410.424488) (xy 10.140752 -410.452225) (xy 10.063437 -410.472244)
			(xy 9.984493 -410.484337) (xy 9.90473 -410.488383) (xy 9.824967 -410.484337) (xy 9.746023 -410.472244)
			(xy 9.668708 -410.452225) (xy 9.593814 -410.424488) (xy 9.522111 -410.389316) (xy 9.454334 -410.34707)
			(xy 9.391178 -410.298184) (xy 9.333293 -410.24316) (xy 9.281271 -410.182561) (xy 9.235647 -410.117011)
			(xy 9.196888 -410.047181) (xy 9.165393 -409.973788) (xy 9.141484 -409.897586) (xy 9.125407 -409.819356)
			(xy 9.117327 -409.739901) (xy 8.152133 -409.739901) (xy 8.144053 -409.819356) (xy 8.127976 -409.897586)
			(xy 8.104067 -409.973788) (xy 8.072572 -410.047181) (xy 8.033813 -410.117011) (xy 7.988189 -410.182561)
			(xy 7.936167 -410.24316) (xy 7.878282 -410.298184) (xy 7.815126 -410.34707) (xy 7.747349 -410.389316)
			(xy 7.675646 -410.424488) (xy 7.600752 -410.452225) (xy 7.523437 -410.472244) (xy 7.444493 -410.484337)
			(xy 7.36473 -410.488383) (xy 7.284967 -410.484337) (xy 7.206023 -410.472244) (xy 7.128708 -410.452225)
			(xy 7.053814 -410.424488) (xy 6.982111 -410.389316) (xy 6.914334 -410.34707) (xy 6.851178 -410.298184)
			(xy 6.793293 -410.24316) (xy 6.741271 -410.182561) (xy 6.695647 -410.117011) (xy 6.656888 -410.047181)
			(xy 6.625393 -409.973788) (xy 6.601484 -409.897586) (xy 6.585407 -409.819356) (xy 6.577327 -409.739901)
			(xy 5.612384 -409.739901) (xy 5.612384 -410.487876) (xy 4.037076 -410.487876) (xy 4.037076 -408.91206)
			(xy 1.27 -408.91206) (xy 1.27 -412.279901) (xy 5.307327 -412.279901) (xy 5.307327 -412.200035) (xy 5.315407 -412.12058)
			(xy 5.331484 -412.04235) (xy 5.355393 -411.966148) (xy 5.386888 -411.892755) (xy 5.425647 -411.822925)
			(xy 5.471271 -411.757375) (xy 5.523293 -411.696776) (xy 5.581178 -411.641752) (xy 5.644334 -411.592866)
			(xy 5.712111 -411.55062) (xy 5.783814 -411.515448) (xy 5.858708 -411.487711) (xy 5.936023 -411.467692)
			(xy 6.014967 -411.455599) (xy 6.09473 -411.451554) (xy 6.174493 -411.455599) (xy 6.253437 -411.467692)
			(xy 6.330752 -411.487711) (xy 6.405646 -411.515448) (xy 6.477349 -411.55062) (xy 6.545126 -411.592866)
			(xy 6.608282 -411.641752) (xy 6.666167 -411.696776) (xy 6.718189 -411.757375) (xy 6.763813 -411.822925)
			(xy 6.802572 -411.892755) (xy 6.834067 -411.966148) (xy 6.857976 -412.04235) (xy 6.874053 -412.12058)
			(xy 6.882133 -412.200035) (xy 6.882638 -412.239968) (xy 6.882133 -412.279901) (xy 7.847327 -412.279901)
			(xy 7.847327 -412.200035) (xy 7.855407 -412.12058) (xy 7.871484 -412.04235) (xy 7.895393 -411.966148)
			(xy 7.926888 -411.892755) (xy 7.965647 -411.822925) (xy 8.011271 -411.757375) (xy 8.063293 -411.696776)
			(xy 8.121178 -411.641752) (xy 8.184334 -411.592866) (xy 8.252111 -411.55062) (xy 8.323814 -411.515448)
			(xy 8.398708 -411.487711) (xy 8.476023 -411.467692) (xy 8.554967 -411.455599) (xy 8.63473 -411.451554)
			(xy 8.714493 -411.455599) (xy 8.793437 -411.467692) (xy 8.870752 -411.487711) (xy 8.945646 -411.515448)
			(xy 9.017349 -411.55062) (xy 9.085126 -411.592866) (xy 9.148282 -411.641752) (xy 9.206167 -411.696776)
			(xy 9.258189 -411.757375) (xy 9.303813 -411.822925) (xy 9.342572 -411.892755) (xy 9.374067 -411.966148)
			(xy 9.397976 -412.04235) (xy 9.414053 -412.12058) (xy 9.422133 -412.200035) (xy 9.422638 -412.239968)
			(xy 9.422133 -412.279901) (xy 10.387327 -412.279901) (xy 10.387327 -412.200035) (xy 10.395407 -412.12058)
			(xy 10.411484 -412.04235) (xy 10.435393 -411.966148) (xy 10.466888 -411.892755) (xy 10.505647 -411.822925)
			(xy 10.551271 -411.757375) (xy 10.603293 -411.696776) (xy 10.661178 -411.641752) (xy 10.724334 -411.592866)
			(xy 10.792111 -411.55062) (xy 10.863814 -411.515448) (xy 10.938708 -411.487711) (xy 11.016023 -411.467692)
			(xy 11.094967 -411.455599) (xy 11.17473 -411.451554) (xy 11.254493 -411.455599) (xy 11.333437 -411.467692)
			(xy 11.410752 -411.487711) (xy 11.485646 -411.515448) (xy 11.557349 -411.55062) (xy 11.625126 -411.592866)
			(xy 11.688282 -411.641752) (xy 11.746167 -411.696776) (xy 11.798189 -411.757375) (xy 11.843813 -411.822925)
			(xy 11.882572 -411.892755) (xy 11.914067 -411.966148) (xy 11.937976 -412.04235) (xy 11.954053 -412.12058)
			(xy 11.962133 -412.200035) (xy 11.962638 -412.239968) (xy 11.962133 -412.279901) (xy 12.927327 -412.279901)
			(xy 12.927327 -412.200035) (xy 12.935407 -412.12058) (xy 12.951484 -412.04235) (xy 12.975393 -411.966148)
			(xy 13.006888 -411.892755) (xy 13.045647 -411.822925) (xy 13.091271 -411.757375) (xy 13.143293 -411.696776)
			(xy 13.201178 -411.641752) (xy 13.264334 -411.592866) (xy 13.332111 -411.55062) (xy 13.403814 -411.515448)
			(xy 13.478708 -411.487711) (xy 13.556023 -411.467692) (xy 13.634967 -411.455599) (xy 13.71473 -411.451554)
			(xy 13.794493 -411.455599) (xy 13.873437 -411.467692) (xy 13.950752 -411.487711) (xy 14.025646 -411.515448)
			(xy 14.097349 -411.55062) (xy 14.165126 -411.592866) (xy 14.228282 -411.641752) (xy 14.286167 -411.696776)
			(xy 14.338189 -411.757375) (xy 14.383813 -411.822925) (xy 14.422572 -411.892755) (xy 14.454067 -411.966148)
			(xy 14.477976 -412.04235) (xy 14.494053 -412.12058) (xy 14.502133 -412.200035) (xy 14.502638 -412.239968)
			(xy 14.502133 -412.279901) (xy 14.494053 -412.359356) (xy 14.477976 -412.437586) (xy 14.454067 -412.513788)
			(xy 14.422572 -412.587181) (xy 14.383813 -412.657011) (xy 14.338189 -412.722561) (xy 14.286167 -412.78316)
			(xy 14.228282 -412.838184) (xy 14.165126 -412.88707) (xy 14.097349 -412.929316) (xy 14.025646 -412.964488)
			(xy 13.950752 -412.992225) (xy 13.873437 -413.012244) (xy 13.794493 -413.024337) (xy 13.71473 -413.028383)
			(xy 13.634967 -413.024337) (xy 13.556023 -413.012244) (xy 13.478708 -412.992225) (xy 13.403814 -412.964488)
			(xy 13.332111 -412.929316) (xy 13.264334 -412.88707) (xy 13.201178 -412.838184) (xy 13.143293 -412.78316)
			(xy 13.091271 -412.722561) (xy 13.045647 -412.657011) (xy 13.006888 -412.587181) (xy 12.975393 -412.513788)
			(xy 12.951484 -412.437586) (xy 12.935407 -412.359356) (xy 12.927327 -412.279901) (xy 11.962133 -412.279901)
			(xy 11.954053 -412.359356) (xy 11.937976 -412.437586) (xy 11.914067 -412.513788) (xy 11.882572 -412.587181)
			(xy 11.843813 -412.657011) (xy 11.798189 -412.722561) (xy 11.746167 -412.78316) (xy 11.688282 -412.838184)
			(xy 11.625126 -412.88707) (xy 11.557349 -412.929316) (xy 11.485646 -412.964488) (xy 11.410752 -412.992225)
			(xy 11.333437 -413.012244) (xy 11.254493 -413.024337) (xy 11.17473 -413.028383) (xy 11.094967 -413.024337)
			(xy 11.016023 -413.012244) (xy 10.938708 -412.992225) (xy 10.863814 -412.964488) (xy 10.792111 -412.929316)
			(xy 10.724334 -412.88707) (xy 10.661178 -412.838184) (xy 10.603293 -412.78316) (xy 10.551271 -412.722561)
			(xy 10.505647 -412.657011) (xy 10.466888 -412.587181) (xy 10.435393 -412.513788) (xy 10.411484 -412.437586)
			(xy 10.395407 -412.359356) (xy 10.387327 -412.279901) (xy 9.422133 -412.279901) (xy 9.414053 -412.359356)
			(xy 9.397976 -412.437586) (xy 9.374067 -412.513788) (xy 9.342572 -412.587181) (xy 9.303813 -412.657011)
			(xy 9.258189 -412.722561) (xy 9.206167 -412.78316) (xy 9.148282 -412.838184) (xy 9.085126 -412.88707)
			(xy 9.017349 -412.929316) (xy 8.945646 -412.964488) (xy 8.870752 -412.992225) (xy 8.793437 -413.012244)
			(xy 8.714493 -413.024337) (xy 8.63473 -413.028383) (xy 8.554967 -413.024337) (xy 8.476023 -413.012244)
			(xy 8.398708 -412.992225) (xy 8.323814 -412.964488) (xy 8.252111 -412.929316) (xy 8.184334 -412.88707)
			(xy 8.121178 -412.838184) (xy 8.063293 -412.78316) (xy 8.011271 -412.722561) (xy 7.965647 -412.657011)
			(xy 7.926888 -412.587181) (xy 7.895393 -412.513788) (xy 7.871484 -412.437586) (xy 7.855407 -412.359356)
			(xy 7.847327 -412.279901) (xy 6.882133 -412.279901) (xy 6.874053 -412.359356) (xy 6.857976 -412.437586)
			(xy 6.834067 -412.513788) (xy 6.802572 -412.587181) (xy 6.763813 -412.657011) (xy 6.718189 -412.722561)
			(xy 6.666167 -412.78316) (xy 6.608282 -412.838184) (xy 6.545126 -412.88707) (xy 6.477349 -412.929316)
			(xy 6.405646 -412.964488) (xy 6.330752 -412.992225) (xy 6.253437 -413.012244) (xy 6.174493 -413.024337)
			(xy 6.09473 -413.028383) (xy 6.014967 -413.024337) (xy 5.936023 -413.012244) (xy 5.858708 -412.992225)
			(xy 5.783814 -412.964488) (xy 5.712111 -412.929316) (xy 5.644334 -412.88707) (xy 5.581178 -412.838184)
			(xy 5.523293 -412.78316) (xy 5.471271 -412.722561) (xy 5.425647 -412.657011) (xy 5.386888 -412.587181)
			(xy 5.355393 -412.513788) (xy 5.331484 -412.437586) (xy 5.315407 -412.359356) (xy 5.307327 -412.279901)
			(xy 1.27 -412.279901) (xy 1.27 -423.940932) (xy 4.839198 -423.940932) (xy 4.839198 -423.84706) (xy 4.847159 -423.753526)
			(xy 4.863023 -423.661004) (xy 4.886677 -423.570161) (xy 4.917949 -423.481652) (xy 4.956615 -423.396113)
			(xy 5.002396 -423.314161) (xy 5.054962 -423.236387) (xy 5.113935 -423.163352) (xy 5.178888 -423.09558)
			(xy 5.249355 -423.033561) (xy 5.324828 -422.977742) (xy 5.404763 -422.928524) (xy 5.488584 -422.886262)
			(xy 5.575687 -422.851262) (xy 5.665444 -422.823774) (xy 5.757209 -422.803997) (xy 5.850321 -422.792074)
			(xy 5.944108 -422.78809) (xy 6.037895 -422.792074) (xy 6.131007 -422.803997) (xy 6.222772 -422.823774)
			(xy 6.312529 -422.851262) (xy 6.399632 -422.886262) (xy 6.483453 -422.928524) (xy 6.563388 -422.977742)
			(xy 6.638861 -423.033561) (xy 6.709328 -423.09558) (xy 6.774281 -423.163352) (xy 6.833254 -423.236387)
			(xy 6.88582 -423.314161) (xy 6.931601 -423.396113) (xy 6.970267 -423.481652) (xy 7.001539 -423.570161)
			(xy 7.025193 -423.661004) (xy 7.041057 -423.753526) (xy 7.049018 -423.84706) (xy 7.049516 -423.893996)
			(xy 7.049018 -423.940932) (xy 10.339314 -423.940932) (xy 10.339314 -423.84706) (xy 10.347275 -423.753526)
			(xy 10.363139 -423.661004) (xy 10.386793 -423.570161) (xy 10.418065 -423.481652) (xy 10.456731 -423.396113)
			(xy 10.502512 -423.314161) (xy 10.555078 -423.236387) (xy 10.614051 -423.163352) (xy 10.679004 -423.09558)
			(xy 10.749471 -423.033561) (xy 10.824944 -422.977742) (xy 10.904879 -422.928524) (xy 10.9887 -422.886262)
			(xy 11.075803 -422.851262) (xy 11.16556 -422.823774) (xy 11.257325 -422.803997) (xy 11.350437 -422.792074)
			(xy 11.444224 -422.78809) (xy 11.538011 -422.792074) (xy 11.631123 -422.803997) (xy 11.722888 -422.823774)
			(xy 11.812645 -422.851262) (xy 11.899748 -422.886262) (xy 11.983569 -422.928524) (xy 12.063504 -422.977742)
			(xy 12.138977 -423.033561) (xy 12.209444 -423.09558) (xy 12.274397 -423.163352) (xy 12.33337 -423.236387)
			(xy 12.385936 -423.314161) (xy 12.431717 -423.396113) (xy 12.470383 -423.481652) (xy 12.501655 -423.570161)
			(xy 12.525309 -423.661004) (xy 12.541173 -423.753526) (xy 12.549134 -423.84706) (xy 12.549632 -423.893996)
			(xy 12.549134 -423.940932) (xy 12.541173 -424.034466) (xy 12.525309 -424.126988) (xy 12.501655 -424.217831)
			(xy 12.470383 -424.30634) (xy 12.431717 -424.391879) (xy 12.385936 -424.473831) (xy 12.33337 -424.551605)
			(xy 12.274397 -424.62464) (xy 12.209444 -424.692412) (xy 12.138977 -424.754431) (xy 12.063504 -424.81025)
			(xy 11.983569 -424.859468) (xy 11.899748 -424.90173) (xy 11.812645 -424.93673) (xy 11.722888 -424.964218)
			(xy 11.631123 -424.983995) (xy 11.538011 -424.995918) (xy 11.444224 -424.999903) (xy 11.350437 -424.995918)
			(xy 11.257325 -424.983995) (xy 11.16556 -424.964218) (xy 11.075803 -424.93673) (xy 10.9887 -424.90173)
			(xy 10.904879 -424.859468) (xy 10.824944 -424.81025) (xy 10.749471 -424.754431) (xy 10.679004 -424.692412)
			(xy 10.614051 -424.62464) (xy 10.555078 -424.551605) (xy 10.502512 -424.473831) (xy 10.456731 -424.391879)
			(xy 10.418065 -424.30634) (xy 10.386793 -424.217831) (xy 10.363139 -424.126988) (xy 10.347275 -424.034466)
			(xy 10.339314 -423.940932) (xy 7.049018 -423.940932) (xy 7.041057 -424.034466) (xy 7.025193 -424.126988)
			(xy 7.001539 -424.217831) (xy 6.970267 -424.30634) (xy 6.931601 -424.391879) (xy 6.88582 -424.473831)
			(xy 6.833254 -424.551605) (xy 6.774281 -424.62464) (xy 6.709328 -424.692412) (xy 6.638861 -424.754431)
			(xy 6.563388 -424.81025) (xy 6.483453 -424.859468) (xy 6.399632 -424.90173) (xy 6.312529 -424.93673)
			(xy 6.222772 -424.964218) (xy 6.131007 -424.983995) (xy 6.037895 -424.995918) (xy 5.944108 -424.999903)
			(xy 5.850321 -424.995918) (xy 5.757209 -424.983995) (xy 5.665444 -424.964218) (xy 5.575687 -424.93673)
			(xy 5.488584 -424.90173) (xy 5.404763 -424.859468) (xy 5.324828 -424.81025) (xy 5.249355 -424.754431)
			(xy 5.178888 -424.692412) (xy 5.113935 -424.62464) (xy 5.054962 -424.551605) (xy 5.002396 -424.473831)
			(xy 4.956615 -424.391879) (xy 4.917949 -424.30634) (xy 4.886677 -424.217831) (xy 4.863023 -424.126988)
			(xy 4.847159 -424.034466) (xy 4.839198 -423.940932) (xy 1.27 -423.940932) (xy 1.27 -428.141076) (xy 4.839198 -428.141076)
			(xy 4.839198 -428.047204) (xy 4.847159 -427.95367) (xy 4.863023 -427.861148) (xy 4.886677 -427.770305)
			(xy 4.917949 -427.681796) (xy 4.956615 -427.596257) (xy 5.002396 -427.514305) (xy 5.054962 -427.436531)
			(xy 5.113935 -427.363496) (xy 5.178888 -427.295724) (xy 5.249355 -427.233705) (xy 5.324828 -427.177886)
			(xy 5.404763 -427.128668) (xy 5.488584 -427.086406) (xy 5.575687 -427.051406) (xy 5.665444 -427.023918)
			(xy 5.757209 -427.004141) (xy 5.850321 -426.992218) (xy 5.944108 -426.988234) (xy 6.037895 -426.992218)
			(xy 6.131007 -427.004141) (xy 6.222772 -427.023918) (xy 6.312529 -427.051406) (xy 6.399632 -427.086406)
			(xy 6.483453 -427.128668) (xy 6.563388 -427.177886) (xy 6.638861 -427.233705) (xy 6.709328 -427.295724)
			(xy 6.774281 -427.363496) (xy 6.833254 -427.436531) (xy 6.88582 -427.514305) (xy 6.931601 -427.596257)
			(xy 6.970267 -427.681796) (xy 7.001539 -427.770305) (xy 7.025193 -427.861148) (xy 7.041057 -427.95367)
			(xy 7.049018 -428.047204) (xy 7.049516 -428.09414) (xy 7.049018 -428.141076) (xy 7.041057 -428.23461)
			(xy 7.025193 -428.327132) (xy 7.001539 -428.417975) (xy 6.970267 -428.506484) (xy 6.931601 -428.592023)
			(xy 6.88582 -428.673975) (xy 6.833254 -428.751749) (xy 6.774281 -428.824784) (xy 6.709328 -428.892556)
			(xy 6.638861 -428.954575) (xy 6.563388 -429.010394) (xy 6.483453 -429.059612) (xy 6.399632 -429.101874)
			(xy 6.312529 -429.136874) (xy 6.222772 -429.164362) (xy 6.131007 -429.184139) (xy 6.037895 -429.196062)
			(xy 5.944108 -429.200047) (xy 5.850321 -429.196062) (xy 5.757209 -429.184139) (xy 5.665444 -429.164362)
			(xy 5.575687 -429.136874) (xy 5.488584 -429.101874) (xy 5.404763 -429.059612) (xy 5.324828 -429.010394)
			(xy 5.249355 -428.954575) (xy 5.178888 -428.892556) (xy 5.113935 -428.824784) (xy 5.054962 -428.751749)
			(xy 5.002396 -428.673975) (xy 4.956615 -428.592023) (xy 4.917949 -428.506484) (xy 4.886677 -428.417975)
			(xy 4.863023 -428.327132) (xy 4.847159 -428.23461) (xy 4.839198 -428.141076) (xy 1.27 -428.141076)
			(xy 1.27 -432.340966) (xy 4.839198 -432.340966) (xy 4.839198 -432.247094) (xy 4.847159 -432.15356)
			(xy 4.863023 -432.061038) (xy 4.886677 -431.970195) (xy 4.917949 -431.881686) (xy 4.956615 -431.796147)
			(xy 5.002396 -431.714195) (xy 5.054962 -431.636421) (xy 5.113935 -431.563386) (xy 5.178888 -431.495614)
			(xy 5.249355 -431.433595) (xy 5.324828 -431.377776) (xy 5.404763 -431.328558) (xy 5.488584 -431.286296)
			(xy 5.575687 -431.251296) (xy 5.665444 -431.223808) (xy 5.757209 -431.204031) (xy 5.850321 -431.192108)
			(xy 5.944108 -431.188124) (xy 6.037895 -431.192108) (xy 6.131007 -431.204031) (xy 6.222772 -431.223808)
			(xy 6.312529 -431.251296) (xy 6.399632 -431.286296) (xy 6.483453 -431.328558) (xy 6.563388 -431.377776)
			(xy 6.638861 -431.433595) (xy 6.709328 -431.495614) (xy 6.774281 -431.563386) (xy 6.833254 -431.636421)
			(xy 6.88582 -431.714195) (xy 6.931601 -431.796147) (xy 6.970267 -431.881686) (xy 7.001539 -431.970195)
			(xy 7.025193 -432.061038) (xy 7.041057 -432.15356) (xy 7.049018 -432.247094) (xy 7.049516 -432.29403)
			(xy 7.049018 -432.340966) (xy 7.041057 -432.4345) (xy 7.025193 -432.527022) (xy 7.001539 -432.617865)
			(xy 6.970267 -432.706374) (xy 6.931601 -432.791913) (xy 6.88582 -432.873865) (xy 6.833254 -432.951639)
			(xy 6.774281 -433.024674) (xy 6.709328 -433.092446) (xy 6.638861 -433.154465) (xy 6.563388 -433.210284)
			(xy 6.483453 -433.259502) (xy 6.399632 -433.301764) (xy 6.312529 -433.336764) (xy 6.222772 -433.364252)
			(xy 6.131007 -433.384029) (xy 6.037895 -433.395952) (xy 5.944108 -433.399937) (xy 5.850321 -433.395952)
			(xy 5.757209 -433.384029) (xy 5.665444 -433.364252) (xy 5.575687 -433.336764) (xy 5.488584 -433.301764)
			(xy 5.404763 -433.259502) (xy 5.324828 -433.210284) (xy 5.249355 -433.154465) (xy 5.178888 -433.092446)
			(xy 5.113935 -433.024674) (xy 5.054962 -432.951639) (xy 5.002396 -432.873865) (xy 4.956615 -432.791913)
			(xy 4.917949 -432.706374) (xy 4.886677 -432.617865) (xy 4.863023 -432.527022) (xy 4.847159 -432.4345)
			(xy 4.839198 -432.340966) (xy 1.27 -432.340966) (xy 1.27 -436.540856) (xy 4.839198 -436.540856) (xy 4.839198 -436.446984)
			(xy 4.847159 -436.35345) (xy 4.863023 -436.260928) (xy 4.886677 -436.170085) (xy 4.917949 -436.081576)
			(xy 4.956615 -435.996037) (xy 5.002396 -435.914085) (xy 5.054962 -435.836311) (xy 5.113935 -435.763276)
			(xy 5.178888 -435.695504) (xy 5.249355 -435.633485) (xy 5.324828 -435.577666) (xy 5.404763 -435.528448)
			(xy 5.488584 -435.486186) (xy 5.575687 -435.451186) (xy 5.665444 -435.423698) (xy 5.757209 -435.403921)
			(xy 5.850321 -435.391998) (xy 5.944108 -435.388014) (xy 6.037895 -435.391998) (xy 6.131007 -435.403921)
			(xy 6.222772 -435.423698) (xy 6.312529 -435.451186) (xy 6.399632 -435.486186) (xy 6.483453 -435.528448)
			(xy 6.563388 -435.577666) (xy 6.638861 -435.633485) (xy 6.709328 -435.695504) (xy 6.774281 -435.763276)
			(xy 6.833254 -435.836311) (xy 6.88582 -435.914085) (xy 6.931601 -435.996037) (xy 6.970267 -436.081576)
			(xy 7.001539 -436.170085) (xy 7.025193 -436.260928) (xy 7.041057 -436.35345) (xy 7.049018 -436.446984)
			(xy 7.049516 -436.49392) (xy 7.049018 -436.540856) (xy 10.339314 -436.540856) (xy 10.339314 -436.446984)
			(xy 10.347275 -436.35345) (xy 10.363139 -436.260928) (xy 10.386793 -436.170085) (xy 10.418065 -436.081576)
			(xy 10.456731 -435.996037) (xy 10.502512 -435.914085) (xy 10.555078 -435.836311) (xy 10.614051 -435.763276)
			(xy 10.679004 -435.695504) (xy 10.749471 -435.633485) (xy 10.824944 -435.577666) (xy 10.904879 -435.528448)
			(xy 10.9887 -435.486186) (xy 11.075803 -435.451186) (xy 11.16556 -435.423698) (xy 11.257325 -435.403921)
			(xy 11.350437 -435.391998) (xy 11.444224 -435.388014) (xy 11.538011 -435.391998) (xy 11.631123 -435.403921)
			(xy 11.722888 -435.423698) (xy 11.812645 -435.451186) (xy 11.899748 -435.486186) (xy 11.983569 -435.528448)
			(xy 12.063504 -435.577666) (xy 12.138977 -435.633485) (xy 12.209444 -435.695504) (xy 12.274397 -435.763276)
			(xy 12.33337 -435.836311) (xy 12.385936 -435.914085) (xy 12.431717 -435.996037) (xy 12.470383 -436.081576)
			(xy 12.501655 -436.170085) (xy 12.525309 -436.260928) (xy 12.541173 -436.35345) (xy 12.549134 -436.446984)
			(xy 12.549632 -436.49392) (xy 12.549134 -436.540856) (xy 12.541173 -436.63439) (xy 12.525309 -436.726912)
			(xy 12.501655 -436.817755) (xy 12.470383 -436.906264) (xy 12.431717 -436.991803) (xy 12.385936 -437.073755)
			(xy 12.33337 -437.151529) (xy 12.274397 -437.224564) (xy 12.209444 -437.292336) (xy 12.138977 -437.354355)
			(xy 12.063504 -437.410174) (xy 11.983569 -437.459392) (xy 11.899748 -437.501654) (xy 11.812645 -437.536654)
			(xy 11.722888 -437.564142) (xy 11.631123 -437.583919) (xy 11.538011 -437.595842) (xy 11.444224 -437.599827)
			(xy 11.350437 -437.595842) (xy 11.257325 -437.583919) (xy 11.16556 -437.564142) (xy 11.075803 -437.536654)
			(xy 10.9887 -437.501654) (xy 10.904879 -437.459392) (xy 10.824944 -437.410174) (xy 10.749471 -437.354355)
			(xy 10.679004 -437.292336) (xy 10.614051 -437.224564) (xy 10.555078 -437.151529) (xy 10.502512 -437.073755)
			(xy 10.456731 -436.991803) (xy 10.418065 -436.906264) (xy 10.386793 -436.817755) (xy 10.363139 -436.726912)
			(xy 10.347275 -436.63439) (xy 10.339314 -436.540856) (xy 7.049018 -436.540856) (xy 7.041057 -436.63439)
			(xy 7.025193 -436.726912) (xy 7.001539 -436.817755) (xy 6.970267 -436.906264) (xy 6.931601 -436.991803)
			(xy 6.88582 -437.073755) (xy 6.833254 -437.151529) (xy 6.774281 -437.224564) (xy 6.709328 -437.292336)
			(xy 6.638861 -437.354355) (xy 6.563388 -437.410174) (xy 6.483453 -437.459392) (xy 6.399632 -437.501654)
			(xy 6.312529 -437.536654) (xy 6.222772 -437.564142) (xy 6.131007 -437.583919) (xy 6.037895 -437.595842)
			(xy 5.944108 -437.599827) (xy 5.850321 -437.595842) (xy 5.757209 -437.583919) (xy 5.665444 -437.564142)
			(xy 5.575687 -437.536654) (xy 5.488584 -437.501654) (xy 5.404763 -437.459392) (xy 5.324828 -437.410174)
			(xy 5.249355 -437.354355) (xy 5.178888 -437.292336) (xy 5.113935 -437.224564) (xy 5.054962 -437.151529)
			(xy 5.002396 -437.073755) (xy 4.956615 -436.991803) (xy 4.917949 -436.906264) (xy 4.886677 -436.817755)
			(xy 4.863023 -436.726912) (xy 4.847159 -436.63439) (xy 4.839198 -436.540856) (xy 1.27 -436.540856)
			(xy 1.27 -440.741) (xy 4.839198 -440.741) (xy 4.839198 -440.647128) (xy 4.847159 -440.553594) (xy 4.863023 -440.461072)
			(xy 4.886677 -440.370229) (xy 4.917949 -440.28172) (xy 4.956615 -440.196181) (xy 5.002396 -440.114229)
			(xy 5.054962 -440.036455) (xy 5.113935 -439.96342) (xy 5.178888 -439.895648) (xy 5.249355 -439.833629)
			(xy 5.324828 -439.77781) (xy 5.404763 -439.728592) (xy 5.488584 -439.68633) (xy 5.575687 -439.65133)
			(xy 5.665444 -439.623842) (xy 5.757209 -439.604065) (xy 5.850321 -439.592142) (xy 5.944108 -439.588158)
			(xy 6.037895 -439.592142) (xy 6.131007 -439.604065) (xy 6.222772 -439.623842) (xy 6.312529 -439.65133)
			(xy 6.399632 -439.68633) (xy 6.483453 -439.728592) (xy 6.563388 -439.77781) (xy 6.638861 -439.833629)
			(xy 6.709328 -439.895648) (xy 6.774281 -439.96342) (xy 6.833254 -440.036455) (xy 6.88582 -440.114229)
			(xy 6.931601 -440.196181) (xy 6.970267 -440.28172) (xy 7.001539 -440.370229) (xy 7.025193 -440.461072)
			(xy 7.041057 -440.553594) (xy 7.049018 -440.647128) (xy 7.049516 -440.694064) (xy 7.049018 -440.741)
			(xy 7.041057 -440.834534) (xy 7.025193 -440.927056) (xy 7.001539 -441.017899) (xy 6.970267 -441.106408)
			(xy 6.931601 -441.191947) (xy 6.88582 -441.273899) (xy 6.833254 -441.351673) (xy 6.774281 -441.424708)
			(xy 6.709328 -441.49248) (xy 6.638861 -441.554499) (xy 6.563388 -441.610318) (xy 6.483453 -441.659536)
			(xy 6.399632 -441.701798) (xy 6.312529 -441.736798) (xy 6.222772 -441.764286) (xy 6.131007 -441.784063)
			(xy 6.037895 -441.795986) (xy 5.944108 -441.799971) (xy 5.850321 -441.795986) (xy 5.757209 -441.784063)
			(xy 5.665444 -441.764286) (xy 5.575687 -441.736798) (xy 5.488584 -441.701798) (xy 5.404763 -441.659536)
			(xy 5.324828 -441.610318) (xy 5.249355 -441.554499) (xy 5.178888 -441.49248) (xy 5.113935 -441.424708)
			(xy 5.054962 -441.351673) (xy 5.002396 -441.273899) (xy 4.956615 -441.191947) (xy 4.917949 -441.106408)
			(xy 4.886677 -441.017899) (xy 4.863023 -440.927056) (xy 4.847159 -440.834534) (xy 4.839198 -440.741)
			(xy 1.27 -440.741) (xy 1.27 -444.94089) (xy 4.839198 -444.94089) (xy 4.839198 -444.847018) (xy 4.847159 -444.753484)
			(xy 4.863023 -444.660962) (xy 4.886677 -444.570119) (xy 4.917949 -444.48161) (xy 4.956615 -444.396071)
			(xy 5.002396 -444.314119) (xy 5.054962 -444.236345) (xy 5.113935 -444.16331) (xy 5.178888 -444.095538)
			(xy 5.249355 -444.033519) (xy 5.324828 -443.9777) (xy 5.404763 -443.928482) (xy 5.488584 -443.88622)
			(xy 5.575687 -443.85122) (xy 5.665444 -443.823732) (xy 5.757209 -443.803955) (xy 5.850321 -443.792032)
			(xy 5.944108 -443.788048) (xy 6.037895 -443.792032) (xy 6.131007 -443.803955) (xy 6.222772 -443.823732)
			(xy 6.312529 -443.85122) (xy 6.399632 -443.88622) (xy 6.483453 -443.928482) (xy 6.563388 -443.9777)
			(xy 6.638861 -444.033519) (xy 6.709328 -444.095538) (xy 6.774281 -444.16331) (xy 6.833254 -444.236345)
			(xy 6.88582 -444.314119) (xy 6.931601 -444.396071) (xy 6.970267 -444.48161) (xy 7.001539 -444.570119)
			(xy 7.025193 -444.660962) (xy 7.041057 -444.753484) (xy 7.049018 -444.847018) (xy 7.049516 -444.893954)
			(xy 7.049018 -444.94089) (xy 7.041057 -445.034424) (xy 7.025193 -445.126946) (xy 7.001539 -445.217789)
			(xy 6.970267 -445.306298) (xy 6.931601 -445.391837) (xy 6.88582 -445.473789) (xy 6.833254 -445.551563)
			(xy 6.774281 -445.624598) (xy 6.709328 -445.69237) (xy 6.638861 -445.754389) (xy 6.563388 -445.810208)
			(xy 6.483453 -445.859426) (xy 6.399632 -445.901688) (xy 6.312529 -445.936688) (xy 6.222772 -445.964176)
			(xy 6.131007 -445.983953) (xy 6.037895 -445.995876) (xy 5.944108 -445.999861) (xy 5.850321 -445.995876)
			(xy 5.757209 -445.983953) (xy 5.665444 -445.964176) (xy 5.575687 -445.936688) (xy 5.488584 -445.901688)
			(xy 5.404763 -445.859426) (xy 5.324828 -445.810208) (xy 5.249355 -445.754389) (xy 5.178888 -445.69237)
			(xy 5.113935 -445.624598) (xy 5.054962 -445.551563) (xy 5.002396 -445.473789) (xy 4.956615 -445.391837)
			(xy 4.917949 -445.306298) (xy 4.886677 -445.217789) (xy 4.863023 -445.126946) (xy 4.847159 -445.034424)
			(xy 4.839198 -444.94089) (xy 1.27 -444.94089) (xy 1.27 -449.141034) (xy 4.839198 -449.141034) (xy 4.839198 -449.047162)
			(xy 4.847159 -448.953628) (xy 4.863023 -448.861106) (xy 4.886677 -448.770263) (xy 4.917949 -448.681754)
			(xy 4.956615 -448.596215) (xy 5.002396 -448.514263) (xy 5.054962 -448.436489) (xy 5.113935 -448.363454)
			(xy 5.178888 -448.295682) (xy 5.249355 -448.233663) (xy 5.324828 -448.177844) (xy 5.404763 -448.128626)
			(xy 5.488584 -448.086364) (xy 5.575687 -448.051364) (xy 5.665444 -448.023876) (xy 5.757209 -448.004099)
			(xy 5.850321 -447.992176) (xy 5.944108 -447.988192) (xy 6.037895 -447.992176) (xy 6.131007 -448.004099)
			(xy 6.222772 -448.023876) (xy 6.312529 -448.051364) (xy 6.399632 -448.086364) (xy 6.483453 -448.128626)
			(xy 6.563388 -448.177844) (xy 6.638861 -448.233663) (xy 6.709328 -448.295682) (xy 6.774281 -448.363454)
			(xy 6.833254 -448.436489) (xy 6.88582 -448.514263) (xy 6.931601 -448.596215) (xy 6.970267 -448.681754)
			(xy 7.001539 -448.770263) (xy 7.025193 -448.861106) (xy 7.041057 -448.953628) (xy 7.049018 -449.047162)
			(xy 7.049516 -449.094098) (xy 7.049018 -449.141034) (xy 10.339314 -449.141034) (xy 10.339314 -449.047162)
			(xy 10.347275 -448.953628) (xy 10.363139 -448.861106) (xy 10.386793 -448.770263) (xy 10.418065 -448.681754)
			(xy 10.456731 -448.596215) (xy 10.502512 -448.514263) (xy 10.555078 -448.436489) (xy 10.614051 -448.363454)
			(xy 10.679004 -448.295682) (xy 10.749471 -448.233663) (xy 10.824944 -448.177844) (xy 10.904879 -448.128626)
			(xy 10.9887 -448.086364) (xy 11.075803 -448.051364) (xy 11.16556 -448.023876) (xy 11.257325 -448.004099)
			(xy 11.350437 -447.992176) (xy 11.444224 -447.988192) (xy 11.538011 -447.992176) (xy 11.631123 -448.004099)
			(xy 11.722888 -448.023876) (xy 11.812645 -448.051364) (xy 11.899748 -448.086364) (xy 11.983569 -448.128626)
			(xy 12.063504 -448.177844) (xy 12.138977 -448.233663) (xy 12.209444 -448.295682) (xy 12.274397 -448.363454)
			(xy 12.33337 -448.436489) (xy 12.385936 -448.514263) (xy 12.431717 -448.596215) (xy 12.470383 -448.681754)
			(xy 12.501655 -448.770263) (xy 12.525309 -448.861106) (xy 12.541173 -448.953628) (xy 12.549134 -449.047162)
			(xy 12.549632 -449.094098) (xy 12.549134 -449.141034) (xy 12.541173 -449.234568) (xy 12.525309 -449.32709)
			(xy 12.501655 -449.417933) (xy 12.470383 -449.506442) (xy 12.431717 -449.591981) (xy 12.385936 -449.673933)
			(xy 12.33337 -449.751707) (xy 12.274397 -449.824742) (xy 12.209444 -449.892514) (xy 12.138977 -449.954533)
			(xy 12.063504 -450.010352) (xy 11.983569 -450.05957) (xy 11.899748 -450.101832) (xy 11.812645 -450.136832)
			(xy 11.722888 -450.16432) (xy 11.631123 -450.184097) (xy 11.538011 -450.19602) (xy 11.444224 -450.200005)
			(xy 11.350437 -450.19602) (xy 11.257325 -450.184097) (xy 11.16556 -450.16432) (xy 11.075803 -450.136832)
			(xy 10.9887 -450.101832) (xy 10.904879 -450.05957) (xy 10.824944 -450.010352) (xy 10.749471 -449.954533)
			(xy 10.679004 -449.892514) (xy 10.614051 -449.824742) (xy 10.555078 -449.751707) (xy 10.502512 -449.673933)
			(xy 10.456731 -449.591981) (xy 10.418065 -449.506442) (xy 10.386793 -449.417933) (xy 10.363139 -449.32709)
			(xy 10.347275 -449.234568) (xy 10.339314 -449.141034) (xy 7.049018 -449.141034) (xy 7.041057 -449.234568)
			(xy 7.025193 -449.32709) (xy 7.001539 -449.417933) (xy 6.970267 -449.506442) (xy 6.931601 -449.591981)
			(xy 6.88582 -449.673933) (xy 6.833254 -449.751707) (xy 6.774281 -449.824742) (xy 6.709328 -449.892514)
			(xy 6.638861 -449.954533) (xy 6.563388 -450.010352) (xy 6.483453 -450.05957) (xy 6.399632 -450.101832)
			(xy 6.312529 -450.136832) (xy 6.222772 -450.16432) (xy 6.131007 -450.184097) (xy 6.037895 -450.19602)
			(xy 5.944108 -450.200005) (xy 5.850321 -450.19602) (xy 5.757209 -450.184097) (xy 5.665444 -450.16432)
			(xy 5.575687 -450.136832) (xy 5.488584 -450.101832) (xy 5.404763 -450.05957) (xy 5.324828 -450.010352)
			(xy 5.249355 -449.954533) (xy 5.178888 -449.892514) (xy 5.113935 -449.824742) (xy 5.054962 -449.751707)
			(xy 5.002396 -449.673933) (xy 4.956615 -449.591981) (xy 4.917949 -449.506442) (xy 4.886677 -449.417933)
			(xy 4.863023 -449.32709) (xy 4.847159 -449.234568) (xy 4.839198 -449.141034) (xy 1.27 -449.141034)
			(xy 1.27 -453.340924) (xy 4.839198 -453.340924) (xy 4.839198 -453.247052) (xy 4.847159 -453.153518)
			(xy 4.863023 -453.060996) (xy 4.886677 -452.970153) (xy 4.917949 -452.881644) (xy 4.956615 -452.796105)
			(xy 5.002396 -452.714153) (xy 5.054962 -452.636379) (xy 5.113935 -452.563344) (xy 5.178888 -452.495572)
			(xy 5.249355 -452.433553) (xy 5.324828 -452.377734) (xy 5.404763 -452.328516) (xy 5.488584 -452.286254)
			(xy 5.575687 -452.251254) (xy 5.665444 -452.223766) (xy 5.757209 -452.203989) (xy 5.850321 -452.192066)
			(xy 5.944108 -452.188082) (xy 6.037895 -452.192066) (xy 6.131007 -452.203989) (xy 6.222772 -452.223766)
			(xy 6.312529 -452.251254) (xy 6.399632 -452.286254) (xy 6.483453 -452.328516) (xy 6.563388 -452.377734)
			(xy 6.638861 -452.433553) (xy 6.709328 -452.495572) (xy 6.774281 -452.563344) (xy 6.833254 -452.636379)
			(xy 6.88582 -452.714153) (xy 6.931601 -452.796105) (xy 6.970267 -452.881644) (xy 7.001539 -452.970153)
			(xy 7.025193 -453.060996) (xy 7.041057 -453.153518) (xy 7.049018 -453.247052) (xy 7.049516 -453.293988)
			(xy 7.049018 -453.340924) (xy 7.041057 -453.434458) (xy 7.025193 -453.52698) (xy 7.001539 -453.617823)
			(xy 6.970267 -453.706332) (xy 6.931601 -453.791871) (xy 6.88582 -453.873823) (xy 6.833254 -453.951597)
			(xy 6.774281 -454.024632) (xy 6.709328 -454.092404) (xy 6.638861 -454.154423) (xy 6.563388 -454.210242)
			(xy 6.483453 -454.25946) (xy 6.399632 -454.301722) (xy 6.312529 -454.336722) (xy 6.222772 -454.36421)
			(xy 6.131007 -454.383987) (xy 6.037895 -454.39591) (xy 5.944108 -454.399895) (xy 5.850321 -454.39591)
			(xy 5.757209 -454.383987) (xy 5.665444 -454.36421) (xy 5.575687 -454.336722) (xy 5.488584 -454.301722)
			(xy 5.404763 -454.25946) (xy 5.324828 -454.210242) (xy 5.249355 -454.154423) (xy 5.178888 -454.092404)
			(xy 5.113935 -454.024632) (xy 5.054962 -453.951597) (xy 5.002396 -453.873823) (xy 4.956615 -453.791871)
			(xy 4.917949 -453.706332) (xy 4.886677 -453.617823) (xy 4.863023 -453.52698) (xy 4.847159 -453.434458)
			(xy 4.839198 -453.340924) (xy 1.27 -453.340924) (xy 1.27 -457.541068) (xy 4.839198 -457.541068) (xy 4.839198 -457.447196)
			(xy 4.847159 -457.353662) (xy 4.863023 -457.26114) (xy 4.886677 -457.170297) (xy 4.917949 -457.081788)
			(xy 4.956615 -456.996249) (xy 5.002396 -456.914297) (xy 5.054962 -456.836523) (xy 5.113935 -456.763488)
			(xy 5.178888 -456.695716) (xy 5.249355 -456.633697) (xy 5.324828 -456.577878) (xy 5.404763 -456.52866)
			(xy 5.488584 -456.486398) (xy 5.575687 -456.451398) (xy 5.665444 -456.42391) (xy 5.757209 -456.404133)
			(xy 5.850321 -456.39221) (xy 5.944108 -456.388226) (xy 6.037895 -456.39221) (xy 6.131007 -456.404133)
			(xy 6.222772 -456.42391) (xy 6.312529 -456.451398) (xy 6.399632 -456.486398) (xy 6.483453 -456.52866)
			(xy 6.563388 -456.577878) (xy 6.638861 -456.633697) (xy 6.709328 -456.695716) (xy 6.774281 -456.763488)
			(xy 6.833254 -456.836523) (xy 6.88582 -456.914297) (xy 6.931601 -456.996249) (xy 6.970267 -457.081788)
			(xy 7.001539 -457.170297) (xy 7.025193 -457.26114) (xy 7.041057 -457.353662) (xy 7.049018 -457.447196)
			(xy 7.049516 -457.494132) (xy 7.049018 -457.541068) (xy 7.041057 -457.634602) (xy 7.025193 -457.727124)
			(xy 7.001539 -457.817967) (xy 6.970267 -457.906476) (xy 6.931601 -457.992015) (xy 6.88582 -458.073967)
			(xy 6.833254 -458.151741) (xy 6.774281 -458.224776) (xy 6.709328 -458.292548) (xy 6.638861 -458.354567)
			(xy 6.563388 -458.410386) (xy 6.483453 -458.459604) (xy 6.399632 -458.501866) (xy 6.312529 -458.536866)
			(xy 6.222772 -458.564354) (xy 6.131007 -458.584131) (xy 6.037895 -458.596054) (xy 5.944108 -458.600039)
			(xy 5.850321 -458.596054) (xy 5.757209 -458.584131) (xy 5.665444 -458.564354) (xy 5.575687 -458.536866)
			(xy 5.488584 -458.501866) (xy 5.404763 -458.459604) (xy 5.324828 -458.410386) (xy 5.249355 -458.354567)
			(xy 5.178888 -458.292548) (xy 5.113935 -458.224776) (xy 5.054962 -458.151741) (xy 5.002396 -458.073967)
			(xy 4.956615 -457.992015) (xy 4.917949 -457.906476) (xy 4.886677 -457.817967) (xy 4.863023 -457.727124)
			(xy 4.847159 -457.634602) (xy 4.839198 -457.541068) (xy 1.27 -457.541068) (xy 1.27 -461.740958) (xy 4.839198 -461.740958)
			(xy 4.839198 -461.647086) (xy 4.847159 -461.553552) (xy 4.863023 -461.46103) (xy 4.886677 -461.370187)
			(xy 4.917949 -461.281678) (xy 4.956615 -461.196139) (xy 5.002396 -461.114187) (xy 5.054962 -461.036413)
			(xy 5.113935 -460.963378) (xy 5.178888 -460.895606) (xy 5.249355 -460.833587) (xy 5.324828 -460.777768)
			(xy 5.404763 -460.72855) (xy 5.488584 -460.686288) (xy 5.575687 -460.651288) (xy 5.665444 -460.6238)
			(xy 5.757209 -460.604023) (xy 5.850321 -460.5921) (xy 5.944108 -460.588116) (xy 5.961811 -460.588868)
			(xy 10.338816 -460.588868) (xy 12.549632 -460.588868) (xy 12.549632 -462.799176) (xy 10.338816 -462.799176)
			(xy 10.338816 -460.588868) (xy 5.961811 -460.588868) (xy 6.037895 -460.5921) (xy 6.131007 -460.604023)
			(xy 6.222772 -460.6238) (xy 6.312529 -460.651288) (xy 6.399632 -460.686288) (xy 6.483453 -460.72855)
			(xy 6.563388 -460.777768) (xy 6.638861 -460.833587) (xy 6.709328 -460.895606) (xy 6.774281 -460.963378)
			(xy 6.833254 -461.036413) (xy 6.88582 -461.114187) (xy 6.931601 -461.196139) (xy 6.970267 -461.281678)
			(xy 7.001539 -461.370187) (xy 7.025193 -461.46103) (xy 7.041057 -461.553552) (xy 7.049018 -461.647086)
			(xy 7.049516 -461.694022) (xy 7.049018 -461.740958) (xy 7.041057 -461.834492) (xy 7.025193 -461.927014)
			(xy 7.001539 -462.017857) (xy 6.970267 -462.106366) (xy 6.931601 -462.191905) (xy 6.88582 -462.273857)
			(xy 6.833254 -462.351631) (xy 6.774281 -462.424666) (xy 6.709328 -462.492438) (xy 6.638861 -462.554457)
			(xy 6.563388 -462.610276) (xy 6.483453 -462.659494) (xy 6.399632 -462.701756) (xy 6.312529 -462.736756)
			(xy 6.222772 -462.764244) (xy 6.131007 -462.784021) (xy 6.037895 -462.795944) (xy 5.944108 -462.799929)
			(xy 5.850321 -462.795944) (xy 5.757209 -462.784021) (xy 5.665444 -462.764244) (xy 5.575687 -462.736756)
			(xy 5.488584 -462.701756) (xy 5.404763 -462.659494) (xy 5.324828 -462.610276) (xy 5.249355 -462.554457)
			(xy 5.178888 -462.492438) (xy 5.113935 -462.424666) (xy 5.054962 -462.351631) (xy 5.002396 -462.273857)
			(xy 4.956615 -462.191905) (xy 4.917949 -462.106366) (xy 4.886677 -462.017857) (xy 4.863023 -461.927014)
			(xy 4.847159 -461.834492) (xy 4.839198 -461.740958) (xy 1.27 -461.740958) (xy 1.27 -464.413362) (xy 29.519874 -464.413362)
			(xy 29.519874 -464.326462) (xy 29.527892 -464.239933) (xy 29.54386 -464.154513) (xy 29.567641 -464.070931)
			(xy 29.599033 -463.989899) (xy 29.637767 -463.91211) (xy 29.683514 -463.838226) (xy 29.735883 -463.768879)
			(xy 29.794427 -463.704659) (xy 29.858647 -463.646115) (xy 29.927994 -463.593746) (xy 30.001878 -463.547999)
			(xy 30.079667 -463.509265) (xy 30.160699 -463.477873) (xy 30.244281 -463.454092) (xy 30.329701 -463.438124)
			(xy 30.41623 -463.430106) (xy 30.50313 -463.430106) (xy 30.589659 -463.438124) (xy 30.675079 -463.454092)
			(xy 30.758661 -463.477873) (xy 30.839693 -463.509265) (xy 30.917482 -463.547999) (xy 30.991366 -463.593746)
			(xy 31.060713 -463.646115) (xy 31.124933 -463.704659) (xy 31.183477 -463.768879) (xy 31.235846 -463.838226)
			(xy 31.281593 -463.91211) (xy 31.320327 -463.989899) (xy 31.351719 -464.070931) (xy 31.3755 -464.154513)
			(xy 31.391468 -464.239933) (xy 31.399486 -464.326462) (xy 31.399988 -464.369912) (xy 31.399486 -464.413362)
			(xy 31.391468 -464.499891) (xy 31.3755 -464.585311) (xy 31.351719 -464.668893) (xy 31.320327 -464.749925)
			(xy 31.281593 -464.827714) (xy 31.235846 -464.901598) (xy 31.183477 -464.970945) (xy 31.124933 -465.035165)
			(xy 31.060713 -465.093709) (xy 30.991366 -465.146078) (xy 30.917482 -465.191825) (xy 30.839693 -465.230559)
			(xy 30.758661 -465.261951) (xy 30.675079 -465.285732) (xy 30.589659 -465.3017) (xy 30.50313 -465.309718)
			(xy 30.41623 -465.309718) (xy 30.329701 -465.3017) (xy 30.244281 -465.285732) (xy 30.160699 -465.261951)
			(xy 30.079667 -465.230559) (xy 30.001878 -465.191825) (xy 29.927994 -465.146078) (xy 29.858647 -465.093709)
			(xy 29.794427 -465.035165) (xy 29.735883 -464.970945) (xy 29.683514 -464.901598) (xy 29.637767 -464.827714)
			(xy 29.599033 -464.749925) (xy 29.567641 -464.668893) (xy 29.54386 -464.585311) (xy 29.527892 -464.499891)
			(xy 29.519874 -464.413362) (xy 1.27 -464.413362) (xy 1.27 -473.69984) (xy 8.597656 -473.69984) (xy 8.601644 -473.44722)
			(xy 8.613605 -473.194852) (xy 8.633527 -472.942988) (xy 8.661391 -472.691878) (xy 8.697167 -472.441772)
			(xy 8.740821 -472.192921) (xy 8.79231 -471.945572) (xy 8.851581 -471.699971) (xy 8.918576 -471.456364)
			(xy 8.993227 -471.214994) (xy 9.075462 -470.9761) (xy 9.165196 -470.739922) (xy 9.262342 -470.506694)
			(xy 9.366802 -470.276648) (xy 9.478473 -470.050016) (xy 9.597242 -469.827021) (xy 9.722991 -469.607887)
			(xy 9.855596 -469.392832) (xy 9.994923 -469.18207) (xy 10.140835 -468.975812) (xy 10.293185 -468.774263)
			(xy 10.451821 -468.577623) (xy 10.616586 -468.38609) (xy 10.787316 -468.199853) (xy 10.96384 -468.019099)
			(xy 11.145982 -467.844008) (xy 11.33356 -467.674754) (xy 11.526388 -467.511505) (xy 11.724273 -467.354426)
			(xy 11.927019 -467.203671) (xy 12.134423 -467.059393) (xy 12.346278 -466.921733) (xy 12.562373 -466.79083)
			(xy 12.782493 -466.666814) (xy 13.006418 -466.549809) (xy 13.233925 -466.439931) (xy 13.464787 -466.33729)
			(xy 13.698775 -466.241988) (xy 13.935654 -466.154121) (xy 14.17519 -466.073774) (xy 14.417142 -466.00103)
			(xy 14.66127 -465.93596) (xy 14.907331 -465.87863) (xy 15.155079 -465.829096) (xy 15.404267 -465.787407)
			(xy 15.654647 -465.753606) (xy 15.905969 -465.727725) (xy 16.157983 -465.709792) (xy 16.410437 -465.699823)
			(xy 16.663081 -465.697829) (xy 16.915661 -465.703811) (xy 17.167927 -465.717764) (xy 17.419626 -465.739674)
			(xy 17.670509 -465.769518) (xy 17.920324 -465.807268) (xy 18.168823 -465.852885) (xy 18.415758 -465.906324)
			(xy 18.660883 -465.967532) (xy 18.903953 -466.036447) (xy 19.144727 -466.113002) (xy 19.382964 -466.197119)
			(xy 19.618427 -466.288716) (xy 19.850881 -466.3877) (xy 20.080095 -466.493972) (xy 20.305839 -466.607428)
			(xy 20.527889 -466.727953) (xy 20.746023 -466.855429) (xy 20.902078 -466.953362) (xy 29.519874 -466.953362)
			(xy 29.519874 -466.866462) (xy 29.527892 -466.779933) (xy 29.54386 -466.694513) (xy 29.567641 -466.610931)
			(xy 29.599033 -466.529899) (xy 29.637767 -466.45211) (xy 29.683514 -466.378226) (xy 29.735883 -466.308879)
			(xy 29.794427 -466.244659) (xy 29.858647 -466.186115) (xy 29.927994 -466.133746) (xy 30.001878 -466.087999)
			(xy 30.079667 -466.049265) (xy 30.160699 -466.017873) (xy 30.244281 -465.994092) (xy 30.329701 -465.978124)
			(xy 30.41623 -465.970106) (xy 30.50313 -465.970106) (xy 30.589659 -465.978124) (xy 30.675079 -465.994092)
			(xy 30.758661 -466.017873) (xy 30.839693 -466.049265) (xy 30.917482 -466.087999) (xy 30.991366 -466.133746)
			(xy 31.060713 -466.186115) (xy 31.124933 -466.244659) (xy 31.183477 -466.308879) (xy 31.235846 -466.378226)
			(xy 31.281593 -466.45211) (xy 31.320327 -466.529899) (xy 31.351719 -466.610931) (xy 31.3755 -466.694513)
			(xy 31.391468 -466.779933) (xy 31.399486 -466.866462) (xy 31.399988 -466.909912) (xy 31.399486 -466.953362)
			(xy 34.599874 -466.953362) (xy 34.599874 -466.866462) (xy 34.607892 -466.779933) (xy 34.62386 -466.694513)
			(xy 34.647641 -466.610931) (xy 34.679033 -466.529899) (xy 34.717767 -466.45211) (xy 34.763514 -466.378226)
			(xy 34.815883 -466.308879) (xy 34.874427 -466.244659) (xy 34.938647 -466.186115) (xy 35.007994 -466.133746)
			(xy 35.081878 -466.087999) (xy 35.159667 -466.049265) (xy 35.240699 -466.017873) (xy 35.324281 -465.994092)
			(xy 35.409701 -465.978124) (xy 35.49623 -465.970106) (xy 35.58313 -465.970106) (xy 35.669659 -465.978124)
			(xy 35.755079 -465.994092) (xy 35.838661 -466.017873) (xy 35.919693 -466.049265) (xy 35.997482 -466.087999)
			(xy 36.071366 -466.133746) (xy 36.140713 -466.186115) (xy 36.204933 -466.244659) (xy 36.263477 -466.308879)
			(xy 36.315846 -466.378226) (xy 36.361593 -466.45211) (xy 36.400327 -466.529899) (xy 36.431719 -466.610931)
			(xy 36.4555 -466.694513) (xy 36.471468 -466.779933) (xy 36.479486 -466.866462) (xy 36.479988 -466.909912)
			(xy 36.479486 -466.953362) (xy 36.471468 -467.039891) (xy 36.4555 -467.125311) (xy 36.431719 -467.208893)
			(xy 36.400327 -467.289925) (xy 36.361593 -467.367714) (xy 36.315846 -467.441598) (xy 36.263477 -467.510945)
			(xy 36.204933 -467.575165) (xy 36.140713 -467.633709) (xy 36.071366 -467.686078) (xy 35.997482 -467.731825)
			(xy 35.919693 -467.770559) (xy 35.838661 -467.801951) (xy 35.755079 -467.825732) (xy 35.669659 -467.8417)
			(xy 35.58313 -467.849718) (xy 35.49623 -467.849718) (xy 35.409701 -467.8417) (xy 35.324281 -467.825732)
			(xy 35.240699 -467.801951) (xy 35.159667 -467.770559) (xy 35.081878 -467.731825) (xy 35.007994 -467.686078)
			(xy 34.938647 -467.633709) (xy 34.874427 -467.575165) (xy 34.815883 -467.510945) (xy 34.763514 -467.441598)
			(xy 34.717767 -467.367714) (xy 34.679033 -467.289925) (xy 34.647641 -467.208893) (xy 34.62386 -467.125311)
			(xy 34.607892 -467.039891) (xy 34.599874 -466.953362) (xy 31.399486 -466.953362) (xy 31.391468 -467.039891)
			(xy 31.3755 -467.125311) (xy 31.351719 -467.208893) (xy 31.320327 -467.289925) (xy 31.281593 -467.367714)
			(xy 31.235846 -467.441598) (xy 31.183477 -467.510945) (xy 31.124933 -467.575165) (xy 31.060713 -467.633709)
			(xy 30.991366 -467.686078) (xy 30.917482 -467.731825) (xy 30.839693 -467.770559) (xy 30.758661 -467.801951)
			(xy 30.675079 -467.825732) (xy 30.589659 -467.8417) (xy 30.50313 -467.849718) (xy 30.41623 -467.849718)
			(xy 30.329701 -467.8417) (xy 30.244281 -467.825732) (xy 30.160699 -467.801951) (xy 30.079667 -467.770559)
			(xy 30.001878 -467.731825) (xy 29.927994 -467.686078) (xy 29.858647 -467.633709) (xy 29.794427 -467.575165)
			(xy 29.735883 -467.510945) (xy 29.683514 -467.441598) (xy 29.637767 -467.367714) (xy 29.599033 -467.289925)
			(xy 29.567641 -467.208893) (xy 29.54386 -467.125311) (xy 29.527892 -467.039891) (xy 29.519874 -466.953362)
			(xy 20.902078 -466.953362) (xy 20.960025 -466.989727) (xy 21.169681 -467.130713) (xy 21.374781 -467.278248)
			(xy 21.575121 -467.432184) (xy 21.770502 -467.592368) (xy 21.960729 -467.75864) (xy 22.145612 -467.930835)
			(xy 22.324968 -468.108779) (xy 22.498616 -468.292298) (xy 22.666384 -468.481206) (xy 22.828105 -468.675317)
			(xy 22.983618 -468.874436) (xy 23.132767 -469.078365) (xy 23.275404 -469.286901) (xy 23.407253 -469.493362)
			(xy 29.519874 -469.493362) (xy 29.519874 -469.406462) (xy 29.527892 -469.319933) (xy 29.54386 -469.234513)
			(xy 29.567641 -469.150931) (xy 29.599033 -469.069899) (xy 29.637767 -468.99211) (xy 29.683514 -468.918226)
			(xy 29.735883 -468.848879) (xy 29.794427 -468.784659) (xy 29.858647 -468.726115) (xy 29.927994 -468.673746)
			(xy 30.001878 -468.627999) (xy 30.079667 -468.589265) (xy 30.160699 -468.557873) (xy 30.244281 -468.534092)
			(xy 30.329701 -468.518124) (xy 30.41623 -468.510106) (xy 30.50313 -468.510106) (xy 30.589659 -468.518124)
			(xy 30.675079 -468.534092) (xy 30.758661 -468.557873) (xy 30.839693 -468.589265) (xy 30.917482 -468.627999)
			(xy 30.991366 -468.673746) (xy 31.060713 -468.726115) (xy 31.124933 -468.784659) (xy 31.183477 -468.848879)
			(xy 31.235846 -468.918226) (xy 31.281593 -468.99211) (xy 31.320327 -469.069899) (xy 31.351719 -469.150931)
			(xy 31.3755 -469.234513) (xy 31.391468 -469.319933) (xy 31.399486 -469.406462) (xy 31.399988 -469.449912)
			(xy 31.399486 -469.493362) (xy 34.599874 -469.493362) (xy 34.599874 -469.406462) (xy 34.607892 -469.319933)
			(xy 34.62386 -469.234513) (xy 34.647641 -469.150931) (xy 34.679033 -469.069899) (xy 34.717767 -468.99211)
			(xy 34.763514 -468.918226) (xy 34.815883 -468.848879) (xy 34.874427 -468.784659) (xy 34.938647 -468.726115)
			(xy 35.007994 -468.673746) (xy 35.081878 -468.627999) (xy 35.159667 -468.589265) (xy 35.240699 -468.557873)
			(xy 35.324281 -468.534092) (xy 35.409701 -468.518124) (xy 35.49623 -468.510106) (xy 35.58313 -468.510106)
			(xy 35.669659 -468.518124) (xy 35.755079 -468.534092) (xy 35.838661 -468.557873) (xy 35.919693 -468.589265)
			(xy 35.997482 -468.627999) (xy 36.071366 -468.673746) (xy 36.140713 -468.726115) (xy 36.204933 -468.784659)
			(xy 36.263477 -468.848879) (xy 36.315846 -468.918226) (xy 36.361593 -468.99211) (xy 36.400327 -469.069899)
			(xy 36.431719 -469.150931) (xy 36.4555 -469.234513) (xy 36.471468 -469.319933) (xy 36.479486 -469.406462)
			(xy 36.479988 -469.449912) (xy 36.479486 -469.493362) (xy 36.471468 -469.579891) (xy 36.4555 -469.665311)
			(xy 36.431719 -469.748893) (xy 36.400327 -469.829925) (xy 36.361593 -469.907714) (xy 36.315846 -469.981598)
			(xy 36.263477 -470.050945) (xy 36.204933 -470.115165) (xy 36.140713 -470.173709) (xy 36.071366 -470.226078)
			(xy 35.997482 -470.271825) (xy 35.919693 -470.310559) (xy 35.838661 -470.341951) (xy 35.755079 -470.365732)
			(xy 35.669659 -470.3817) (xy 35.58313 -470.389718) (xy 35.49623 -470.389718) (xy 35.409701 -470.3817)
			(xy 35.324281 -470.365732) (xy 35.240699 -470.341951) (xy 35.159667 -470.310559) (xy 35.081878 -470.271825)
			(xy 35.007994 -470.226078) (xy 34.938647 -470.173709) (xy 34.874427 -470.115165) (xy 34.815883 -470.050945)
			(xy 34.763514 -469.981598) (xy 34.717767 -469.907714) (xy 34.679033 -469.829925) (xy 34.647641 -469.748893)
			(xy 34.62386 -469.665311) (xy 34.607892 -469.579891) (xy 34.599874 -469.493362) (xy 31.399486 -469.493362)
			(xy 31.391468 -469.579891) (xy 31.3755 -469.665311) (xy 31.351719 -469.748893) (xy 31.320327 -469.829925)
			(xy 31.281593 -469.907714) (xy 31.235846 -469.981598) (xy 31.183477 -470.050945) (xy 31.124933 -470.115165)
			(xy 31.060713 -470.173709) (xy 30.991366 -470.226078) (xy 30.917482 -470.271825) (xy 30.839693 -470.310559)
			(xy 30.758661 -470.341951) (xy 30.675079 -470.365732) (xy 30.589659 -470.3817) (xy 30.50313 -470.389718)
			(xy 30.41623 -470.389718) (xy 30.329701 -470.3817) (xy 30.244281 -470.365732) (xy 30.160699 -470.341951)
			(xy 30.079667 -470.310559) (xy 30.001878 -470.271825) (xy 29.927994 -470.226078) (xy 29.858647 -470.173709)
			(xy 29.794427 -470.115165) (xy 29.735883 -470.050945) (xy 29.683514 -469.981598) (xy 29.637767 -469.907714)
			(xy 29.599033 -469.829925) (xy 29.567641 -469.748893) (xy 29.54386 -469.665311) (xy 29.527892 -469.579891)
			(xy 29.519874 -469.493362) (xy 23.407253 -469.493362) (xy 23.411387 -469.499836) (xy 23.54058 -469.716958)
			(xy 23.662855 -469.93805) (xy 23.778089 -470.162891) (xy 23.886168 -470.391259) (xy 23.986983 -470.622924)
			(xy 24.080435 -470.857657) (xy 24.16643 -471.095222) (xy 24.244883 -471.335384) (xy 24.315715 -471.577903)
			(xy 24.378856 -471.822538) (xy 24.426226 -472.033362) (xy 29.519874 -472.033362) (xy 29.519874 -471.946462)
			(xy 29.527892 -471.859933) (xy 29.54386 -471.774513) (xy 29.567641 -471.690931) (xy 29.599033 -471.609899)
			(xy 29.637767 -471.53211) (xy 29.683514 -471.458226) (xy 29.735883 -471.388879) (xy 29.794427 -471.324659)
			(xy 29.858647 -471.266115) (xy 29.927994 -471.213746) (xy 30.001878 -471.167999) (xy 30.079667 -471.129265)
			(xy 30.160699 -471.097873) (xy 30.244281 -471.074092) (xy 30.329701 -471.058124) (xy 30.41623 -471.050106)
			(xy 30.50313 -471.050106) (xy 30.589659 -471.058124) (xy 30.675079 -471.074092) (xy 30.758661 -471.097873)
			(xy 30.839693 -471.129265) (xy 30.917482 -471.167999) (xy 30.991366 -471.213746) (xy 31.060713 -471.266115)
			(xy 31.124933 -471.324659) (xy 31.183477 -471.388879) (xy 31.235846 -471.458226) (xy 31.281593 -471.53211)
			(xy 31.320327 -471.609899) (xy 31.351719 -471.690931) (xy 31.3755 -471.774513) (xy 31.391468 -471.859933)
			(xy 31.399486 -471.946462) (xy 31.399988 -471.989912) (xy 31.399486 -472.033362) (xy 34.599874 -472.033362)
			(xy 34.599874 -471.946462) (xy 34.607892 -471.859933) (xy 34.62386 -471.774513) (xy 34.647641 -471.690931)
			(xy 34.679033 -471.609899) (xy 34.717767 -471.53211) (xy 34.763514 -471.458226) (xy 34.815883 -471.388879)
			(xy 34.874427 -471.324659) (xy 34.938647 -471.266115) (xy 35.007994 -471.213746) (xy 35.081878 -471.167999)
			(xy 35.159667 -471.129265) (xy 35.240699 -471.097873) (xy 35.324281 -471.074092) (xy 35.409701 -471.058124)
			(xy 35.49623 -471.050106) (xy 35.58313 -471.050106) (xy 35.669659 -471.058124) (xy 35.755079 -471.074092)
			(xy 35.838661 -471.097873) (xy 35.919693 -471.129265) (xy 35.997482 -471.167999) (xy 36.071366 -471.213746)
			(xy 36.140713 -471.266115) (xy 36.204933 -471.324659) (xy 36.263477 -471.388879) (xy 36.315846 -471.458226)
			(xy 36.361593 -471.53211) (xy 36.400327 -471.609899) (xy 36.431719 -471.690931) (xy 36.4555 -471.774513)
			(xy 36.471468 -471.859933) (xy 36.479486 -471.946462) (xy 36.479988 -471.989912) (xy 36.479486 -472.033362)
			(xy 36.471468 -472.119891) (xy 36.468956 -472.133331) (xy 70.698381 -472.133331) (xy 70.698381 -472.070069)
			(xy 70.706638 -472.007349) (xy 70.72301 -471.946242) (xy 70.747218 -471.887796) (xy 70.778848 -471.833008)
			(xy 70.817357 -471.782818) (xy 70.862088 -471.738084) (xy 70.912275 -471.69957) (xy 70.96706 -471.667936)
			(xy 71.025504 -471.643723) (xy 71.086609 -471.627346) (xy 71.149329 -471.619084) (xy 71.18096 -471.618564)
			(xy 72.553576 -471.618564) (xy 72.581843 -471.61901) (xy 72.637986 -471.625657) (xy 72.692971 -471.638805)
			(xy 72.746048 -471.658274) (xy 72.796492 -471.683799) (xy 72.820276 -471.699082) (xy 72.85228 -471.720164)
			(xy 73.015094 -471.720164) (xy 73.048876 -471.694764) (xy 73.075345 -471.675556) (xy 73.132284 -471.64338)
			(xy 73.192874 -471.618762) (xy 73.256119 -471.602107) (xy 73.320976 -471.593689) (xy 73.353676 -471.593164)
			(xy 74.575924 -471.593164) (xy 74.607882 -471.593723) (xy 74.671295 -471.601737) (xy 74.733203 -471.617635)
			(xy 74.79263 -471.641166) (xy 74.848639 -471.67196) (xy 74.900348 -471.709531) (xy 74.94694 -471.753286)
			(xy 74.987681 -471.802535) (xy 75.021928 -471.856503) (xy 75.049142 -471.914336) (xy 75.068893 -471.975125)
			(xy 75.080869 -472.037909) (xy 75.084883 -472.1017) (xy 75.080869 -472.165491) (xy 75.068893 -472.228275)
			(xy 75.049142 -472.289064) (xy 75.021928 -472.346897) (xy 74.987681 -472.400865) (xy 74.94694 -472.450114)
			(xy 74.900348 -472.493869) (xy 74.848639 -472.53144) (xy 74.79263 -472.562234) (xy 74.733203 -472.585765)
			(xy 74.671295 -472.601663) (xy 74.607882 -472.609677) (xy 74.575924 -472.61018) (xy 73.353676 -472.61018)
			(xy 73.320974 -472.609669) (xy 73.256111 -472.601273) (xy 73.192861 -472.584623) (xy 73.132272 -472.559994)
			(xy 73.075343 -472.527794) (xy 73.048876 -472.50858) (xy 73.015094 -472.48318) (xy 72.85228 -472.48318)
			(xy 72.820276 -472.504262) (xy 72.796496 -472.519554) (xy 72.746061 -472.545108) (xy 72.692984 -472.564591)
			(xy 72.637995 -472.577737) (xy 72.581845 -472.584366) (xy 72.553576 -472.58478) (xy 71.18096 -472.58478)
			(xy 71.149329 -472.584316) (xy 71.086609 -472.576054) (xy 71.025504 -472.559677) (xy 70.96706 -472.535464)
			(xy 70.912275 -472.50383) (xy 70.862088 -472.465316) (xy 70.817357 -472.420582) (xy 70.778848 -472.370392)
			(xy 70.747218 -472.315604) (xy 70.72301 -472.257158) (xy 70.706638 -472.196051) (xy 70.698381 -472.133331)
			(xy 36.468956 -472.133331) (xy 36.4555 -472.205311) (xy 36.431719 -472.288893) (xy 36.400327 -472.369925)
			(xy 36.361593 -472.447714) (xy 36.315846 -472.521598) (xy 36.263477 -472.590945) (xy 36.204933 -472.655165)
			(xy 36.140713 -472.713709) (xy 36.071366 -472.766078) (xy 35.997482 -472.811825) (xy 35.919693 -472.850559)
			(xy 35.838661 -472.881951) (xy 35.755079 -472.905732) (xy 35.669659 -472.9217) (xy 35.58313 -472.929718)
			(xy 35.49623 -472.929718) (xy 35.409701 -472.9217) (xy 35.324281 -472.905732) (xy 35.240699 -472.881951)
			(xy 35.159667 -472.850559) (xy 35.081878 -472.811825) (xy 35.007994 -472.766078) (xy 34.938647 -472.713709)
			(xy 34.874427 -472.655165) (xy 34.815883 -472.590945) (xy 34.763514 -472.521598) (xy 34.717767 -472.447714)
			(xy 34.679033 -472.369925) (xy 34.647641 -472.288893) (xy 34.62386 -472.205311) (xy 34.607892 -472.119891)
			(xy 34.599874 -472.033362) (xy 31.399486 -472.033362) (xy 31.391468 -472.119891) (xy 31.3755 -472.205311)
			(xy 31.351719 -472.288893) (xy 31.320327 -472.369925) (xy 31.281593 -472.447714) (xy 31.235846 -472.521598)
			(xy 31.183477 -472.590945) (xy 31.124933 -472.655165) (xy 31.060713 -472.713709) (xy 30.991366 -472.766078)
			(xy 30.917482 -472.811825) (xy 30.839693 -472.850559) (xy 30.758661 -472.881951) (xy 30.675079 -472.905732)
			(xy 30.589659 -472.9217) (xy 30.50313 -472.929718) (xy 30.41623 -472.929718) (xy 30.329701 -472.9217)
			(xy 30.244281 -472.905732) (xy 30.160699 -472.881951) (xy 30.079667 -472.850559) (xy 30.001878 -472.811825)
			(xy 29.927994 -472.766078) (xy 29.858647 -472.713709) (xy 29.794427 -472.655165) (xy 29.735883 -472.590945)
			(xy 29.683514 -472.521598) (xy 29.637767 -472.447714) (xy 29.599033 -472.369925) (xy 29.567641 -472.288893)
			(xy 29.54386 -472.205311) (xy 29.527892 -472.119891) (xy 29.519874 -472.033362) (xy 24.426226 -472.033362)
			(xy 24.434243 -472.069043) (xy 24.48182 -472.317174) (xy 24.52154 -472.566684) (xy 24.553364 -472.817323)
			(xy 24.57726 -473.068841) (xy 24.593204 -473.320989) (xy 24.601179 -473.573514) (xy 24.601678 -473.69984)
			(xy 24.601179 -473.826166) (xy 24.593204 -474.078691) (xy 24.57726 -474.330839) (xy 24.554219 -474.573362)
			(xy 29.519874 -474.573362) (xy 29.519874 -474.486462) (xy 29.527892 -474.399933) (xy 29.54386 -474.314513)
			(xy 29.567641 -474.230931) (xy 29.599033 -474.149899) (xy 29.637767 -474.07211) (xy 29.683514 -473.998226)
			(xy 29.735883 -473.928879) (xy 29.794427 -473.864659) (xy 29.858647 -473.806115) (xy 29.927994 -473.753746)
			(xy 30.001878 -473.707999) (xy 30.079667 -473.669265) (xy 30.160699 -473.637873) (xy 30.244281 -473.614092)
			(xy 30.329701 -473.598124) (xy 30.41623 -473.590106) (xy 30.50313 -473.590106) (xy 30.589659 -473.598124)
			(xy 30.675079 -473.614092) (xy 30.758661 -473.637873) (xy 30.839693 -473.669265) (xy 30.917482 -473.707999)
			(xy 30.991366 -473.753746) (xy 31.060713 -473.806115) (xy 31.124933 -473.864659) (xy 31.183477 -473.928879)
			(xy 31.235846 -473.998226) (xy 31.281593 -474.07211) (xy 31.320327 -474.149899) (xy 31.351719 -474.230931)
			(xy 31.3755 -474.314513) (xy 31.391468 -474.399933) (xy 31.399486 -474.486462) (xy 31.399988 -474.529912)
			(xy 31.399486 -474.573362) (xy 34.599874 -474.573362) (xy 34.599874 -474.486462) (xy 34.607892 -474.399933)
			(xy 34.62386 -474.314513) (xy 34.647641 -474.230931) (xy 34.679033 -474.149899) (xy 34.717767 -474.07211)
			(xy 34.763514 -473.998226) (xy 34.815883 -473.928879) (xy 34.874427 -473.864659) (xy 34.938647 -473.806115)
			(xy 35.007994 -473.753746) (xy 35.081878 -473.707999) (xy 35.159667 -473.669265) (xy 35.240699 -473.637873)
			(xy 35.324281 -473.614092) (xy 35.409701 -473.598124) (xy 35.49623 -473.590106) (xy 35.58313 -473.590106)
			(xy 35.669659 -473.598124) (xy 35.755079 -473.614092) (xy 35.838661 -473.637873) (xy 35.919693 -473.669265)
			(xy 35.997482 -473.707999) (xy 36.071366 -473.753746) (xy 36.140713 -473.806115) (xy 36.204933 -473.864659)
			(xy 36.263477 -473.928879) (xy 36.315846 -473.998226) (xy 36.317206 -474.000423) (xy 37.996106 -474.000423)
			(xy 37.996106 -473.929101) (xy 38.004092 -473.858227) (xy 38.019962 -473.788692) (xy 38.043519 -473.721372)
			(xy 38.074464 -473.657113) (xy 38.11241 -473.596722) (xy 38.156879 -473.54096) (xy 38.207312 -473.490527)
			(xy 38.263074 -473.446058) (xy 38.323465 -473.408112) (xy 38.387724 -473.377167) (xy 38.455044 -473.35361)
			(xy 38.524579 -473.33774) (xy 38.595453 -473.329754) (xy 38.666775 -473.329754) (xy 38.737649 -473.33774)
			(xy 38.807184 -473.35361) (xy 38.874504 -473.377167) (xy 38.938763 -473.408112) (xy 38.999154 -473.446058)
			(xy 39.054916 -473.490527) (xy 39.105349 -473.54096) (xy 39.149818 -473.596722) (xy 39.187764 -473.657113)
			(xy 39.218709 -473.721372) (xy 39.242266 -473.788692) (xy 39.258136 -473.858227) (xy 39.266122 -473.929101)
			(xy 39.266622 -473.964762) (xy 39.266122 -474.000423) (xy 39.882818 -474.000423) (xy 39.882818 -473.929101)
			(xy 39.890804 -473.858227) (xy 39.906674 -473.788692) (xy 39.930231 -473.721372) (xy 39.961176 -473.657113)
			(xy 39.999122 -473.596722) (xy 40.043591 -473.54096) (xy 40.094024 -473.490527) (xy 40.149786 -473.446058)
			(xy 40.210177 -473.408112) (xy 40.274436 -473.377167) (xy 40.341756 -473.35361) (xy 40.411291 -473.33774)
			(xy 40.482165 -473.329754) (xy 40.553487 -473.329754) (xy 40.624361 -473.33774) (xy 40.693896 -473.35361)
			(xy 40.761216 -473.377167) (xy 40.825475 -473.408112) (xy 40.885866 -473.446058) (xy 40.941628 -473.490527)
			(xy 40.992061 -473.54096) (xy 41.03653 -473.596722) (xy 41.05814 -473.631115) (xy 70.63155 -473.631115)
			(xy 70.63155 -473.567885) (xy 70.639804 -473.505196) (xy 70.656169 -473.44412) (xy 70.680366 -473.385703)
			(xy 70.711981 -473.330945) (xy 70.750474 -473.280781) (xy 70.795184 -473.236071) (xy 70.845348 -473.197579)
			(xy 70.900107 -473.165964) (xy 70.958524 -473.141768) (xy 71.0196 -473.125403) (xy 71.082289 -473.11715)
			(xy 71.113904 -473.116656) (xy 72.532748 -473.116656) (xy 72.561036 -473.117031) (xy 72.617231 -473.123587)
			(xy 72.672273 -473.136673) (xy 72.725405 -473.15611) (xy 72.775898 -473.181631) (xy 72.799702 -473.19692)
			(xy 72.831452 -473.218256) (xy 72.888856 -473.218256) (xy 72.888856 -473.27312) (xy 72.908721 -473.295438)
			(xy 72.943348 -473.34413) (xy 72.971706 -473.396721) (xy 72.993362 -473.452407) (xy 73.007985 -473.510339)
			(xy 73.015353 -473.569633) (xy 73.015352 -473.629382) (xy 73.007982 -473.688675) (xy 72.993357 -473.746607)
			(xy 72.9717 -473.802293) (xy 72.94334 -473.854883) (xy 72.908712 -473.903574) (xy 72.888856 -473.9259)
			(xy 72.888856 -473.980764) (xy 72.831452 -473.980764) (xy 72.799702 -474.0021) (xy 72.775889 -474.017371)
			(xy 72.725388 -474.042866) (xy 72.672257 -474.062293) (xy 72.617221 -474.075388) (xy 72.561034 -474.081971)
			(xy 72.532748 -474.082364) (xy 71.113904 -474.082364) (xy 71.082289 -474.08185) (xy 71.0196 -474.073597)
			(xy 70.958524 -474.057232) (xy 70.900107 -474.033036) (xy 70.845348 -474.001421) (xy 70.795184 -473.962929)
			(xy 70.750474 -473.918219) (xy 70.711981 -473.868055) (xy 70.680366 -473.813297) (xy 70.656169 -473.75488)
			(xy 70.639804 -473.693804) (xy 70.63155 -473.631115) (xy 41.05814 -473.631115) (xy 41.074476 -473.657113)
			(xy 41.105421 -473.721372) (xy 41.128978 -473.788692) (xy 41.144848 -473.858227) (xy 41.152834 -473.929101)
			(xy 41.153334 -473.964762) (xy 41.152834 -474.000423) (xy 41.144848 -474.071297) (xy 41.128978 -474.140832)
			(xy 41.105421 -474.208152) (xy 41.074476 -474.272411) (xy 41.03653 -474.332802) (xy 40.992061 -474.388564)
			(xy 40.941628 -474.438997) (xy 40.885866 -474.483466) (xy 40.825475 -474.521412) (xy 40.761216 -474.552357)
			(xy 40.693896 -474.575914) (xy 40.624361 -474.591784) (xy 40.553487 -474.59977) (xy 40.482165 -474.59977)
			(xy 40.411291 -474.591784) (xy 40.341756 -474.575914) (xy 40.274436 -474.552357) (xy 40.210177 -474.521412)
			(xy 40.149786 -474.483466) (xy 40.094024 -474.438997) (xy 40.043591 -474.388564) (xy 39.999122 -474.332802)
			(xy 39.961176 -474.272411) (xy 39.930231 -474.208152) (xy 39.906674 -474.140832) (xy 39.890804 -474.071297)
			(xy 39.882818 -474.000423) (xy 39.266122 -474.000423) (xy 39.258136 -474.071297) (xy 39.242266 -474.140832)
			(xy 39.218709 -474.208152) (xy 39.187764 -474.272411) (xy 39.149818 -474.332802) (xy 39.105349 -474.388564)
			(xy 39.054916 -474.438997) (xy 38.999154 -474.483466) (xy 38.938763 -474.521412) (xy 38.874504 -474.552357)
			(xy 38.807184 -474.575914) (xy 38.737649 -474.591784) (xy 38.666775 -474.59977) (xy 38.595453 -474.59977)
			(xy 38.524579 -474.591784) (xy 38.455044 -474.575914) (xy 38.387724 -474.552357) (xy 38.323465 -474.521412)
			(xy 38.263074 -474.483466) (xy 38.207312 -474.438997) (xy 38.156879 -474.388564) (xy 38.11241 -474.332802)
			(xy 38.074464 -474.272411) (xy 38.043519 -474.208152) (xy 38.019962 -474.140832) (xy 38.004092 -474.071297)
			(xy 37.996106 -474.000423) (xy 36.317206 -474.000423) (xy 36.361593 -474.07211) (xy 36.400327 -474.149899)
			(xy 36.431719 -474.230931) (xy 36.4555 -474.314513) (xy 36.471468 -474.399933) (xy 36.479486 -474.486462)
			(xy 36.479988 -474.529912) (xy 36.479486 -474.573362) (xy 36.471468 -474.659891) (xy 36.4555 -474.745311)
			(xy 36.431719 -474.828893) (xy 36.400327 -474.909925) (xy 36.361593 -474.987714) (xy 36.315846 -475.061598)
			(xy 36.263477 -475.130945) (xy 36.204933 -475.195165) (xy 36.140713 -475.253709) (xy 36.071366 -475.306078)
			(xy 35.997482 -475.351825) (xy 35.919693 -475.390559) (xy 35.838661 -475.421951) (xy 35.755079 -475.445732)
			(xy 35.669659 -475.4617) (xy 35.58313 -475.469718) (xy 35.49623 -475.469718) (xy 35.409701 -475.4617)
			(xy 35.324281 -475.445732) (xy 35.240699 -475.421951) (xy 35.159667 -475.390559) (xy 35.081878 -475.351825)
			(xy 35.007994 -475.306078) (xy 34.938647 -475.253709) (xy 34.874427 -475.195165) (xy 34.815883 -475.130945)
			(xy 34.763514 -475.061598) (xy 34.717767 -474.987714) (xy 34.679033 -474.909925) (xy 34.647641 -474.828893)
			(xy 34.62386 -474.745311) (xy 34.607892 -474.659891) (xy 34.599874 -474.573362) (xy 31.399486 -474.573362)
			(xy 31.391468 -474.659891) (xy 31.3755 -474.745311) (xy 31.351719 -474.828893) (xy 31.320327 -474.909925)
			(xy 31.281593 -474.987714) (xy 31.235846 -475.061598) (xy 31.183477 -475.130945) (xy 31.124933 -475.195165)
			(xy 31.060713 -475.253709) (xy 30.991366 -475.306078) (xy 30.917482 -475.351825) (xy 30.839693 -475.390559)
			(xy 30.758661 -475.421951) (xy 30.675079 -475.445732) (xy 30.589659 -475.4617) (xy 30.50313 -475.469718)
			(xy 30.41623 -475.469718) (xy 30.329701 -475.4617) (xy 30.244281 -475.445732) (xy 30.160699 -475.421951)
			(xy 30.079667 -475.390559) (xy 30.001878 -475.351825) (xy 29.927994 -475.306078) (xy 29.858647 -475.253709)
			(xy 29.794427 -475.195165) (xy 29.735883 -475.130945) (xy 29.683514 -475.061598) (xy 29.637767 -474.987714)
			(xy 29.599033 -474.909925) (xy 29.567641 -474.828893) (xy 29.54386 -474.745311) (xy 29.527892 -474.659891)
			(xy 29.519874 -474.573362) (xy 24.554219 -474.573362) (xy 24.553364 -474.582357) (xy 24.52154 -474.832996)
			(xy 24.48182 -475.082506) (xy 24.434243 -475.330637) (xy 24.378856 -475.577142) (xy 24.315715 -475.821777)
			(xy 24.312131 -475.834049) (xy 37.996106 -475.834049) (xy 37.996106 -475.762727) (xy 38.004092 -475.691853)
			(xy 38.019962 -475.622318) (xy 38.043519 -475.554998) (xy 38.074464 -475.490739) (xy 38.11241 -475.430348)
			(xy 38.156879 -475.374586) (xy 38.207312 -475.324153) (xy 38.263074 -475.279684) (xy 38.323465 -475.241738)
			(xy 38.387724 -475.210793) (xy 38.455044 -475.187236) (xy 38.524579 -475.171366) (xy 38.595453 -475.16338)
			(xy 38.666775 -475.16338) (xy 38.737649 -475.171366) (xy 38.807184 -475.187236) (xy 38.874504 -475.210793)
			(xy 38.938763 -475.241738) (xy 38.999154 -475.279684) (xy 39.054916 -475.324153) (xy 39.105349 -475.374586)
			(xy 39.149818 -475.430348) (xy 39.187764 -475.490739) (xy 39.218709 -475.554998) (xy 39.242266 -475.622318)
			(xy 39.258136 -475.691853) (xy 39.266122 -475.762727) (xy 39.266622 -475.798388) (xy 39.266122 -475.834049)
			(xy 39.882818 -475.834049) (xy 39.882818 -475.762727) (xy 39.890804 -475.691853) (xy 39.906674 -475.622318)
			(xy 39.930231 -475.554998) (xy 39.961176 -475.490739) (xy 39.999122 -475.430348) (xy 40.043591 -475.374586)
			(xy 40.094024 -475.324153) (xy 40.149786 -475.279684) (xy 40.210177 -475.241738) (xy 40.274436 -475.210793)
			(xy 40.341756 -475.187236) (xy 40.411291 -475.171366) (xy 40.482165 -475.16338) (xy 40.553487 -475.16338)
			(xy 40.624361 -475.171366) (xy 40.693896 -475.187236) (xy 40.761216 -475.210793) (xy 40.825475 -475.241738)
			(xy 40.885866 -475.279684) (xy 40.941628 -475.324153) (xy 40.992061 -475.374586) (xy 41.03653 -475.430348)
			(xy 41.074476 -475.490739) (xy 41.105421 -475.554998) (xy 41.128978 -475.622318) (xy 41.144848 -475.691853)
			(xy 41.152834 -475.762727) (xy 41.153334 -475.798388) (xy 41.152834 -475.834049) (xy 42.12386 -475.834049)
			(xy 42.12386 -475.762727) (xy 42.131846 -475.691853) (xy 42.147716 -475.622318) (xy 42.171273 -475.554998)
			(xy 42.202218 -475.490739) (xy 42.240164 -475.430348) (xy 42.284633 -475.374586) (xy 42.335066 -475.324153)
			(xy 42.390828 -475.279684) (xy 42.451219 -475.241738) (xy 42.515478 -475.210793) (xy 42.582798 -475.187236)
			(xy 42.652333 -475.171366) (xy 42.723207 -475.16338) (xy 42.794529 -475.16338) (xy 42.865403 -475.171366)
			(xy 42.934938 -475.187236) (xy 43.002258 -475.210793) (xy 43.066517 -475.241738) (xy 43.126908 -475.279684)
			(xy 43.18267 -475.324153) (xy 43.233103 -475.374586) (xy 43.277572 -475.430348) (xy 43.315518 -475.490739)
			(xy 43.346463 -475.554998) (xy 43.37002 -475.622318) (xy 43.38589 -475.691853) (xy 43.393876 -475.762727)
			(xy 43.394376 -475.798388) (xy 43.393876 -475.834049) (xy 44.027844 -475.834049) (xy 44.027844 -475.762727)
			(xy 44.03583 -475.691853) (xy 44.0517 -475.622318) (xy 44.075257 -475.554998) (xy 44.106202 -475.490739)
			(xy 44.144148 -475.430348) (xy 44.188617 -475.374586) (xy 44.23905 -475.324153) (xy 44.294812 -475.279684)
			(xy 44.355203 -475.241738) (xy 44.419462 -475.210793) (xy 44.486782 -475.187236) (xy 44.556317 -475.171366)
			(xy 44.627191 -475.16338) (xy 44.698513 -475.16338) (xy 44.769387 -475.171366) (xy 44.838922 -475.187236)
			(xy 44.906242 -475.210793) (xy 44.970501 -475.241738) (xy 45.030892 -475.279684) (xy 45.086654 -475.324153)
			(xy 45.137087 -475.374586) (xy 45.181556 -475.430348) (xy 45.219502 -475.490739) (xy 45.250447 -475.554998)
			(xy 45.274004 -475.622318) (xy 45.289874 -475.691853) (xy 45.29786 -475.762727) (xy 45.29836 -475.798388)
			(xy 45.29786 -475.834049) (xy 45.289874 -475.904923) (xy 45.274004 -475.974458) (xy 45.250447 -476.041778)
			(xy 45.219502 -476.106037) (xy 45.181556 -476.166428) (xy 45.137087 -476.22219) (xy 45.086654 -476.272623)
			(xy 45.030892 -476.317092) (xy 44.970501 -476.355038) (xy 44.906242 -476.385983) (xy 44.838922 -476.40954)
			(xy 44.769387 -476.42541) (xy 44.698513 -476.433396) (xy 44.627191 -476.433396) (xy 44.556317 -476.42541)
			(xy 44.486782 -476.40954) (xy 44.419462 -476.385983) (xy 44.355203 -476.355038) (xy 44.294812 -476.317092)
			(xy 44.23905 -476.272623) (xy 44.188617 -476.22219) (xy 44.144148 -476.166428) (xy 44.106202 -476.106037)
			(xy 44.075257 -476.041778) (xy 44.0517 -475.974458) (xy 44.03583 -475.904923) (xy 44.027844 -475.834049)
			(xy 43.393876 -475.834049) (xy 43.38589 -475.904923) (xy 43.37002 -475.974458) (xy 43.346463 -476.041778)
			(xy 43.315518 -476.106037) (xy 43.277572 -476.166428) (xy 43.233103 -476.22219) (xy 43.18267 -476.272623)
			(xy 43.126908 -476.317092) (xy 43.066517 -476.355038) (xy 43.002258 -476.385983) (xy 42.934938 -476.40954)
			(xy 42.865403 -476.42541) (xy 42.794529 -476.433396) (xy 42.723207 -476.433396) (xy 42.652333 -476.42541)
			(xy 42.582798 -476.40954) (xy 42.515478 -476.385983) (xy 42.451219 -476.355038) (xy 42.390828 -476.317092)
			(xy 42.335066 -476.272623) (xy 42.284633 -476.22219) (xy 42.240164 -476.166428) (xy 42.202218 -476.106037)
			(xy 42.171273 -476.041778) (xy 42.147716 -475.974458) (xy 42.131846 -475.904923) (xy 42.12386 -475.834049)
			(xy 41.152834 -475.834049) (xy 41.144848 -475.904923) (xy 41.128978 -475.974458) (xy 41.105421 -476.041778)
			(xy 41.074476 -476.106037) (xy 41.03653 -476.166428) (xy 40.992061 -476.22219) (xy 40.941628 -476.272623)
			(xy 40.885866 -476.317092) (xy 40.825475 -476.355038) (xy 40.761216 -476.385983) (xy 40.693896 -476.40954)
			(xy 40.624361 -476.42541) (xy 40.553487 -476.433396) (xy 40.482165 -476.433396) (xy 40.411291 -476.42541)
			(xy 40.341756 -476.40954) (xy 40.274436 -476.385983) (xy 40.210177 -476.355038) (xy 40.149786 -476.317092)
			(xy 40.094024 -476.272623) (xy 40.043591 -476.22219) (xy 39.999122 -476.166428) (xy 39.961176 -476.106037)
			(xy 39.930231 -476.041778) (xy 39.906674 -475.974458) (xy 39.890804 -475.904923) (xy 39.882818 -475.834049)
			(xy 39.266122 -475.834049) (xy 39.258136 -475.904923) (xy 39.242266 -475.974458) (xy 39.218709 -476.041778)
			(xy 39.187764 -476.106037) (xy 39.149818 -476.166428) (xy 39.105349 -476.22219) (xy 39.054916 -476.272623)
			(xy 38.999154 -476.317092) (xy 38.938763 -476.355038) (xy 38.874504 -476.385983) (xy 38.807184 -476.40954)
			(xy 38.737649 -476.42541) (xy 38.666775 -476.433396) (xy 38.595453 -476.433396) (xy 38.524579 -476.42541)
			(xy 38.455044 -476.40954) (xy 38.387724 -476.385983) (xy 38.323465 -476.355038) (xy 38.263074 -476.317092)
			(xy 38.207312 -476.272623) (xy 38.156879 -476.22219) (xy 38.11241 -476.166428) (xy 38.074464 -476.106037)
			(xy 38.043519 -476.041778) (xy 38.019962 -475.974458) (xy 38.004092 -475.904923) (xy 37.996106 -475.834049)
			(xy 24.312131 -475.834049) (xy 24.244883 -476.064296) (xy 24.16643 -476.304458) (xy 24.080435 -476.542023)
			(xy 23.986983 -476.776756) (xy 23.886168 -477.008421) (xy 23.836503 -477.113362) (xy 29.519874 -477.113362)
			(xy 29.519874 -477.026462) (xy 29.527892 -476.939933) (xy 29.54386 -476.854513) (xy 29.567641 -476.770931)
			(xy 29.599033 -476.689899) (xy 29.637767 -476.61211) (xy 29.683514 -476.538226) (xy 29.735883 -476.468879)
			(xy 29.794427 -476.404659) (xy 29.858647 -476.346115) (xy 29.927994 -476.293746) (xy 30.001878 -476.247999)
			(xy 30.079667 -476.209265) (xy 30.160699 -476.177873) (xy 30.244281 -476.154092) (xy 30.329701 -476.138124)
			(xy 30.41623 -476.130106) (xy 30.50313 -476.130106) (xy 30.589659 -476.138124) (xy 30.675079 -476.154092)
			(xy 30.758661 -476.177873) (xy 30.839693 -476.209265) (xy 30.917482 -476.247999) (xy 30.991366 -476.293746)
			(xy 31.060713 -476.346115) (xy 31.124933 -476.404659) (xy 31.183477 -476.468879) (xy 31.235846 -476.538226)
			(xy 31.281593 -476.61211) (xy 31.320327 -476.689899) (xy 31.351719 -476.770931) (xy 31.3755 -476.854513)
			(xy 31.391468 -476.939933) (xy 31.399486 -477.026462) (xy 31.399988 -477.069912) (xy 31.399486 -477.113362)
			(xy 34.599874 -477.113362) (xy 34.599874 -477.026462) (xy 34.607892 -476.939933) (xy 34.62386 -476.854513)
			(xy 34.647641 -476.770931) (xy 34.679033 -476.689899) (xy 34.717767 -476.61211) (xy 34.763514 -476.538226)
			(xy 34.815883 -476.468879) (xy 34.874427 -476.404659) (xy 34.938647 -476.346115) (xy 35.007994 -476.293746)
			(xy 35.081878 -476.247999) (xy 35.159667 -476.209265) (xy 35.240699 -476.177873) (xy 35.324281 -476.154092)
			(xy 35.409701 -476.138124) (xy 35.49623 -476.130106) (xy 35.58313 -476.130106) (xy 35.669659 -476.138124)
			(xy 35.755079 -476.154092) (xy 35.838661 -476.177873) (xy 35.919693 -476.209265) (xy 35.997482 -476.247999)
			(xy 36.071366 -476.293746) (xy 36.140713 -476.346115) (xy 36.204933 -476.404659) (xy 36.263477 -476.468879)
			(xy 36.315846 -476.538226) (xy 36.361593 -476.61211) (xy 36.400327 -476.689899) (xy 36.431719 -476.770931)
			(xy 36.4555 -476.854513) (xy 36.471468 -476.939933) (xy 36.479486 -477.026462) (xy 36.479988 -477.069912)
			(xy 36.479486 -477.113362) (xy 36.471468 -477.199891) (xy 36.4555 -477.285311) (xy 36.431719 -477.368893)
			(xy 36.400327 -477.449925) (xy 36.361593 -477.527714) (xy 36.315846 -477.601598) (xy 36.263477 -477.670945)
			(xy 36.205097 -477.734985) (xy 37.996106 -477.734985) (xy 37.996106 -477.663663) (xy 38.004092 -477.592789)
			(xy 38.019962 -477.523254) (xy 38.043519 -477.455934) (xy 38.074464 -477.391675) (xy 38.11241 -477.331284)
			(xy 38.156879 -477.275522) (xy 38.207312 -477.225089) (xy 38.263074 -477.18062) (xy 38.323465 -477.142674)
			(xy 38.387724 -477.111729) (xy 38.455044 -477.088172) (xy 38.524579 -477.072302) (xy 38.595453 -477.064316)
			(xy 38.666775 -477.064316) (xy 38.737649 -477.072302) (xy 38.807184 -477.088172) (xy 38.874504 -477.111729)
			(xy 38.938763 -477.142674) (xy 38.999154 -477.18062) (xy 39.054916 -477.225089) (xy 39.105349 -477.275522)
			(xy 39.149818 -477.331284) (xy 39.187764 -477.391675) (xy 39.218709 -477.455934) (xy 39.242266 -477.523254)
			(xy 39.258136 -477.592789) (xy 39.266122 -477.663663) (xy 39.266622 -477.699324) (xy 39.266122 -477.734985)
			(xy 39.882818 -477.734985) (xy 39.882818 -477.663663) (xy 39.890804 -477.592789) (xy 39.906674 -477.523254)
			(xy 39.930231 -477.455934) (xy 39.961176 -477.391675) (xy 39.999122 -477.331284) (xy 40.043591 -477.275522)
			(xy 40.094024 -477.225089) (xy 40.149786 -477.18062) (xy 40.210177 -477.142674) (xy 40.274436 -477.111729)
			(xy 40.341756 -477.088172) (xy 40.411291 -477.072302) (xy 40.482165 -477.064316) (xy 40.553487 -477.064316)
			(xy 40.624361 -477.072302) (xy 40.693896 -477.088172) (xy 40.761216 -477.111729) (xy 40.825475 -477.142674)
			(xy 40.885866 -477.18062) (xy 40.941628 -477.225089) (xy 40.992061 -477.275522) (xy 41.03653 -477.331284)
			(xy 41.074476 -477.391675) (xy 41.105421 -477.455934) (xy 41.128978 -477.523254) (xy 41.144848 -477.592789)
			(xy 41.152834 -477.663663) (xy 41.153334 -477.699324) (xy 41.152834 -477.734985) (xy 42.12386 -477.734985)
			(xy 42.12386 -477.663663) (xy 42.131846 -477.592789) (xy 42.147716 -477.523254) (xy 42.171273 -477.455934)
			(xy 42.202218 -477.391675) (xy 42.240164 -477.331284) (xy 42.284633 -477.275522) (xy 42.335066 -477.225089)
			(xy 42.390828 -477.18062) (xy 42.451219 -477.142674) (xy 42.515478 -477.111729) (xy 42.582798 -477.088172)
			(xy 42.652333 -477.072302) (xy 42.723207 -477.064316) (xy 42.794529 -477.064316) (xy 42.865403 -477.072302)
			(xy 42.934938 -477.088172) (xy 43.002258 -477.111729) (xy 43.066517 -477.142674) (xy 43.126908 -477.18062)
			(xy 43.18267 -477.225089) (xy 43.233103 -477.275522) (xy 43.277572 -477.331284) (xy 43.315518 -477.391675)
			(xy 43.346463 -477.455934) (xy 43.37002 -477.523254) (xy 43.38589 -477.592789) (xy 43.393876 -477.663663)
			(xy 43.394376 -477.699324) (xy 43.393876 -477.734985) (xy 44.027844 -477.734985) (xy 44.027844 -477.663663)
			(xy 44.03583 -477.592789) (xy 44.0517 -477.523254) (xy 44.075257 -477.455934) (xy 44.106202 -477.391675)
			(xy 44.144148 -477.331284) (xy 44.188617 -477.275522) (xy 44.23905 -477.225089) (xy 44.294812 -477.18062)
			(xy 44.355203 -477.142674) (xy 44.419462 -477.111729) (xy 44.486782 -477.088172) (xy 44.556317 -477.072302)
			(xy 44.627191 -477.064316) (xy 44.698513 -477.064316) (xy 44.769387 -477.072302) (xy 44.838922 -477.088172)
			(xy 44.906242 -477.111729) (xy 44.970501 -477.142674) (xy 45.030892 -477.18062) (xy 45.086654 -477.225089)
			(xy 45.137087 -477.275522) (xy 45.181556 -477.331284) (xy 45.219502 -477.391675) (xy 45.250447 -477.455934)
			(xy 45.274004 -477.523254) (xy 45.289874 -477.592789) (xy 45.29786 -477.663663) (xy 45.29836 -477.699324)
			(xy 45.29786 -477.734985) (xy 45.289874 -477.805859) (xy 45.274004 -477.875394) (xy 45.250447 -477.942714)
			(xy 45.219502 -478.006973) (xy 45.181556 -478.067364) (xy 45.137087 -478.123126) (xy 45.086654 -478.173559)
			(xy 45.030892 -478.218028) (xy 44.970501 -478.255974) (xy 44.906242 -478.286919) (xy 44.838922 -478.310476)
			(xy 44.769387 -478.326346) (xy 44.698513 -478.334332) (xy 44.627191 -478.334332) (xy 44.556317 -478.326346)
			(xy 44.486782 -478.310476) (xy 44.419462 -478.286919) (xy 44.355203 -478.255974) (xy 44.294812 -478.218028)
			(xy 44.23905 -478.173559) (xy 44.188617 -478.123126) (xy 44.144148 -478.067364) (xy 44.106202 -478.006973)
			(xy 44.075257 -477.942714) (xy 44.0517 -477.875394) (xy 44.03583 -477.805859) (xy 44.027844 -477.734985)
			(xy 43.393876 -477.734985) (xy 43.38589 -477.805859) (xy 43.37002 -477.875394) (xy 43.346463 -477.942714)
			(xy 43.315518 -478.006973) (xy 43.277572 -478.067364) (xy 43.233103 -478.123126) (xy 43.18267 -478.173559)
			(xy 43.126908 -478.218028) (xy 43.066517 -478.255974) (xy 43.002258 -478.286919) (xy 42.934938 -478.310476)
			(xy 42.865403 -478.326346) (xy 42.794529 -478.334332) (xy 42.723207 -478.334332) (xy 42.652333 -478.326346)
			(xy 42.582798 -478.310476) (xy 42.515478 -478.286919) (xy 42.451219 -478.255974) (xy 42.390828 -478.218028)
			(xy 42.335066 -478.173559) (xy 42.284633 -478.123126) (xy 42.240164 -478.067364) (xy 42.202218 -478.006973)
			(xy 42.171273 -477.942714) (xy 42.147716 -477.875394) (xy 42.131846 -477.805859) (xy 42.12386 -477.734985)
			(xy 41.152834 -477.734985) (xy 41.144848 -477.805859) (xy 41.128978 -477.875394) (xy 41.105421 -477.942714)
			(xy 41.074476 -478.006973) (xy 41.03653 -478.067364) (xy 40.992061 -478.123126) (xy 40.941628 -478.173559)
			(xy 40.885866 -478.218028) (xy 40.825475 -478.255974) (xy 40.761216 -478.286919) (xy 40.693896 -478.310476)
			(xy 40.624361 -478.326346) (xy 40.553487 -478.334332) (xy 40.482165 -478.334332) (xy 40.411291 -478.326346)
			(xy 40.341756 -478.310476) (xy 40.274436 -478.286919) (xy 40.210177 -478.255974) (xy 40.149786 -478.218028)
			(xy 40.094024 -478.173559) (xy 40.043591 -478.123126) (xy 39.999122 -478.067364) (xy 39.961176 -478.006973)
			(xy 39.930231 -477.942714) (xy 39.906674 -477.875394) (xy 39.890804 -477.805859) (xy 39.882818 -477.734985)
			(xy 39.266122 -477.734985) (xy 39.258136 -477.805859) (xy 39.242266 -477.875394) (xy 39.218709 -477.942714)
			(xy 39.187764 -478.006973) (xy 39.149818 -478.067364) (xy 39.105349 -478.123126) (xy 39.054916 -478.173559)
			(xy 38.999154 -478.218028) (xy 38.938763 -478.255974) (xy 38.874504 -478.286919) (xy 38.807184 -478.310476)
			(xy 38.737649 -478.326346) (xy 38.666775 -478.334332) (xy 38.595453 -478.334332) (xy 38.524579 -478.326346)
			(xy 38.455044 -478.310476) (xy 38.387724 -478.286919) (xy 38.323465 -478.255974) (xy 38.263074 -478.218028)
			(xy 38.207312 -478.173559) (xy 38.156879 -478.123126) (xy 38.11241 -478.067364) (xy 38.074464 -478.006973)
			(xy 38.043519 -477.942714) (xy 38.019962 -477.875394) (xy 38.004092 -477.805859) (xy 37.996106 -477.734985)
			(xy 36.205097 -477.734985) (xy 36.204933 -477.735165) (xy 36.140713 -477.793709) (xy 36.071366 -477.846078)
			(xy 35.997482 -477.891825) (xy 35.919693 -477.930559) (xy 35.838661 -477.961951) (xy 35.755079 -477.985732)
			(xy 35.669659 -478.0017) (xy 35.58313 -478.009718) (xy 35.49623 -478.009718) (xy 35.409701 -478.0017)
			(xy 35.324281 -477.985732) (xy 35.240699 -477.961951) (xy 35.159667 -477.930559) (xy 35.081878 -477.891825)
			(xy 35.007994 -477.846078) (xy 34.938647 -477.793709) (xy 34.874427 -477.735165) (xy 34.815883 -477.670945)
			(xy 34.763514 -477.601598) (xy 34.717767 -477.527714) (xy 34.679033 -477.449925) (xy 34.647641 -477.368893)
			(xy 34.62386 -477.285311) (xy 34.607892 -477.199891) (xy 34.599874 -477.113362) (xy 31.399486 -477.113362)
			(xy 31.391468 -477.199891) (xy 31.3755 -477.285311) (xy 31.351719 -477.368893) (xy 31.320327 -477.449925)
			(xy 31.281593 -477.527714) (xy 31.235846 -477.601598) (xy 31.183477 -477.670945) (xy 31.124933 -477.735165)
			(xy 31.060713 -477.793709) (xy 30.991366 -477.846078) (xy 30.917482 -477.891825) (xy 30.839693 -477.930559)
			(xy 30.758661 -477.961951) (xy 30.675079 -477.985732) (xy 30.589659 -478.0017) (xy 30.50313 -478.009718)
			(xy 30.41623 -478.009718) (xy 30.329701 -478.0017) (xy 30.244281 -477.985732) (xy 30.160699 -477.961951)
			(xy 30.079667 -477.930559) (xy 30.001878 -477.891825) (xy 29.927994 -477.846078) (xy 29.858647 -477.793709)
			(xy 29.794427 -477.735165) (xy 29.735883 -477.670945) (xy 29.683514 -477.601598) (xy 29.637767 -477.527714)
			(xy 29.599033 -477.449925) (xy 29.567641 -477.368893) (xy 29.54386 -477.285311) (xy 29.527892 -477.199891)
			(xy 29.519874 -477.113362) (xy 23.836503 -477.113362) (xy 23.778089 -477.236789) (xy 23.662855 -477.46163)
			(xy 23.54058 -477.682722) (xy 23.411387 -477.899844) (xy 23.275404 -478.112779) (xy 23.132767 -478.321315)
			(xy 22.983618 -478.525244) (xy 22.828105 -478.724363) (xy 22.666384 -478.918474) (xy 22.498616 -479.107382)
			(xy 22.324968 -479.290901) (xy 22.145612 -479.468845) (xy 21.960729 -479.64104) (xy 21.946632 -479.653362)
			(xy 29.519874 -479.653362) (xy 29.519874 -479.566462) (xy 29.527892 -479.479933) (xy 29.54386 -479.394513)
			(xy 29.567641 -479.310931) (xy 29.599033 -479.229899) (xy 29.637767 -479.15211) (xy 29.683514 -479.078226)
			(xy 29.735883 -479.008879) (xy 29.794427 -478.944659) (xy 29.858647 -478.886115) (xy 29.927994 -478.833746)
			(xy 30.001878 -478.787999) (xy 30.079667 -478.749265) (xy 30.160699 -478.717873) (xy 30.244281 -478.694092)
			(xy 30.329701 -478.678124) (xy 30.41623 -478.670106) (xy 30.50313 -478.670106) (xy 30.589659 -478.678124)
			(xy 30.675079 -478.694092) (xy 30.758661 -478.717873) (xy 30.839693 -478.749265) (xy 30.917482 -478.787999)
			(xy 30.991366 -478.833746) (xy 31.060713 -478.886115) (xy 31.124933 -478.944659) (xy 31.183477 -479.008879)
			(xy 31.235846 -479.078226) (xy 31.281593 -479.15211) (xy 31.320327 -479.229899) (xy 31.351719 -479.310931)
			(xy 31.3755 -479.394513) (xy 31.391468 -479.479933) (xy 31.399486 -479.566462) (xy 31.399988 -479.609912)
			(xy 31.399486 -479.653362) (xy 34.599874 -479.653362) (xy 34.599874 -479.566462) (xy 34.607892 -479.479933)
			(xy 34.62386 -479.394513) (xy 34.647641 -479.310931) (xy 34.679033 -479.229899) (xy 34.717767 -479.15211)
			(xy 34.763514 -479.078226) (xy 34.815883 -479.008879) (xy 34.874427 -478.944659) (xy 34.938647 -478.886115)
			(xy 35.007994 -478.833746) (xy 35.081878 -478.787999) (xy 35.159667 -478.749265) (xy 35.240699 -478.717873)
			(xy 35.324281 -478.694092) (xy 35.409701 -478.678124) (xy 35.49623 -478.670106) (xy 35.58313 -478.670106)
			(xy 35.669659 -478.678124) (xy 35.755079 -478.694092) (xy 35.838661 -478.717873) (xy 35.919693 -478.749265)
			(xy 35.997482 -478.787999) (xy 36.071366 -478.833746) (xy 36.140713 -478.886115) (xy 36.204933 -478.944659)
			(xy 36.263477 -479.008879) (xy 36.315846 -479.078226) (xy 36.361593 -479.15211) (xy 36.400327 -479.229899)
			(xy 36.431719 -479.310931) (xy 36.4555 -479.394513) (xy 36.458417 -479.410115) (xy 37.996106 -479.410115)
			(xy 37.996106 -479.338793) (xy 38.004092 -479.267919) (xy 38.019962 -479.198384) (xy 38.043519 -479.131064)
			(xy 38.074464 -479.066805) (xy 38.11241 -479.006414) (xy 38.156879 -478.950652) (xy 38.207312 -478.900219)
			(xy 38.263074 -478.85575) (xy 38.323465 -478.817804) (xy 38.387724 -478.786859) (xy 38.455044 -478.763302)
			(xy 38.524579 -478.747432) (xy 38.595453 -478.739446) (xy 38.666775 -478.739446) (xy 38.737649 -478.747432)
			(xy 38.807184 -478.763302) (xy 38.874504 -478.786859) (xy 38.938763 -478.817804) (xy 38.999154 -478.85575)
			(xy 39.054916 -478.900219) (xy 39.105349 -478.950652) (xy 39.149818 -479.006414) (xy 39.187764 -479.066805)
			(xy 39.218709 -479.131064) (xy 39.242266 -479.198384) (xy 39.258136 -479.267919) (xy 39.266122 -479.338793)
			(xy 39.266622 -479.374454) (xy 39.266122 -479.410115) (xy 39.882818 -479.410115) (xy 39.882818 -479.338793)
			(xy 39.890804 -479.267919) (xy 39.906674 -479.198384) (xy 39.930231 -479.131064) (xy 39.961176 -479.066805)
			(xy 39.999122 -479.006414) (xy 40.043591 -478.950652) (xy 40.094024 -478.900219) (xy 40.149786 -478.85575)
			(xy 40.210177 -478.817804) (xy 40.274436 -478.786859) (xy 40.341756 -478.763302) (xy 40.411291 -478.747432)
			(xy 40.482165 -478.739446) (xy 40.553487 -478.739446) (xy 40.624361 -478.747432) (xy 40.693896 -478.763302)
			(xy 40.761216 -478.786859) (xy 40.825475 -478.817804) (xy 40.885866 -478.85575) (xy 40.941628 -478.900219)
			(xy 40.992061 -478.950652) (xy 41.03653 -479.006414) (xy 41.074476 -479.066805) (xy 41.105421 -479.131064)
			(xy 41.128978 -479.198384) (xy 41.144848 -479.267919) (xy 41.152834 -479.338793) (xy 41.153334 -479.374454)
			(xy 41.152834 -479.410115) (xy 42.12386 -479.410115) (xy 42.12386 -479.338793) (xy 42.131846 -479.267919)
			(xy 42.147716 -479.198384) (xy 42.171273 -479.131064) (xy 42.202218 -479.066805) (xy 42.240164 -479.006414)
			(xy 42.284633 -478.950652) (xy 42.335066 -478.900219) (xy 42.390828 -478.85575) (xy 42.451219 -478.817804)
			(xy 42.515478 -478.786859) (xy 42.582798 -478.763302) (xy 42.652333 -478.747432) (xy 42.723207 -478.739446)
			(xy 42.794529 -478.739446) (xy 42.865403 -478.747432) (xy 42.934938 -478.763302) (xy 43.002258 -478.786859)
			(xy 43.066517 -478.817804) (xy 43.126908 -478.85575) (xy 43.18267 -478.900219) (xy 43.233103 -478.950652)
			(xy 43.277572 -479.006414) (xy 43.315518 -479.066805) (xy 43.346463 -479.131064) (xy 43.37002 -479.198384)
			(xy 43.38589 -479.267919) (xy 43.393876 -479.338793) (xy 43.394376 -479.374454) (xy 43.393876 -479.410115)
			(xy 44.027844 -479.410115) (xy 44.027844 -479.338793) (xy 44.03583 -479.267919) (xy 44.0517 -479.198384)
			(xy 44.075257 -479.131064) (xy 44.106202 -479.066805) (xy 44.144148 -479.006414) (xy 44.188617 -478.950652)
			(xy 44.23905 -478.900219) (xy 44.294812 -478.85575) (xy 44.355203 -478.817804) (xy 44.419462 -478.786859)
			(xy 44.486782 -478.763302) (xy 44.556317 -478.747432) (xy 44.627191 -478.739446) (xy 44.698513 -478.739446)
			(xy 44.769387 -478.747432) (xy 44.838922 -478.763302) (xy 44.906242 -478.786859) (xy 44.933335 -478.799906)
			(xy 74.39914 -478.799906) (xy 74.39914 -477.799908) (xy 74.399635 -477.715487) (xy 74.407549 -477.546829)
			(xy 74.423359 -477.378729) (xy 74.447032 -477.211554) (xy 74.478514 -477.045672) (xy 74.517737 -476.881448)
			(xy 74.564615 -476.719244) (xy 74.619044 -476.559414) (xy 74.680904 -476.402312) (xy 74.750061 -476.248282)
			(xy 74.826361 -476.097663) (xy 74.909637 -475.950785) (xy 74.999706 -475.807973) (xy 75.09637 -475.669539)
			(xy 75.199416 -475.535788) (xy 75.308619 -475.407014) (xy 75.423737 -475.2835) (xy 75.544518 -475.165518)
			(xy 75.670697 -475.053327) (xy 75.801995 -474.947173) (xy 75.938125 -474.847291) (xy 76.078787 -474.753898)
			(xy 76.223672 -474.667202) (xy 76.372461 -474.587392) (xy 76.524828 -474.514644) (xy 76.680437 -474.449117)
			(xy 76.838946 -474.390957) (xy 77.000007 -474.340289) (xy 77.163266 -474.297227) (xy 77.328364 -474.261865)
			(xy 77.494938 -474.23428) (xy 77.662622 -474.214533) (xy 77.831048 -474.202667) (xy 77.999844 -474.198709)
			(xy 78.16864 -474.202667) (xy 78.337066 -474.214533) (xy 78.50475 -474.23428) (xy 78.671324 -474.261865)
			(xy 78.836422 -474.297227) (xy 78.999681 -474.340289) (xy 79.160742 -474.390957) (xy 79.319251 -474.449117)
			(xy 79.47486 -474.514644) (xy 79.627227 -474.587392) (xy 79.776016 -474.667202) (xy 79.920901 -474.753898)
			(xy 80.061563 -474.847291) (xy 80.197693 -474.947173) (xy 80.328991 -475.053327) (xy 80.45517 -475.165518)
			(xy 80.575951 -475.2835) (xy 80.691069 -475.407014) (xy 80.800272 -475.535788) (xy 80.903318 -475.669539)
			(xy 80.999982 -475.807973) (xy 81.090051 -475.950785) (xy 81.173327 -476.097663) (xy 81.249627 -476.248282)
			(xy 81.318784 -476.402312) (xy 81.380644 -476.559414) (xy 81.435073 -476.719244) (xy 81.481951 -476.881448)
			(xy 81.521174 -477.045672) (xy 81.552656 -477.211554) (xy 81.576329 -477.378729) (xy 81.592139 -477.546829)
			(xy 81.600053 -477.715487) (xy 81.600548 -477.799908) (xy 81.600548 -478.799906) (xy 81.600053 -478.884327)
			(xy 81.592139 -479.052985) (xy 81.576329 -479.221085) (xy 81.552656 -479.38826) (xy 81.521174 -479.554142)
			(xy 81.481951 -479.718366) (xy 81.435073 -479.88057) (xy 81.380644 -480.0404) (xy 81.318784 -480.197502)
			(xy 81.249627 -480.351532) (xy 81.173327 -480.502151) (xy 81.090051 -480.649029) (xy 80.999982 -480.791841)
			(xy 80.903318 -480.930275) (xy 80.800272 -481.064026) (xy 80.691069 -481.1928) (xy 80.575951 -481.316314)
			(xy 80.45517 -481.434296) (xy 80.328991 -481.546487) (xy 80.197693 -481.652641) (xy 80.061563 -481.752523)
			(xy 79.920901 -481.845916) (xy 79.776016 -481.932612) (xy 79.627227 -482.012422) (xy 79.47486 -482.08517)
			(xy 79.319251 -482.150697) (xy 79.160742 -482.208857) (xy 78.999681 -482.259525) (xy 78.836422 -482.302587)
			(xy 78.671324 -482.337949) (xy 78.50475 -482.365534) (xy 78.337066 -482.385281) (xy 78.16864 -482.397147)
			(xy 77.999844 -482.401105) (xy 77.831048 -482.397147) (xy 77.662622 -482.385281) (xy 77.494938 -482.365534)
			(xy 77.328364 -482.337949) (xy 77.163266 -482.302587) (xy 77.000007 -482.259525) (xy 76.838946 -482.208857)
			(xy 76.680437 -482.150697) (xy 76.524828 -482.08517) (xy 76.372461 -482.012422) (xy 76.223672 -481.932612)
			(xy 76.078787 -481.845916) (xy 75.938125 -481.752523) (xy 75.801995 -481.652641) (xy 75.670697 -481.546487)
			(xy 75.544518 -481.434296) (xy 75.423737 -481.316314) (xy 75.308619 -481.1928) (xy 75.199416 -481.064026)
			(xy 75.09637 -480.930275) (xy 74.999706 -480.791841) (xy 74.909637 -480.649029) (xy 74.826361 -480.502151)
			(xy 74.750061 -480.351532) (xy 74.680904 -480.197502) (xy 74.619044 -480.0404) (xy 74.564615 -479.88057)
			(xy 74.517737 -479.718366) (xy 74.478514 -479.554142) (xy 74.447032 -479.38826) (xy 74.423359 -479.221085)
			(xy 74.407549 -479.052985) (xy 74.399635 -478.884327) (xy 74.39914 -478.799906) (xy 44.933335 -478.799906)
			(xy 44.970501 -478.817804) (xy 45.030892 -478.85575) (xy 45.086654 -478.900219) (xy 45.137087 -478.950652)
			(xy 45.181556 -479.006414) (xy 45.219502 -479.066805) (xy 45.250447 -479.131064) (xy 45.274004 -479.198384)
			(xy 45.289874 -479.267919) (xy 45.29786 -479.338793) (xy 45.29836 -479.374454) (xy 45.29786 -479.410115)
			(xy 45.289874 -479.480989) (xy 45.274004 -479.550524) (xy 45.250447 -479.617844) (xy 45.219502 -479.682103)
			(xy 45.181556 -479.742494) (xy 45.137087 -479.798256) (xy 45.086654 -479.848689) (xy 45.030892 -479.893158)
			(xy 44.970501 -479.931104) (xy 44.906242 -479.962049) (xy 44.838922 -479.985606) (xy 44.769387 -480.001476)
			(xy 44.698513 -480.009462) (xy 44.627191 -480.009462) (xy 44.556317 -480.001476) (xy 44.486782 -479.985606)
			(xy 44.419462 -479.962049) (xy 44.355203 -479.931104) (xy 44.294812 -479.893158) (xy 44.23905 -479.848689)
			(xy 44.188617 -479.798256) (xy 44.144148 -479.742494) (xy 44.106202 -479.682103) (xy 44.075257 -479.617844)
			(xy 44.0517 -479.550524) (xy 44.03583 -479.480989) (xy 44.027844 -479.410115) (xy 43.393876 -479.410115)
			(xy 43.38589 -479.480989) (xy 43.37002 -479.550524) (xy 43.346463 -479.617844) (xy 43.315518 -479.682103)
			(xy 43.277572 -479.742494) (xy 43.233103 -479.798256) (xy 43.18267 -479.848689) (xy 43.126908 -479.893158)
			(xy 43.066517 -479.931104) (xy 43.002258 -479.962049) (xy 42.934938 -479.985606) (xy 42.865403 -480.001476)
			(xy 42.794529 -480.009462) (xy 42.723207 -480.009462) (xy 42.652333 -480.001476) (xy 42.582798 -479.985606)
			(xy 42.515478 -479.962049) (xy 42.451219 -479.931104) (xy 42.390828 -479.893158) (xy 42.335066 -479.848689)
			(xy 42.284633 -479.798256) (xy 42.240164 -479.742494) (xy 42.202218 -479.682103) (xy 42.171273 -479.617844)
			(xy 42.147716 -479.550524) (xy 42.131846 -479.480989) (xy 42.12386 -479.410115) (xy 41.152834 -479.410115)
			(xy 41.144848 -479.480989) (xy 41.128978 -479.550524) (xy 41.105421 -479.617844) (xy 41.074476 -479.682103)
			(xy 41.03653 -479.742494) (xy 40.992061 -479.798256) (xy 40.941628 -479.848689) (xy 40.885866 -479.893158)
			(xy 40.825475 -479.931104) (xy 40.761216 -479.962049) (xy 40.693896 -479.985606) (xy 40.624361 -480.001476)
			(xy 40.553487 -480.009462) (xy 40.482165 -480.009462) (xy 40.411291 -480.001476) (xy 40.341756 -479.985606)
			(xy 40.274436 -479.962049) (xy 40.210177 -479.931104) (xy 40.149786 -479.893158) (xy 40.094024 -479.848689)
			(xy 40.043591 -479.798256) (xy 39.999122 -479.742494) (xy 39.961176 -479.682103) (xy 39.930231 -479.617844)
			(xy 39.906674 -479.550524) (xy 39.890804 -479.480989) (xy 39.882818 -479.410115) (xy 39.266122 -479.410115)
			(xy 39.258136 -479.480989) (xy 39.242266 -479.550524) (xy 39.218709 -479.617844) (xy 39.187764 -479.682103)
			(xy 39.149818 -479.742494) (xy 39.105349 -479.798256) (xy 39.054916 -479.848689) (xy 38.999154 -479.893158)
			(xy 38.938763 -479.931104) (xy 38.874504 -479.962049) (xy 38.807184 -479.985606) (xy 38.737649 -480.001476)
			(xy 38.666775 -480.009462) (xy 38.595453 -480.009462) (xy 38.524579 -480.001476) (xy 38.455044 -479.985606)
			(xy 38.387724 -479.962049) (xy 38.323465 -479.931104) (xy 38.263074 -479.893158) (xy 38.207312 -479.848689)
			(xy 38.156879 -479.798256) (xy 38.11241 -479.742494) (xy 38.074464 -479.682103) (xy 38.043519 -479.617844)
			(xy 38.019962 -479.550524) (xy 38.004092 -479.480989) (xy 37.996106 -479.410115) (xy 36.458417 -479.410115)
			(xy 36.471468 -479.479933) (xy 36.479486 -479.566462) (xy 36.479988 -479.609912) (xy 36.479486 -479.653362)
			(xy 36.471468 -479.739891) (xy 36.4555 -479.825311) (xy 36.431719 -479.908893) (xy 36.400327 -479.989925)
			(xy 36.361593 -480.067714) (xy 36.315846 -480.141598) (xy 36.263477 -480.210945) (xy 36.204933 -480.275165)
			(xy 36.140713 -480.333709) (xy 36.071366 -480.386078) (xy 35.997482 -480.431825) (xy 35.919693 -480.470559)
			(xy 35.838661 -480.501951) (xy 35.755079 -480.525732) (xy 35.669659 -480.5417) (xy 35.58313 -480.549718)
			(xy 35.49623 -480.549718) (xy 35.409701 -480.5417) (xy 35.324281 -480.525732) (xy 35.240699 -480.501951)
			(xy 35.159667 -480.470559) (xy 35.081878 -480.431825) (xy 35.007994 -480.386078) (xy 34.938647 -480.333709)
			(xy 34.874427 -480.275165) (xy 34.815883 -480.210945) (xy 34.763514 -480.141598) (xy 34.717767 -480.067714)
			(xy 34.679033 -479.989925) (xy 34.647641 -479.908893) (xy 34.62386 -479.825311) (xy 34.607892 -479.739891)
			(xy 34.599874 -479.653362) (xy 31.399486 -479.653362) (xy 31.391468 -479.739891) (xy 31.3755 -479.825311)
			(xy 31.351719 -479.908893) (xy 31.320327 -479.989925) (xy 31.281593 -480.067714) (xy 31.235846 -480.141598)
			(xy 31.183477 -480.210945) (xy 31.124933 -480.275165) (xy 31.060713 -480.333709) (xy 30.991366 -480.386078)
			(xy 30.917482 -480.431825) (xy 30.839693 -480.470559) (xy 30.758661 -480.501951) (xy 30.675079 -480.525732)
			(xy 30.589659 -480.5417) (xy 30.50313 -480.549718) (xy 30.41623 -480.549718) (xy 30.329701 -480.5417)
			(xy 30.244281 -480.525732) (xy 30.160699 -480.501951) (xy 30.079667 -480.470559) (xy 30.001878 -480.431825)
			(xy 29.927994 -480.386078) (xy 29.858647 -480.333709) (xy 29.794427 -480.275165) (xy 29.735883 -480.210945)
			(xy 29.683514 -480.141598) (xy 29.637767 -480.067714) (xy 29.599033 -479.989925) (xy 29.567641 -479.908893)
			(xy 29.54386 -479.825311) (xy 29.527892 -479.739891) (xy 29.519874 -479.653362) (xy 21.946632 -479.653362)
			(xy 21.770502 -479.807312) (xy 21.575121 -479.967496) (xy 21.374781 -480.121432) (xy 21.169681 -480.268967)
			(xy 20.960025 -480.409953) (xy 20.746023 -480.544251) (xy 20.527889 -480.671727) (xy 20.305839 -480.792252)
			(xy 20.080095 -480.905708) (xy 19.850881 -481.01198) (xy 19.618427 -481.110964) (xy 19.382964 -481.202561)
			(xy 19.144727 -481.286678) (xy 18.903953 -481.363233) (xy 18.660883 -481.432148) (xy 18.415758 -481.493356)
			(xy 18.168823 -481.546795) (xy 17.920324 -481.592412) (xy 17.670509 -481.630162) (xy 17.419626 -481.660006)
			(xy 17.167927 -481.681916) (xy 16.915661 -481.695869) (xy 16.663081 -481.701851) (xy 16.410437 -481.699857)
			(xy 16.157983 -481.689888) (xy 15.905969 -481.671955) (xy 15.654647 -481.646074) (xy 15.404267 -481.612273)
			(xy 15.155079 -481.570584) (xy 14.907331 -481.52105) (xy 14.66127 -481.46372) (xy 14.417142 -481.39865)
			(xy 14.17519 -481.325906) (xy 13.935654 -481.245559) (xy 13.698775 -481.157692) (xy 13.464787 -481.06239)
			(xy 13.233925 -480.959749) (xy 13.006418 -480.849871) (xy 12.782493 -480.732866) (xy 12.562373 -480.60885)
			(xy 12.346278 -480.477947) (xy 12.134423 -480.340287) (xy 11.927019 -480.196009) (xy 11.724273 -480.045254)
			(xy 11.526388 -479.888175) (xy 11.33356 -479.724926) (xy 11.145982 -479.555672) (xy 10.96384 -479.380581)
			(xy 10.787316 -479.199827) (xy 10.616586 -479.01359) (xy 10.451821 -478.822057) (xy 10.293185 -478.625417)
			(xy 10.140835 -478.423868) (xy 9.994923 -478.21761) (xy 9.855596 -478.006848) (xy 9.722991 -477.791793)
			(xy 9.597242 -477.572659) (xy 9.478473 -477.349664) (xy 9.366802 -477.123032) (xy 9.262342 -476.892986)
			(xy 9.165196 -476.659758) (xy 9.075462 -476.42358) (xy 8.993227 -476.184686) (xy 8.918576 -475.943316)
			(xy 8.851581 -475.699709) (xy 8.79231 -475.454108) (xy 8.740821 -475.206759) (xy 8.697167 -474.957908)
			(xy 8.661391 -474.707802) (xy 8.633527 -474.456692) (xy 8.613605 -474.204828) (xy 8.601644 -473.95246)
			(xy 8.597656 -473.69984) (xy 1.27 -473.69984) (xy 1.27 -482.193362) (xy 29.519874 -482.193362) (xy 29.519874 -482.106462)
			(xy 29.527892 -482.019933) (xy 29.54386 -481.934513) (xy 29.567641 -481.850931) (xy 29.599033 -481.769899)
			(xy 29.637767 -481.69211) (xy 29.683514 -481.618226) (xy 29.735883 -481.548879) (xy 29.794427 -481.484659)
			(xy 29.858647 -481.426115) (xy 29.927994 -481.373746) (xy 30.001878 -481.327999) (xy 30.079667 -481.289265)
			(xy 30.160699 -481.257873) (xy 30.244281 -481.234092) (xy 30.329701 -481.218124) (xy 30.41623 -481.210106)
			(xy 30.50313 -481.210106) (xy 30.589659 -481.218124) (xy 30.675079 -481.234092) (xy 30.758661 -481.257873)
			(xy 30.839693 -481.289265) (xy 30.917482 -481.327999) (xy 30.991366 -481.373746) (xy 31.060713 -481.426115)
			(xy 31.124933 -481.484659) (xy 31.183477 -481.548879) (xy 31.235846 -481.618226) (xy 31.281593 -481.69211)
			(xy 31.320327 -481.769899) (xy 31.351719 -481.850931) (xy 31.3755 -481.934513) (xy 31.391468 -482.019933)
			(xy 31.399486 -482.106462) (xy 31.399988 -482.149912) (xy 31.399486 -482.193362) (xy 34.599874 -482.193362)
			(xy 34.599874 -482.106462) (xy 34.607892 -482.019933) (xy 34.62386 -481.934513) (xy 34.647641 -481.850931)
			(xy 34.679033 -481.769899) (xy 34.717767 -481.69211) (xy 34.763514 -481.618226) (xy 34.815883 -481.548879)
			(xy 34.874427 -481.484659) (xy 34.938647 -481.426115) (xy 35.007994 -481.373746) (xy 35.081878 -481.327999)
			(xy 35.159667 -481.289265) (xy 35.240699 -481.257873) (xy 35.324281 -481.234092) (xy 35.409701 -481.218124)
			(xy 35.49623 -481.210106) (xy 35.58313 -481.210106) (xy 35.669659 -481.218124) (xy 35.755079 -481.234092)
			(xy 35.838661 -481.257873) (xy 35.919693 -481.289265) (xy 35.997482 -481.327999) (xy 36.071366 -481.373746)
			(xy 36.13432 -481.421287) (xy 37.952672 -481.421287) (xy 37.952672 -481.349965) (xy 37.960658 -481.279091)
			(xy 37.976528 -481.209556) (xy 38.000085 -481.142236) (xy 38.03103 -481.077977) (xy 38.068976 -481.017586)
			(xy 38.113445 -480.961824) (xy 38.163878 -480.911391) (xy 38.21964 -480.866922) (xy 38.280031 -480.828976)
			(xy 38.34429 -480.798031) (xy 38.41161 -480.774474) (xy 38.481145 -480.758604) (xy 38.552019 -480.750618)
			(xy 38.623341 -480.750618) (xy 38.694215 -480.758604) (xy 38.76375 -480.774474) (xy 38.83107 -480.798031)
			(xy 38.895329 -480.828976) (xy 38.95572 -480.866922) (xy 39.011482 -480.911391) (xy 39.061915 -480.961824)
			(xy 39.106384 -481.017586) (xy 39.14433 -481.077977) (xy 39.175275 -481.142236) (xy 39.198832 -481.209556)
			(xy 39.214702 -481.279091) (xy 39.222688 -481.349965) (xy 39.223188 -481.385626) (xy 39.222688 -481.421287)
			(xy 39.839384 -481.421287) (xy 39.839384 -481.349965) (xy 39.84737 -481.279091) (xy 39.86324 -481.209556)
			(xy 39.886797 -481.142236) (xy 39.917742 -481.077977) (xy 39.955688 -481.017586) (xy 40.000157 -480.961824)
			(xy 40.05059 -480.911391) (xy 40.106352 -480.866922) (xy 40.166743 -480.828976) (xy 40.231002 -480.798031)
			(xy 40.298322 -480.774474) (xy 40.367857 -480.758604) (xy 40.438731 -480.750618) (xy 40.510053 -480.750618)
			(xy 40.580927 -480.758604) (xy 40.650462 -480.774474) (xy 40.717782 -480.798031) (xy 40.782041 -480.828976)
			(xy 40.842432 -480.866922) (xy 40.898194 -480.911391) (xy 40.948627 -480.961824) (xy 40.993096 -481.017586)
			(xy 41.031042 -481.077977) (xy 41.061987 -481.142236) (xy 41.085544 -481.209556) (xy 41.101414 -481.279091)
			(xy 41.1094 -481.349965) (xy 41.1099 -481.385626) (xy 41.1094 -481.421287) (xy 42.080426 -481.421287)
			(xy 42.080426 -481.349965) (xy 42.088412 -481.279091) (xy 42.104282 -481.209556) (xy 42.127839 -481.142236)
			(xy 42.158784 -481.077977) (xy 42.19673 -481.017586) (xy 42.241199 -480.961824) (xy 42.291632 -480.911391)
			(xy 42.347394 -480.866922) (xy 42.407785 -480.828976) (xy 42.472044 -480.798031) (xy 42.539364 -480.774474)
			(xy 42.608899 -480.758604) (xy 42.679773 -480.750618) (xy 42.751095 -480.750618) (xy 42.821969 -480.758604)
			(xy 42.891504 -480.774474) (xy 42.958824 -480.798031) (xy 43.023083 -480.828976) (xy 43.083474 -480.866922)
			(xy 43.139236 -480.911391) (xy 43.189669 -480.961824) (xy 43.234138 -481.017586) (xy 43.272084 -481.077977)
			(xy 43.303029 -481.142236) (xy 43.326586 -481.209556) (xy 43.342456 -481.279091) (xy 43.350442 -481.349965)
			(xy 43.350942 -481.385626) (xy 43.350442 -481.421287) (xy 43.98441 -481.421287) (xy 43.98441 -481.349965)
			(xy 43.992396 -481.279091) (xy 44.008266 -481.209556) (xy 44.031823 -481.142236) (xy 44.062768 -481.077977)
			(xy 44.100714 -481.017586) (xy 44.145183 -480.961824) (xy 44.195616 -480.911391) (xy 44.251378 -480.866922)
			(xy 44.311769 -480.828976) (xy 44.376028 -480.798031) (xy 44.443348 -480.774474) (xy 44.512883 -480.758604)
			(xy 44.583757 -480.750618) (xy 44.655079 -480.750618) (xy 44.725953 -480.758604) (xy 44.795488 -480.774474)
			(xy 44.862808 -480.798031) (xy 44.927067 -480.828976) (xy 44.987458 -480.866922) (xy 45.04322 -480.911391)
			(xy 45.093653 -480.961824) (xy 45.138122 -481.017586) (xy 45.176068 -481.077977) (xy 45.207013 -481.142236)
			(xy 45.23057 -481.209556) (xy 45.24644 -481.279091) (xy 45.254426 -481.349965) (xy 45.254926 -481.385626)
			(xy 45.254426 -481.421287) (xy 45.24644 -481.492161) (xy 45.23057 -481.561696) (xy 45.207013 -481.629016)
			(xy 45.176068 -481.693275) (xy 45.138122 -481.753666) (xy 45.093653 -481.809428) (xy 45.04322 -481.859861)
			(xy 44.987458 -481.90433) (xy 44.927067 -481.942276) (xy 44.862808 -481.973221) (xy 44.795488 -481.996778)
			(xy 44.725953 -482.012648) (xy 44.655079 -482.020634) (xy 44.583757 -482.020634) (xy 44.512883 -482.012648)
			(xy 44.443348 -481.996778) (xy 44.376028 -481.973221) (xy 44.311769 -481.942276) (xy 44.251378 -481.90433)
			(xy 44.195616 -481.859861) (xy 44.145183 -481.809428) (xy 44.100714 -481.753666) (xy 44.062768 -481.693275)
			(xy 44.031823 -481.629016) (xy 44.008266 -481.561696) (xy 43.992396 -481.492161) (xy 43.98441 -481.421287)
			(xy 43.350442 -481.421287) (xy 43.342456 -481.492161) (xy 43.326586 -481.561696) (xy 43.303029 -481.629016)
			(xy 43.272084 -481.693275) (xy 43.234138 -481.753666) (xy 43.189669 -481.809428) (xy 43.139236 -481.859861)
			(xy 43.083474 -481.90433) (xy 43.023083 -481.942276) (xy 42.958824 -481.973221) (xy 42.891504 -481.996778)
			(xy 42.821969 -482.012648) (xy 42.751095 -482.020634) (xy 42.679773 -482.020634) (xy 42.608899 -482.012648)
			(xy 42.539364 -481.996778) (xy 42.472044 -481.973221) (xy 42.407785 -481.942276) (xy 42.347394 -481.90433)
			(xy 42.291632 -481.859861) (xy 42.241199 -481.809428) (xy 42.19673 -481.753666) (xy 42.158784 -481.693275)
			(xy 42.127839 -481.629016) (xy 42.104282 -481.561696) (xy 42.088412 -481.492161) (xy 42.080426 -481.421287)
			(xy 41.1094 -481.421287) (xy 41.101414 -481.492161) (xy 41.085544 -481.561696) (xy 41.061987 -481.629016)
			(xy 41.031042 -481.693275) (xy 40.993096 -481.753666) (xy 40.948627 -481.809428) (xy 40.898194 -481.859861)
			(xy 40.842432 -481.90433) (xy 40.782041 -481.942276) (xy 40.717782 -481.973221) (xy 40.650462 -481.996778)
			(xy 40.580927 -482.012648) (xy 40.510053 -482.020634) (xy 40.438731 -482.020634) (xy 40.367857 -482.012648)
			(xy 40.298322 -481.996778) (xy 40.231002 -481.973221) (xy 40.166743 -481.942276) (xy 40.106352 -481.90433)
			(xy 40.05059 -481.859861) (xy 40.000157 -481.809428) (xy 39.955688 -481.753666) (xy 39.917742 -481.693275)
			(xy 39.886797 -481.629016) (xy 39.86324 -481.561696) (xy 39.84737 -481.492161) (xy 39.839384 -481.421287)
			(xy 39.222688 -481.421287) (xy 39.214702 -481.492161) (xy 39.198832 -481.561696) (xy 39.175275 -481.629016)
			(xy 39.14433 -481.693275) (xy 39.106384 -481.753666) (xy 39.061915 -481.809428) (xy 39.011482 -481.859861)
			(xy 38.95572 -481.90433) (xy 38.895329 -481.942276) (xy 38.83107 -481.973221) (xy 38.76375 -481.996778)
			(xy 38.694215 -482.012648) (xy 38.623341 -482.020634) (xy 38.552019 -482.020634) (xy 38.481145 -482.012648)
			(xy 38.41161 -481.996778) (xy 38.34429 -481.973221) (xy 38.280031 -481.942276) (xy 38.21964 -481.90433)
			(xy 38.163878 -481.859861) (xy 38.113445 -481.809428) (xy 38.068976 -481.753666) (xy 38.03103 -481.693275)
			(xy 38.000085 -481.629016) (xy 37.976528 -481.561696) (xy 37.960658 -481.492161) (xy 37.952672 -481.421287)
			(xy 36.13432 -481.421287) (xy 36.140713 -481.426115) (xy 36.204933 -481.484659) (xy 36.263477 -481.548879)
			(xy 36.315846 -481.618226) (xy 36.361593 -481.69211) (xy 36.400327 -481.769899) (xy 36.431719 -481.850931)
			(xy 36.4555 -481.934513) (xy 36.471468 -482.019933) (xy 36.479486 -482.106462) (xy 36.479988 -482.149912)
			(xy 36.479486 -482.193362) (xy 36.471468 -482.279891) (xy 36.4555 -482.365311) (xy 36.431719 -482.448893)
			(xy 36.400327 -482.529925) (xy 36.361593 -482.607714) (xy 36.315846 -482.681598) (xy 36.263477 -482.750945)
			(xy 36.204933 -482.815165) (xy 36.140713 -482.873709) (xy 36.071366 -482.926078) (xy 35.997482 -482.971825)
			(xy 35.919693 -483.010559) (xy 35.838661 -483.041951) (xy 35.755079 -483.065732) (xy 35.669659 -483.0817)
			(xy 35.58313 -483.089718) (xy 35.49623 -483.089718) (xy 35.409701 -483.0817) (xy 35.324281 -483.065732)
			(xy 35.240699 -483.041951) (xy 35.159667 -483.010559) (xy 35.081878 -482.971825) (xy 35.007994 -482.926078)
			(xy 34.938647 -482.873709) (xy 34.874427 -482.815165) (xy 34.815883 -482.750945) (xy 34.763514 -482.681598)
			(xy 34.717767 -482.607714) (xy 34.679033 -482.529925) (xy 34.647641 -482.448893) (xy 34.62386 -482.365311)
			(xy 34.607892 -482.279891) (xy 34.599874 -482.193362) (xy 31.399486 -482.193362) (xy 31.391468 -482.279891)
			(xy 31.3755 -482.365311) (xy 31.351719 -482.448893) (xy 31.320327 -482.529925) (xy 31.281593 -482.607714)
			(xy 31.235846 -482.681598) (xy 31.183477 -482.750945) (xy 31.124933 -482.815165) (xy 31.060713 -482.873709)
			(xy 30.991366 -482.926078) (xy 30.917482 -482.971825) (xy 30.839693 -483.010559) (xy 30.758661 -483.041951)
			(xy 30.675079 -483.065732) (xy 30.589659 -483.0817) (xy 30.50313 -483.089718) (xy 30.41623 -483.089718)
			(xy 30.329701 -483.0817) (xy 30.244281 -483.065732) (xy 30.160699 -483.041951) (xy 30.079667 -483.010559)
			(xy 30.001878 -482.971825) (xy 29.927994 -482.926078) (xy 29.858647 -482.873709) (xy 29.794427 -482.815165)
			(xy 29.735883 -482.750945) (xy 29.683514 -482.681598) (xy 29.637767 -482.607714) (xy 29.599033 -482.529925)
			(xy 29.567641 -482.448893) (xy 29.54386 -482.365311) (xy 29.527892 -482.279891) (xy 29.519874 -482.193362)
			(xy 1.27 -482.193362) (xy 1.27 -483.311809) (xy 37.952672 -483.311809) (xy 37.952672 -483.240487)
			(xy 37.960658 -483.169613) (xy 37.976528 -483.100078) (xy 38.000085 -483.032758) (xy 38.03103 -482.968499)
			(xy 38.068976 -482.908108) (xy 38.113445 -482.852346) (xy 38.163878 -482.801913) (xy 38.21964 -482.757444)
			(xy 38.280031 -482.719498) (xy 38.34429 -482.688553) (xy 38.41161 -482.664996) (xy 38.481145 -482.649126)
			(xy 38.552019 -482.64114) (xy 38.623341 -482.64114) (xy 38.694215 -482.649126) (xy 38.76375 -482.664996)
			(xy 38.83107 -482.688553) (xy 38.895329 -482.719498) (xy 38.95572 -482.757444) (xy 39.011482 -482.801913)
			(xy 39.061915 -482.852346) (xy 39.106384 -482.908108) (xy 39.14433 -482.968499) (xy 39.175275 -483.032758)
			(xy 39.198832 -483.100078) (xy 39.214702 -483.169613) (xy 39.222688 -483.240487) (xy 39.223188 -483.276148)
			(xy 39.222688 -483.311809) (xy 39.839384 -483.311809) (xy 39.839384 -483.240487) (xy 39.84737 -483.169613)
			(xy 39.86324 -483.100078) (xy 39.886797 -483.032758) (xy 39.917742 -482.968499) (xy 39.955688 -482.908108)
			(xy 40.000157 -482.852346) (xy 40.05059 -482.801913) (xy 40.106352 -482.757444) (xy 40.166743 -482.719498)
			(xy 40.231002 -482.688553) (xy 40.298322 -482.664996) (xy 40.367857 -482.649126) (xy 40.438731 -482.64114)
			(xy 40.510053 -482.64114) (xy 40.580927 -482.649126) (xy 40.650462 -482.664996) (xy 40.717782 -482.688553)
			(xy 40.782041 -482.719498) (xy 40.842432 -482.757444) (xy 40.898194 -482.801913) (xy 40.948627 -482.852346)
			(xy 40.993096 -482.908108) (xy 41.031042 -482.968499) (xy 41.061987 -483.032758) (xy 41.085544 -483.100078)
			(xy 41.101414 -483.169613) (xy 41.1094 -483.240487) (xy 41.1099 -483.276148) (xy 41.1094 -483.311809)
			(xy 42.080426 -483.311809) (xy 42.080426 -483.240487) (xy 42.088412 -483.169613) (xy 42.104282 -483.100078)
			(xy 42.127839 -483.032758) (xy 42.158784 -482.968499) (xy 42.19673 -482.908108) (xy 42.241199 -482.852346)
			(xy 42.291632 -482.801913) (xy 42.347394 -482.757444) (xy 42.407785 -482.719498) (xy 42.472044 -482.688553)
			(xy 42.539364 -482.664996) (xy 42.608899 -482.649126) (xy 42.679773 -482.64114) (xy 42.751095 -482.64114)
			(xy 42.821969 -482.649126) (xy 42.891504 -482.664996) (xy 42.958824 -482.688553) (xy 43.023083 -482.719498)
			(xy 43.083474 -482.757444) (xy 43.139236 -482.801913) (xy 43.189669 -482.852346) (xy 43.234138 -482.908108)
			(xy 43.272084 -482.968499) (xy 43.303029 -483.032758) (xy 43.326586 -483.100078) (xy 43.342456 -483.169613)
			(xy 43.350442 -483.240487) (xy 43.350942 -483.276148) (xy 43.350442 -483.311809) (xy 43.98441 -483.311809)
			(xy 43.98441 -483.240487) (xy 43.992396 -483.169613) (xy 44.008266 -483.100078) (xy 44.031823 -483.032758)
			(xy 44.062768 -482.968499) (xy 44.100714 -482.908108) (xy 44.145183 -482.852346) (xy 44.195616 -482.801913)
			(xy 44.251378 -482.757444) (xy 44.311769 -482.719498) (xy 44.376028 -482.688553) (xy 44.443348 -482.664996)
			(xy 44.512883 -482.649126) (xy 44.583757 -482.64114) (xy 44.655079 -482.64114) (xy 44.725953 -482.649126)
			(xy 44.795488 -482.664996) (xy 44.862808 -482.688553) (xy 44.927067 -482.719498) (xy 44.97121 -482.747235)
			(xy 47.507896 -482.747235) (xy 47.507896 -482.666125) (xy 47.515846 -482.585406) (xy 47.531669 -482.505855)
			(xy 47.555214 -482.428239) (xy 47.586253 -482.353303) (xy 47.624488 -482.281771) (xy 47.66955 -482.214331)
			(xy 47.721005 -482.151632) (xy 47.778358 -482.094279) (xy 47.841057 -482.042824) (xy 47.908497 -481.997762)
			(xy 47.980029 -481.959527) (xy 48.054965 -481.928488) (xy 48.132581 -481.904943) (xy 48.212132 -481.88912)
			(xy 48.292851 -481.88117) (xy 48.373961 -481.88117) (xy 48.45468 -481.88912) (xy 48.534231 -481.904943)
			(xy 48.611847 -481.928488) (xy 48.686783 -481.959527) (xy 48.758315 -481.997762) (xy 48.825755 -482.042824)
			(xy 48.888454 -482.094279) (xy 48.945807 -482.151632) (xy 48.997262 -482.214331) (xy 49.042324 -482.281771)
			(xy 49.080559 -482.353303) (xy 49.111598 -482.428239) (xy 49.135143 -482.505855) (xy 49.150966 -482.585406)
			(xy 49.158916 -482.666125) (xy 49.159414 -482.70668) (xy 49.158916 -482.747235) (xy 49.150966 -482.827954)
			(xy 49.135143 -482.907505) (xy 49.111598 -482.985121) (xy 49.080559 -483.060057) (xy 49.042324 -483.131589)
			(xy 48.997262 -483.199029) (xy 48.945807 -483.261728) (xy 48.888454 -483.319081) (xy 48.825755 -483.370536)
			(xy 48.758315 -483.415598) (xy 48.686783 -483.453833) (xy 48.611847 -483.484872) (xy 48.534231 -483.508417)
			(xy 48.45468 -483.52424) (xy 48.373961 -483.53219) (xy 48.292851 -483.53219) (xy 48.212132 -483.52424)
			(xy 48.132581 -483.508417) (xy 48.054965 -483.484872) (xy 47.980029 -483.453833) (xy 47.908497 -483.415598)
			(xy 47.841057 -483.370536) (xy 47.778358 -483.319081) (xy 47.721005 -483.261728) (xy 47.66955 -483.199029)
			(xy 47.624488 -483.131589) (xy 47.586253 -483.060057) (xy 47.555214 -482.985121) (xy 47.531669 -482.907505)
			(xy 47.515846 -482.827954) (xy 47.507896 -482.747235) (xy 44.97121 -482.747235) (xy 44.987458 -482.757444)
			(xy 45.04322 -482.801913) (xy 45.093653 -482.852346) (xy 45.138122 -482.908108) (xy 45.176068 -482.968499)
			(xy 45.207013 -483.032758) (xy 45.23057 -483.100078) (xy 45.24644 -483.169613) (xy 45.254426 -483.240487)
			(xy 45.254926 -483.276148) (xy 45.254426 -483.311809) (xy 45.24644 -483.382683) (xy 45.23057 -483.452218)
			(xy 45.207013 -483.519538) (xy 45.176068 -483.583797) (xy 45.138122 -483.644188) (xy 45.093653 -483.69995)
			(xy 45.04322 -483.750383) (xy 44.987458 -483.794852) (xy 44.927067 -483.832798) (xy 44.862808 -483.863743)
			(xy 44.795488 -483.8873) (xy 44.725953 -483.90317) (xy 44.655079 -483.911156) (xy 44.583757 -483.911156)
			(xy 44.512883 -483.90317) (xy 44.443348 -483.8873) (xy 44.376028 -483.863743) (xy 44.311769 -483.832798)
			(xy 44.251378 -483.794852) (xy 44.195616 -483.750383) (xy 44.145183 -483.69995) (xy 44.100714 -483.644188)
			(xy 44.062768 -483.583797) (xy 44.031823 -483.519538) (xy 44.008266 -483.452218) (xy 43.992396 -483.382683)
			(xy 43.98441 -483.311809) (xy 43.350442 -483.311809) (xy 43.342456 -483.382683) (xy 43.326586 -483.452218)
			(xy 43.303029 -483.519538) (xy 43.272084 -483.583797) (xy 43.234138 -483.644188) (xy 43.189669 -483.69995)
			(xy 43.139236 -483.750383) (xy 43.083474 -483.794852) (xy 43.023083 -483.832798) (xy 42.958824 -483.863743)
			(xy 42.891504 -483.8873) (xy 42.821969 -483.90317) (xy 42.751095 -483.911156) (xy 42.679773 -483.911156)
			(xy 42.608899 -483.90317) (xy 42.539364 -483.8873) (xy 42.472044 -483.863743) (xy 42.407785 -483.832798)
			(xy 42.347394 -483.794852) (xy 42.291632 -483.750383) (xy 42.241199 -483.69995) (xy 42.19673 -483.644188)
			(xy 42.158784 -483.583797) (xy 42.127839 -483.519538) (xy 42.104282 -483.452218) (xy 42.088412 -483.382683)
			(xy 42.080426 -483.311809) (xy 41.1094 -483.311809) (xy 41.101414 -483.382683) (xy 41.085544 -483.452218)
			(xy 41.061987 -483.519538) (xy 41.031042 -483.583797) (xy 40.993096 -483.644188) (xy 40.948627 -483.69995)
			(xy 40.898194 -483.750383) (xy 40.842432 -483.794852) (xy 40.782041 -483.832798) (xy 40.717782 -483.863743)
			(xy 40.650462 -483.8873) (xy 40.580927 -483.90317) (xy 40.510053 -483.911156) (xy 40.438731 -483.911156)
			(xy 40.367857 -483.90317) (xy 40.298322 -483.8873) (xy 40.231002 -483.863743) (xy 40.166743 -483.832798)
			(xy 40.106352 -483.794852) (xy 40.05059 -483.750383) (xy 40.000157 -483.69995) (xy 39.955688 -483.644188)
			(xy 39.917742 -483.583797) (xy 39.886797 -483.519538) (xy 39.86324 -483.452218) (xy 39.84737 -483.382683)
			(xy 39.839384 -483.311809) (xy 39.222688 -483.311809) (xy 39.214702 -483.382683) (xy 39.198832 -483.452218)
			(xy 39.175275 -483.519538) (xy 39.14433 -483.583797) (xy 39.106384 -483.644188) (xy 39.061915 -483.69995)
			(xy 39.011482 -483.750383) (xy 38.95572 -483.794852) (xy 38.895329 -483.832798) (xy 38.83107 -483.863743)
			(xy 38.76375 -483.8873) (xy 38.694215 -483.90317) (xy 38.623341 -483.911156) (xy 38.552019 -483.911156)
			(xy 38.481145 -483.90317) (xy 38.41161 -483.8873) (xy 38.34429 -483.863743) (xy 38.280031 -483.832798)
			(xy 38.21964 -483.794852) (xy 38.163878 -483.750383) (xy 38.113445 -483.69995) (xy 38.068976 -483.644188)
			(xy 38.03103 -483.583797) (xy 38.000085 -483.519538) (xy 37.976528 -483.452218) (xy 37.960658 -483.382683)
			(xy 37.952672 -483.311809) (xy 1.27 -483.311809) (xy 1.27 -484.733362) (xy 29.519874 -484.733362)
			(xy 29.519874 -484.646462) (xy 29.527892 -484.559933) (xy 29.54386 -484.474513) (xy 29.567641 -484.390931)
			(xy 29.599033 -484.309899) (xy 29.637767 -484.23211) (xy 29.683514 -484.158226) (xy 29.735883 -484.088879)
			(xy 29.794427 -484.024659) (xy 29.858647 -483.966115) (xy 29.927994 -483.913746) (xy 30.001878 -483.867999)
			(xy 30.079667 -483.829265) (xy 30.160699 -483.797873) (xy 30.244281 -483.774092) (xy 30.329701 -483.758124)
			(xy 30.41623 -483.750106) (xy 30.50313 -483.750106) (xy 30.589659 -483.758124) (xy 30.675079 -483.774092)
			(xy 30.758661 -483.797873) (xy 30.839693 -483.829265) (xy 30.917482 -483.867999) (xy 30.991366 -483.913746)
			(xy 31.060713 -483.966115) (xy 31.124933 -484.024659) (xy 31.183477 -484.088879) (xy 31.235846 -484.158226)
			(xy 31.281593 -484.23211) (xy 31.320327 -484.309899) (xy 31.351719 -484.390931) (xy 31.3755 -484.474513)
			(xy 31.391468 -484.559933) (xy 31.399486 -484.646462) (xy 31.399988 -484.689912) (xy 31.399486 -484.733362)
			(xy 34.599874 -484.733362) (xy 34.599874 -484.646462) (xy 34.607892 -484.559933) (xy 34.62386 -484.474513)
			(xy 34.647641 -484.390931) (xy 34.679033 -484.309899) (xy 34.717767 -484.23211) (xy 34.763514 -484.158226)
			(xy 34.815883 -484.088879) (xy 34.874427 -484.024659) (xy 34.938647 -483.966115) (xy 35.007994 -483.913746)
			(xy 35.081878 -483.867999) (xy 35.159667 -483.829265) (xy 35.240699 -483.797873) (xy 35.324281 -483.774092)
			(xy 35.409701 -483.758124) (xy 35.49623 -483.750106) (xy 35.58313 -483.750106) (xy 35.669659 -483.758124)
			(xy 35.755079 -483.774092) (xy 35.838661 -483.797873) (xy 35.919693 -483.829265) (xy 35.997482 -483.867999)
			(xy 36.071366 -483.913746) (xy 36.140713 -483.966115) (xy 36.204933 -484.024659) (xy 36.263477 -484.088879)
			(xy 36.315846 -484.158226) (xy 36.361593 -484.23211) (xy 36.400327 -484.309899) (xy 36.431719 -484.390931)
			(xy 36.4555 -484.474513) (xy 36.471468 -484.559933) (xy 36.479486 -484.646462) (xy 36.479988 -484.689912)
			(xy 36.479486 -484.733362) (xy 36.471468 -484.819891) (xy 36.4555 -484.905311) (xy 36.431719 -484.988893)
			(xy 36.400327 -485.069925) (xy 36.361593 -485.147714) (xy 36.315846 -485.221598) (xy 36.263477 -485.290945)
			(xy 36.206949 -485.352953) (xy 37.952672 -485.352953) (xy 37.952672 -485.281631) (xy 37.960658 -485.210757)
			(xy 37.976528 -485.141222) (xy 38.000085 -485.073902) (xy 38.03103 -485.009643) (xy 38.068976 -484.949252)
			(xy 38.113445 -484.89349) (xy 38.163878 -484.843057) (xy 38.21964 -484.798588) (xy 38.280031 -484.760642)
			(xy 38.34429 -484.729697) (xy 38.41161 -484.70614) (xy 38.481145 -484.69027) (xy 38.552019 -484.682284)
			(xy 38.623341 -484.682284) (xy 38.694215 -484.69027) (xy 38.76375 -484.70614) (xy 38.83107 -484.729697)
			(xy 38.895329 -484.760642) (xy 38.95572 -484.798588) (xy 39.011482 -484.843057) (xy 39.061915 -484.89349)
			(xy 39.106384 -484.949252) (xy 39.14433 -485.009643) (xy 39.175275 -485.073902) (xy 39.198832 -485.141222)
			(xy 39.214702 -485.210757) (xy 39.222688 -485.281631) (xy 39.223188 -485.317292) (xy 39.222688 -485.352953)
			(xy 39.839384 -485.352953) (xy 39.839384 -485.281631) (xy 39.84737 -485.210757) (xy 39.86324 -485.141222)
			(xy 39.886797 -485.073902) (xy 39.917742 -485.009643) (xy 39.955688 -484.949252) (xy 40.000157 -484.89349)
			(xy 40.05059 -484.843057) (xy 40.106352 -484.798588) (xy 40.166743 -484.760642) (xy 40.231002 -484.729697)
			(xy 40.298322 -484.70614) (xy 40.367857 -484.69027) (xy 40.438731 -484.682284) (xy 40.510053 -484.682284)
			(xy 40.580927 -484.69027) (xy 40.650462 -484.70614) (xy 40.717782 -484.729697) (xy 40.782041 -484.760642)
			(xy 40.842432 -484.798588) (xy 40.898194 -484.843057) (xy 40.948627 -484.89349) (xy 40.993096 -484.949252)
			(xy 41.031042 -485.009643) (xy 41.061987 -485.073902) (xy 41.085544 -485.141222) (xy 41.101414 -485.210757)
			(xy 41.1094 -485.281631) (xy 41.1099 -485.317292) (xy 41.1094 -485.352953) (xy 42.080426 -485.352953)
			(xy 42.080426 -485.281631) (xy 42.088412 -485.210757) (xy 42.104282 -485.141222) (xy 42.127839 -485.073902)
			(xy 42.158784 -485.009643) (xy 42.19673 -484.949252) (xy 42.241199 -484.89349) (xy 42.291632 -484.843057)
			(xy 42.347394 -484.798588) (xy 42.407785 -484.760642) (xy 42.472044 -484.729697) (xy 42.539364 -484.70614)
			(xy 42.608899 -484.69027) (xy 42.679773 -484.682284) (xy 42.751095 -484.682284) (xy 42.821969 -484.69027)
			(xy 42.891504 -484.70614) (xy 42.958824 -484.729697) (xy 43.023083 -484.760642) (xy 43.083474 -484.798588)
			(xy 43.139236 -484.843057) (xy 43.189669 -484.89349) (xy 43.234138 -484.949252) (xy 43.272084 -485.009643)
			(xy 43.303029 -485.073902) (xy 43.326586 -485.141222) (xy 43.342456 -485.210757) (xy 43.350442 -485.281631)
			(xy 43.350942 -485.317292) (xy 43.350442 -485.352953) (xy 43.98441 -485.352953) (xy 43.98441 -485.281631)
			(xy 43.992396 -485.210757) (xy 44.008266 -485.141222) (xy 44.031823 -485.073902) (xy 44.062768 -485.009643)
			(xy 44.100714 -484.949252) (xy 44.145183 -484.89349) (xy 44.195616 -484.843057) (xy 44.251378 -484.798588)
			(xy 44.311769 -484.760642) (xy 44.376028 -484.729697) (xy 44.443348 -484.70614) (xy 44.512883 -484.69027)
			(xy 44.583757 -484.682284) (xy 44.655079 -484.682284) (xy 44.725953 -484.69027) (xy 44.795488 -484.70614)
			(xy 44.862808 -484.729697) (xy 44.927067 -484.760642) (xy 44.987458 -484.798588) (xy 45.04322 -484.843057)
			(xy 45.093653 -484.89349) (xy 45.138122 -484.949252) (xy 45.176068 -485.009643) (xy 45.207013 -485.073902)
			(xy 45.23057 -485.141222) (xy 45.24644 -485.210757) (xy 45.254426 -485.281631) (xy 45.254926 -485.317292)
			(xy 45.254426 -485.352953) (xy 45.24644 -485.423827) (xy 45.246117 -485.425242) (xy 87.09609 -485.425242)
			(xy 87.100161 -485.36962) (xy 87.112287 -485.315183) (xy 87.13221 -485.263092) (xy 87.159506 -485.214457)
			(xy 87.193592 -485.170314) (xy 87.233741 -485.131605) (xy 87.279099 -485.099154) (xy 87.328699 -485.073653)
			(xy 87.381483 -485.055646) (xy 87.436326 -485.045516) (xy 87.49206 -485.043479) (xy 87.547497 -485.049579)
			(xy 87.601454 -485.063685) (xy 87.652783 -485.085497) (xy 87.700389 -485.114551) (xy 87.743257 -485.150226)
			(xy 87.780474 -485.191763) (xy 87.811247 -485.238276) (xy 87.834919 -485.288773) (xy 87.850987 -485.34218)
			(xy 87.859107 -485.397356) (xy 87.859616 -485.425242) (xy 87.859107 -485.453128) (xy 87.850987 -485.508304)
			(xy 87.834919 -485.561711) (xy 87.811247 -485.612208) (xy 87.780474 -485.658721) (xy 87.743257 -485.700258)
			(xy 87.700389 -485.735933) (xy 87.652783 -485.764987) (xy 87.601454 -485.786799) (xy 87.547497 -485.800905)
			(xy 87.49206 -485.807005) (xy 87.436326 -485.804968) (xy 87.381483 -485.794838) (xy 87.328699 -485.776831)
			(xy 87.279099 -485.75133) (xy 87.233741 -485.718879) (xy 87.193592 -485.68017) (xy 87.159506 -485.636027)
			(xy 87.13221 -485.587392) (xy 87.112287 -485.535301) (xy 87.100161 -485.480864) (xy 87.09609 -485.425242)
			(xy 45.246117 -485.425242) (xy 45.23057 -485.493362) (xy 45.207013 -485.560682) (xy 45.176068 -485.624941)
			(xy 45.138122 -485.685332) (xy 45.093653 -485.741094) (xy 45.04322 -485.791527) (xy 44.987458 -485.835996)
			(xy 44.927067 -485.873942) (xy 44.862808 -485.904887) (xy 44.795488 -485.928444) (xy 44.725953 -485.944314)
			(xy 44.655079 -485.9523) (xy 44.583757 -485.9523) (xy 44.512883 -485.944314) (xy 44.443348 -485.928444)
			(xy 44.376028 -485.904887) (xy 44.311769 -485.873942) (xy 44.251378 -485.835996) (xy 44.195616 -485.791527)
			(xy 44.145183 -485.741094) (xy 44.100714 -485.685332) (xy 44.062768 -485.624941) (xy 44.031823 -485.560682)
			(xy 44.008266 -485.493362) (xy 43.992396 -485.423827) (xy 43.98441 -485.352953) (xy 43.350442 -485.352953)
			(xy 43.342456 -485.423827) (xy 43.326586 -485.493362) (xy 43.303029 -485.560682) (xy 43.272084 -485.624941)
			(xy 43.234138 -485.685332) (xy 43.189669 -485.741094) (xy 43.139236 -485.791527) (xy 43.083474 -485.835996)
			(xy 43.023083 -485.873942) (xy 42.958824 -485.904887) (xy 42.891504 -485.928444) (xy 42.821969 -485.944314)
			(xy 42.751095 -485.9523) (xy 42.679773 -485.9523) (xy 42.608899 -485.944314) (xy 42.539364 -485.928444)
			(xy 42.472044 -485.904887) (xy 42.407785 -485.873942) (xy 42.347394 -485.835996) (xy 42.291632 -485.791527)
			(xy 42.241199 -485.741094) (xy 42.19673 -485.685332) (xy 42.158784 -485.624941) (xy 42.127839 -485.560682)
			(xy 42.104282 -485.493362) (xy 42.088412 -485.423827) (xy 42.080426 -485.352953) (xy 41.1094 -485.352953)
			(xy 41.101414 -485.423827) (xy 41.085544 -485.493362) (xy 41.061987 -485.560682) (xy 41.031042 -485.624941)
			(xy 40.993096 -485.685332) (xy 40.948627 -485.741094) (xy 40.898194 -485.791527) (xy 40.842432 -485.835996)
			(xy 40.782041 -485.873942) (xy 40.717782 -485.904887) (xy 40.650462 -485.928444) (xy 40.580927 -485.944314)
			(xy 40.510053 -485.9523) (xy 40.438731 -485.9523) (xy 40.367857 -485.944314) (xy 40.298322 -485.928444)
			(xy 40.231002 -485.904887) (xy 40.166743 -485.873942) (xy 40.106352 -485.835996) (xy 40.05059 -485.791527)
			(xy 40.000157 -485.741094) (xy 39.955688 -485.685332) (xy 39.917742 -485.624941) (xy 39.886797 -485.560682)
			(xy 39.86324 -485.493362) (xy 39.84737 -485.423827) (xy 39.839384 -485.352953) (xy 39.222688 -485.352953)
			(xy 39.214702 -485.423827) (xy 39.198832 -485.493362) (xy 39.175275 -485.560682) (xy 39.14433 -485.624941)
			(xy 39.106384 -485.685332) (xy 39.061915 -485.741094) (xy 39.011482 -485.791527) (xy 38.95572 -485.835996)
			(xy 38.895329 -485.873942) (xy 38.83107 -485.904887) (xy 38.76375 -485.928444) (xy 38.694215 -485.944314)
			(xy 38.623341 -485.9523) (xy 38.552019 -485.9523) (xy 38.481145 -485.944314) (xy 38.41161 -485.928444)
			(xy 38.34429 -485.904887) (xy 38.280031 -485.873942) (xy 38.21964 -485.835996) (xy 38.163878 -485.791527)
			(xy 38.113445 -485.741094) (xy 38.068976 -485.685332) (xy 38.03103 -485.624941) (xy 38.000085 -485.560682)
			(xy 37.976528 -485.493362) (xy 37.960658 -485.423827) (xy 37.952672 -485.352953) (xy 36.206949 -485.352953)
			(xy 36.204933 -485.355165) (xy 36.140713 -485.413709) (xy 36.071366 -485.466078) (xy 35.997482 -485.511825)
			(xy 35.919693 -485.550559) (xy 35.838661 -485.581951) (xy 35.755079 -485.605732) (xy 35.669659 -485.6217)
			(xy 35.58313 -485.629718) (xy 35.49623 -485.629718) (xy 35.409701 -485.6217) (xy 35.324281 -485.605732)
			(xy 35.240699 -485.581951) (xy 35.159667 -485.550559) (xy 35.081878 -485.511825) (xy 35.007994 -485.466078)
			(xy 34.938647 -485.413709) (xy 34.874427 -485.355165) (xy 34.815883 -485.290945) (xy 34.763514 -485.221598)
			(xy 34.717767 -485.147714) (xy 34.679033 -485.069925) (xy 34.647641 -484.988893) (xy 34.62386 -484.905311)
			(xy 34.607892 -484.819891) (xy 34.599874 -484.733362) (xy 31.399486 -484.733362) (xy 31.391468 -484.819891)
			(xy 31.3755 -484.905311) (xy 31.351719 -484.988893) (xy 31.320327 -485.069925) (xy 31.281593 -485.147714)
			(xy 31.235846 -485.221598) (xy 31.183477 -485.290945) (xy 31.124933 -485.355165) (xy 31.060713 -485.413709)
			(xy 30.991366 -485.466078) (xy 30.917482 -485.511825) (xy 30.839693 -485.550559) (xy 30.758661 -485.581951)
			(xy 30.675079 -485.605732) (xy 30.589659 -485.6217) (xy 30.50313 -485.629718) (xy 30.41623 -485.629718)
			(xy 30.329701 -485.6217) (xy 30.244281 -485.605732) (xy 30.160699 -485.581951) (xy 30.079667 -485.550559)
			(xy 30.001878 -485.511825) (xy 29.927994 -485.466078) (xy 29.858647 -485.413709) (xy 29.794427 -485.355165)
			(xy 29.735883 -485.290945) (xy 29.683514 -485.221598) (xy 29.637767 -485.147714) (xy 29.599033 -485.069925)
			(xy 29.567641 -484.988893) (xy 29.54386 -484.905311) (xy 29.527892 -484.819891) (xy 29.519874 -484.733362)
			(xy 1.27 -484.733362) (xy 1.27 -486.669334) (xy 1.270551 -486.692696) (xy 1.279134 -486.738627) (xy 1.29597 -486.782214)
			(xy 1.320492 -486.821989) (xy 1.351871 -486.85661) (xy 1.389052 -486.88491) (xy 1.430779 -486.905936)
			(xy 1.475648 -486.918978) (xy 1.522145 -486.923598) (xy 1.568703 -486.919638) (xy 1.613752 -486.907234)
			(xy 1.655774 -486.886802) (xy 1.693352 -486.859032) (xy 1.709674 -486.842308) (xy 1.754144 -486.795272)
			(xy 1.848064 -486.706175) (xy 1.947334 -486.623082) (xy 2.051571 -486.546313) (xy 2.160374 -486.476164)
			(xy 2.273323 -486.412906) (xy 2.389982 -486.356783) (xy 2.5099 -486.308012) (xy 2.632615 -486.26678)
			(xy 2.757653 -486.233247) (xy 2.884532 -486.207542) (xy 3.012762 -486.189765) (xy 3.141848 -486.179983)
			(xy 3.271293 -486.178236) (xy 3.400597 -486.184529) (xy 3.52926 -486.198838) (xy 3.656786 -486.221108)
			(xy 3.782684 -486.251253) (xy 3.906468 -486.289157) (xy 4.027658 -486.334673) (xy 4.14579 -486.387627)
			(xy 4.260405 -486.447812) (xy 4.371062 -486.514999) (xy 4.477334 -486.588926) (xy 4.578812 -486.669308)
			(xy 4.675102 -486.755837) (xy 4.765834 -486.848177) (xy 4.850658 -486.945972) (xy 4.929246 -487.048845)
			(xy 5.001295 -487.1564) (xy 5.066527 -487.26822) (xy 5.124691 -487.383875) (xy 5.175561 -487.502918)
			(xy 5.218942 -487.624889) (xy 5.254666 -487.749319) (xy 5.282595 -487.875727) (xy 5.302622 -488.003625)
			(xy 5.314669 -488.13252) (xy 5.31869 -488.261914) (xy 12.580624 -488.261914) (xy 12.584655 -488.132348)
			(xy 12.596734 -488.003284) (xy 12.616813 -487.87522) (xy 12.644815 -487.748653) (xy 12.680632 -487.62407)
			(xy 12.724124 -487.501956) (xy 12.775124 -487.382782) (xy 12.833435 -487.267009) (xy 12.89883 -487.155085)
			(xy 12.971057 -487.047443) (xy 13.049837 -486.9445) (xy 13.134864 -486.846654) (xy 13.225809 -486.754282)
			(xy 13.322321 -486.667744) (xy 13.424027 -486.587373) (xy 13.530533 -486.513481) (xy 13.641426 -486.446353)
			(xy 13.756278 -486.386249) (xy 13.874645 -486.333402) (xy 13.996068 -486.288015) (xy 14.120078 -486.250266)
			(xy 14.246195 -486.220299) (xy 14.373931 -486.19823) (xy 14.502792 -486.184146) (xy 14.632279 -486.1781)
			(xy 14.761892 -486.180116) (xy 14.891128 -486.190186) (xy 15.019489 -486.208271) (xy 15.146477 -486.234301)
			(xy 15.271601 -486.268176) (xy 15.394377 -486.309764) (xy 15.51433 -486.358905) (xy 15.630995 -486.415408)
			(xy 15.743923 -486.479055) (xy 15.852675 -486.549599) (xy 15.956831 -486.626768) (xy 16.055988 -486.710263)
			(xy 16.149762 -486.799761) (xy 16.237791 -486.894916) (xy 16.319734 -486.995359) (xy 16.395273 -487.100702)
			(xy 16.464118 -487.210538) (xy 16.49825 -487.273362) (xy 29.519874 -487.273362) (xy 29.519874 -487.186462)
			(xy 29.527892 -487.099933) (xy 29.54386 -487.014513) (xy 29.567641 -486.930931) (xy 29.599033 -486.849899)
			(xy 29.637767 -486.77211) (xy 29.683514 -486.698226) (xy 29.735883 -486.628879) (xy 29.794427 -486.564659)
			(xy 29.858647 -486.506115) (xy 29.927994 -486.453746) (xy 30.001878 -486.407999) (xy 30.079667 -486.369265)
			(xy 30.160699 -486.337873) (xy 30.244281 -486.314092) (xy 30.329701 -486.298124) (xy 30.41623 -486.290106)
			(xy 30.50313 -486.290106) (xy 30.589659 -486.298124) (xy 30.675079 -486.314092) (xy 30.758661 -486.337873)
			(xy 30.839693 -486.369265) (xy 30.917482 -486.407999) (xy 30.991366 -486.453746) (xy 31.060713 -486.506115)
			(xy 31.124933 -486.564659) (xy 31.183477 -486.628879) (xy 31.235846 -486.698226) (xy 31.281593 -486.77211)
			(xy 31.320327 -486.849899) (xy 31.351719 -486.930931) (xy 31.3755 -487.014513) (xy 31.391468 -487.099933)
			(xy 31.399486 -487.186462) (xy 31.399988 -487.229912) (xy 31.399486 -487.273362) (xy 34.599874 -487.273362)
			(xy 34.599874 -487.186462) (xy 34.607892 -487.099933) (xy 34.62386 -487.014513) (xy 34.647641 -486.930931)
			(xy 34.679033 -486.849899) (xy 34.717767 -486.77211) (xy 34.763514 -486.698226) (xy 34.815883 -486.628879)
			(xy 34.874427 -486.564659) (xy 34.938647 -486.506115) (xy 35.007994 -486.453746) (xy 35.081878 -486.407999)
			(xy 35.159667 -486.369265) (xy 35.240699 -486.337873) (xy 35.324281 -486.314092) (xy 35.409701 -486.298124)
			(xy 35.49623 -486.290106) (xy 35.58313 -486.290106) (xy 35.669659 -486.298124) (xy 35.755079 -486.314092)
			(xy 35.838661 -486.337873) (xy 35.919693 -486.369265) (xy 35.997482 -486.407999) (xy 36.071366 -486.453746)
			(xy 36.140713 -486.506115) (xy 36.204933 -486.564659) (xy 36.263477 -486.628879) (xy 36.315846 -486.698226)
			(xy 36.361593 -486.77211) (xy 36.400327 -486.849899) (xy 36.431719 -486.930931) (xy 36.4555 -487.014513)
			(xy 36.471468 -487.099933) (xy 36.479486 -487.186462) (xy 36.479988 -487.229912) (xy 36.479608 -487.262779)
			(xy 37.952672 -487.262779) (xy 37.952672 -487.191457) (xy 37.960658 -487.120583) (xy 37.976528 -487.051048)
			(xy 38.000085 -486.983728) (xy 38.03103 -486.919469) (xy 38.068976 -486.859078) (xy 38.113445 -486.803316)
			(xy 38.163878 -486.752883) (xy 38.21964 -486.708414) (xy 38.280031 -486.670468) (xy 38.34429 -486.639523)
			(xy 38.41161 -486.615966) (xy 38.481145 -486.600096) (xy 38.552019 -486.59211) (xy 38.623341 -486.59211)
			(xy 38.694215 -486.600096) (xy 38.76375 -486.615966) (xy 38.83107 -486.639523) (xy 38.895329 -486.670468)
			(xy 38.95572 -486.708414) (xy 39.011482 -486.752883) (xy 39.061915 -486.803316) (xy 39.106384 -486.859078)
			(xy 39.14433 -486.919469) (xy 39.175275 -486.983728) (xy 39.198832 -487.051048) (xy 39.214702 -487.120583)
			(xy 39.222688 -487.191457) (xy 39.223188 -487.227118) (xy 39.222688 -487.262779) (xy 39.839384 -487.262779)
			(xy 39.839384 -487.191457) (xy 39.84737 -487.120583) (xy 39.86324 -487.051048) (xy 39.886797 -486.983728)
			(xy 39.917742 -486.919469) (xy 39.955688 -486.859078) (xy 40.000157 -486.803316) (xy 40.05059 -486.752883)
			(xy 40.106352 -486.708414) (xy 40.166743 -486.670468) (xy 40.231002 -486.639523) (xy 40.298322 -486.615966)
			(xy 40.367857 -486.600096) (xy 40.438731 -486.59211) (xy 40.510053 -486.59211) (xy 40.580927 -486.600096)
			(xy 40.650462 -486.615966) (xy 40.717782 -486.639523) (xy 40.782041 -486.670468) (xy 40.842432 -486.708414)
			(xy 40.898194 -486.752883) (xy 40.948627 -486.803316) (xy 40.993096 -486.859078) (xy 41.031042 -486.919469)
			(xy 41.061987 -486.983728) (xy 41.085544 -487.051048) (xy 41.101414 -487.120583) (xy 41.1094 -487.191457)
			(xy 41.1099 -487.227118) (xy 41.1094 -487.262779) (xy 42.080426 -487.262779) (xy 42.080426 -487.191457)
			(xy 42.088412 -487.120583) (xy 42.104282 -487.051048) (xy 42.127839 -486.983728) (xy 42.158784 -486.919469)
			(xy 42.19673 -486.859078) (xy 42.241199 -486.803316) (xy 42.291632 -486.752883) (xy 42.347394 -486.708414)
			(xy 42.407785 -486.670468) (xy 42.472044 -486.639523) (xy 42.539364 -486.615966) (xy 42.608899 -486.600096)
			(xy 42.679773 -486.59211) (xy 42.751095 -486.59211) (xy 42.821969 -486.600096) (xy 42.891504 -486.615966)
			(xy 42.958824 -486.639523) (xy 43.023083 -486.670468) (xy 43.083474 -486.708414) (xy 43.139236 -486.752883)
			(xy 43.189669 -486.803316) (xy 43.234138 -486.859078) (xy 43.272084 -486.919469) (xy 43.303029 -486.983728)
			(xy 43.326586 -487.051048) (xy 43.342456 -487.120583) (xy 43.350442 -487.191457) (xy 43.350942 -487.227118)
			(xy 43.350442 -487.262779) (xy 43.98441 -487.262779) (xy 43.98441 -487.191457) (xy 43.992396 -487.120583)
			(xy 44.008266 -487.051048) (xy 44.031823 -486.983728) (xy 44.062768 -486.919469) (xy 44.100714 -486.859078)
			(xy 44.145183 -486.803316) (xy 44.195616 -486.752883) (xy 44.251378 -486.708414) (xy 44.311769 -486.670468)
			(xy 44.376028 -486.639523) (xy 44.443348 -486.615966) (xy 44.512883 -486.600096) (xy 44.583757 -486.59211)
			(xy 44.655079 -486.59211) (xy 44.725953 -486.600096) (xy 44.795488 -486.615966) (xy 44.862808 -486.639523)
			(xy 44.927067 -486.670468) (xy 44.987458 -486.708414) (xy 45.04322 -486.752883) (xy 45.093653 -486.803316)
			(xy 45.138122 -486.859078) (xy 45.158387 -486.89133) (xy 69.041264 -486.89133) (xy 69.041264 -485.985058)
			(xy 69.041678 -485.952878) (xy 69.049795 -485.889031) (xy 69.065907 -485.826719) (xy 69.089755 -485.76694)
			(xy 69.120959 -485.710649) (xy 69.159019 -485.658748) (xy 69.203327 -485.612066) (xy 69.253172 -485.571351)
			(xy 69.307759 -485.537254) (xy 69.366213 -485.51032) (xy 69.427599 -485.49098) (xy 69.490936 -485.479544)
			(xy 69.55521 -485.476195) (xy 69.619392 -485.480986) (xy 69.682456 -485.49384) (xy 69.743393 -485.514552)
			(xy 69.801228 -485.542791) (xy 69.855036 -485.578105) (xy 69.903955 -485.619929) (xy 69.925946 -485.643428)
			(xy 69.942164 -485.660507) (xy 69.979713 -485.688928) (xy 70.021853 -485.709952) (xy 70.067142 -485.722861)
			(xy 70.114033 -485.727214) (xy 70.160924 -485.722861) (xy 70.206213 -485.709952) (xy 70.248353 -485.688928)
			(xy 70.285902 -485.660507) (xy 70.30212 -485.643428) (xy 70.324457 -485.619594) (xy 70.374184 -485.577237)
			(xy 70.428928 -485.5416) (xy 70.487786 -485.51327) (xy 70.549788 -485.492713) (xy 70.613913 -485.480267)
			(xy 70.679104 -485.476139) (xy 70.744286 -485.480396) (xy 70.808386 -485.492969) (xy 70.870348 -485.513649)
			(xy 70.92915 -485.542096) (xy 70.983823 -485.577841) (xy 71.033466 -485.620296) (xy 71.055738 -485.64419)
			(xy 71.071968 -485.661371) (xy 71.109587 -485.689975) (xy 71.151842 -485.71114) (xy 71.197278 -485.724137)
			(xy 71.244333 -485.72852) (xy 71.291388 -485.724137) (xy 71.336824 -485.71114) (xy 71.379079 -485.689975)
			(xy 71.416698 -485.661371) (xy 71.432928 -485.64419) (xy 71.455126 -485.620509) (xy 71.50443 -485.578295)
			(xy 71.558705 -485.542699) (xy 71.61707 -485.514301) (xy 71.678574 -485.493563) (xy 71.742217 -485.480821)
			(xy 71.806965 -485.476283) (xy 71.871764 -485.480023) (xy 71.93556 -485.49198) (xy 71.997315 -485.511959)
			(xy 72.056025 -485.539636) (xy 72.110735 -485.57456) (xy 72.160554 -485.616163) (xy 72.18299 -485.639618)
			(xy 72.199189 -485.656337) (xy 72.236509 -485.684156) (xy 72.278269 -485.704718) (xy 72.323073 -485.717336)
			(xy 72.369426 -485.72159) (xy 72.415779 -485.717336) (xy 72.460583 -485.704718) (xy 72.502343 -485.684156)
			(xy 72.539663 -485.656337) (xy 72.555862 -485.639618) (xy 72.578 -485.616456) (xy 72.62711 -485.575304)
			(xy 72.681003 -485.540651) (xy 72.738824 -485.513045) (xy 72.799655 -485.492925) (xy 72.862533 -485.48061)
			(xy 72.92646 -485.476294) (xy 72.990422 -485.480047) (xy 73.053406 -485.491808) (xy 73.114412 -485.511392)
			(xy 73.172474 -485.538487) (xy 73.22667 -485.572665) (xy 73.27614 -485.613383) (xy 73.320102 -485.659995)
			(xy 73.357856 -485.711762) (xy 73.388806 -485.767864) (xy 73.412459 -485.827411) (xy 73.428441 -485.889458)
			(xy 73.436499 -485.953022) (xy 73.436988 -485.985058) (xy 73.436988 -486.805732) (xy 87.38438 -486.805732)
			(xy 87.388451 -486.75011) (xy 87.400577 -486.695673) (xy 87.4205 -486.643582) (xy 87.447796 -486.594947)
			(xy 87.481882 -486.550804) (xy 87.522031 -486.512095) (xy 87.567389 -486.479644) (xy 87.616989 -486.454143)
			(xy 87.669773 -486.436136) (xy 87.724616 -486.426006) (xy 87.78035 -486.423969) (xy 87.835787 -486.430069)
			(xy 87.889744 -486.444175) (xy 87.941073 -486.465987) (xy 87.988679 -486.495041) (xy 88.031547 -486.530716)
			(xy 88.068764 -486.572253) (xy 88.099537 -486.618766) (xy 88.123209 -486.669263) (xy 88.139277 -486.72267)
			(xy 88.147397 -486.777846) (xy 88.147906 -486.805732) (xy 88.147397 -486.833618) (xy 88.139277 -486.888794)
			(xy 88.123209 -486.942201) (xy 88.099537 -486.992698) (xy 88.068764 -487.039211) (xy 88.031547 -487.080748)
			(xy 87.988679 -487.116423) (xy 87.941073 -487.145477) (xy 87.889744 -487.167289) (xy 87.835787 -487.181395)
			(xy 87.78035 -487.187495) (xy 87.724616 -487.185458) (xy 87.669773 -487.175328) (xy 87.616989 -487.157321)
			(xy 87.567389 -487.13182) (xy 87.522031 -487.099369) (xy 87.481882 -487.06066) (xy 87.447796 -487.016517)
			(xy 87.4205 -486.967882) (xy 87.400577 -486.915791) (xy 87.388451 -486.861354) (xy 87.38438 -486.805732)
			(xy 73.436988 -486.805732) (xy 73.436988 -486.89133) (xy 73.436458 -486.924055) (xy 73.428072 -486.988967)
			(xy 73.411429 -487.052266) (xy 73.386804 -487.112907) (xy 73.354604 -487.169889) (xy 73.335388 -487.196384)
			(xy 73.309988 -487.230166) (xy 73.309988 -487.247184) (xy 73.294748 -487.247184) (xy 73.289674 -487.251502)
			(xy 91.911676 -487.251502) (xy 91.915747 -487.19588) (xy 91.927873 -487.141443) (xy 91.947796 -487.089352)
			(xy 91.975092 -487.040717) (xy 92.009178 -486.996574) (xy 92.049327 -486.957865) (xy 92.094685 -486.925414)
			(xy 92.144285 -486.899913) (xy 92.197069 -486.881906) (xy 92.251912 -486.871776) (xy 92.307646 -486.869739)
			(xy 92.363083 -486.875839) (xy 92.41704 -486.889945) (xy 92.468369 -486.911757) (xy 92.515975 -486.940811)
			(xy 92.558843 -486.976486) (xy 92.565839 -486.984294) (xy 95.986344 -486.984294) (xy 95.990415 -486.928672)
			(xy 96.002541 -486.874235) (xy 96.022464 -486.822144) (xy 96.04976 -486.773509) (xy 96.083846 -486.729366)
			(xy 96.123995 -486.690657) (xy 96.169353 -486.658206) (xy 96.218953 -486.632705) (xy 96.271737 -486.614698)
			(xy 96.32658 -486.604568) (xy 96.382314 -486.602531) (xy 96.437751 -486.608631) (xy 96.491708 -486.622737)
			(xy 96.543037 -486.644549) (xy 96.590643 -486.673603) (xy 96.633511 -486.709278) (xy 96.670728 -486.750815)
			(xy 96.701501 -486.797328) (xy 96.725173 -486.847825) (xy 96.741241 -486.901232) (xy 96.749361 -486.956408)
			(xy 96.74987 -486.984294) (xy 96.749361 -487.01218) (xy 96.741241 -487.067356) (xy 96.725173 -487.120763)
			(xy 96.701501 -487.17126) (xy 96.670728 -487.217773) (xy 96.633511 -487.25931) (xy 96.590643 -487.294985)
			(xy 96.543037 -487.324039) (xy 96.491708 -487.345851) (xy 96.437751 -487.359957) (xy 96.382314 -487.366057)
			(xy 96.32658 -487.36402) (xy 96.271737 -487.35389) (xy 96.218953 -487.335883) (xy 96.169353 -487.310382)
			(xy 96.123995 -487.277931) (xy 96.083846 -487.239222) (xy 96.04976 -487.195079) (xy 96.022464 -487.146444)
			(xy 96.002541 -487.094353) (xy 95.990415 -487.039916) (xy 95.986344 -486.984294) (xy 92.565839 -486.984294)
			(xy 92.59606 -487.018023) (xy 92.626833 -487.064536) (xy 92.650505 -487.115033) (xy 92.666573 -487.16844)
			(xy 92.674693 -487.223616) (xy 92.675202 -487.251502) (xy 92.674693 -487.279388) (xy 92.666573 -487.334564)
			(xy 92.650505 -487.387971) (xy 92.626833 -487.438468) (xy 92.59606 -487.484981) (xy 92.593604 -487.487722)
			(xy 94.810832 -487.487722) (xy 94.814903 -487.4321) (xy 94.827029 -487.377663) (xy 94.846952 -487.325572)
			(xy 94.874248 -487.276937) (xy 94.908334 -487.232794) (xy 94.948483 -487.194085) (xy 94.993841 -487.161634)
			(xy 95.043441 -487.136133) (xy 95.096225 -487.118126) (xy 95.151068 -487.107996) (xy 95.206802 -487.105959)
			(xy 95.262239 -487.112059) (xy 95.316196 -487.126165) (xy 95.367525 -487.147977) (xy 95.415131 -487.177031)
			(xy 95.457999 -487.212706) (xy 95.495216 -487.254243) (xy 95.525989 -487.300756) (xy 95.549661 -487.351253)
			(xy 95.565729 -487.40466) (xy 95.573849 -487.459836) (xy 95.574358 -487.487722) (xy 95.573849 -487.515608)
			(xy 95.565729 -487.570784) (xy 95.549661 -487.624191) (xy 95.525989 -487.674688) (xy 95.495216 -487.721201)
			(xy 95.457999 -487.762738) (xy 95.415131 -487.798413) (xy 95.367525 -487.827467) (xy 95.316196 -487.849279)
			(xy 95.262239 -487.863385) (xy 95.206802 -487.869485) (xy 95.151068 -487.867448) (xy 95.096225 -487.857318)
			(xy 95.043441 -487.839311) (xy 94.993841 -487.81381) (xy 94.948483 -487.781359) (xy 94.908334 -487.74265)
			(xy 94.874248 -487.698507) (xy 94.846952 -487.649872) (xy 94.827029 -487.597781) (xy 94.814903 -487.543344)
			(xy 94.810832 -487.487722) (xy 92.593604 -487.487722) (xy 92.558843 -487.526518) (xy 92.515975 -487.562193)
			(xy 92.468369 -487.591247) (xy 92.41704 -487.613059) (xy 92.363083 -487.627165) (xy 92.307646 -487.633265)
			(xy 92.251912 -487.631228) (xy 92.197069 -487.621098) (xy 92.144285 -487.603091) (xy 92.094685 -487.57759)
			(xy 92.049327 -487.545139) (xy 92.009178 -487.50643) (xy 91.975092 -487.462287) (xy 91.947796 -487.413652)
			(xy 91.927873 -487.361561) (xy 91.915747 -487.307124) (xy 91.911676 -487.251502) (xy 73.289674 -487.251502)
			(xy 73.258934 -487.277664) (xy 73.233757 -487.298517) (xy 73.179025 -487.334268) (xy 73.12016 -487.362707)
			(xy 73.058135 -487.383362) (xy 72.993973 -487.395893) (xy 72.928734 -487.400093) (xy 72.863495 -487.395893)
			(xy 72.799333 -487.383362) (xy 72.737308 -487.362707) (xy 72.678443 -487.334268) (xy 72.623711 -487.298517)
			(xy 72.598534 -487.277664) (xy 72.56272 -487.247184) (xy 72.54748 -487.247184) (xy 72.54748 -487.230166)
			(xy 72.52208 -487.196384) (xy 72.510818 -487.181136) (xy 72.49035 -487.149224) (xy 72.481186 -487.13263)
			(xy 72.473583 -487.119453) (xy 72.453227 -487.096859) (xy 72.428095 -487.079733) (xy 72.399621 -487.069051)
			(xy 72.369426 -487.065421) (xy 72.339231 -487.069051) (xy 72.310757 -487.079733) (xy 72.285625 -487.096859)
			(xy 72.265269 -487.119453) (xy 72.257666 -487.13263) (xy 72.248495 -487.14922) (xy 72.228024 -487.181129)
			(xy 72.216772 -487.196384) (xy 72.191372 -487.230166) (xy 72.191372 -487.247184) (xy 72.176132 -487.247184)
			(xy 72.140318 -487.277664) (xy 72.115141 -487.298517) (xy 72.060409 -487.334268) (xy 72.001544 -487.362707)
			(xy 71.939519 -487.383362) (xy 71.875357 -487.395893) (xy 71.810118 -487.400093) (xy 71.744879 -487.395893)
			(xy 71.680717 -487.383362) (xy 71.618692 -487.362707) (xy 71.559827 -487.334268) (xy 71.505095 -487.298517)
			(xy 71.479918 -487.277664) (xy 71.444104 -487.247184) (xy 71.428864 -487.247184) (xy 71.428864 -487.230166)
			(xy 71.403464 -487.196384) (xy 71.390613 -487.178851) (xy 71.367591 -487.141973) (xy 71.35749 -487.122724)
			(xy 71.350052 -487.109063) (xy 71.329678 -487.085573) (xy 71.304221 -487.067717) (xy 71.275196 -487.056559)
			(xy 71.244333 -487.052765) (xy 71.21347 -487.056559) (xy 71.184445 -487.067717) (xy 71.158988 -487.085573)
			(xy 71.138614 -487.109063) (xy 71.131176 -487.122724) (xy 71.121084 -487.141978) (xy 71.098064 -487.178859)
			(xy 71.085202 -487.196384) (xy 71.060056 -487.230166) (xy 71.060056 -487.247184) (xy 71.044562 -487.247184)
			(xy 71.008748 -487.277664) (xy 70.983571 -487.298517) (xy 70.928839 -487.334268) (xy 70.869974 -487.362707)
			(xy 70.807949 -487.383362) (xy 70.743787 -487.395893) (xy 70.678548 -487.400093) (xy 70.613309 -487.395893)
			(xy 70.549147 -487.383362) (xy 70.487122 -487.362707) (xy 70.428257 -487.334268) (xy 70.373525 -487.298517)
			(xy 70.348348 -487.277664) (xy 70.312534 -487.247184) (xy 70.29704 -487.247184) (xy 70.29704 -487.230166)
			(xy 70.271894 -487.196384) (xy 70.259356 -487.179325) (xy 70.236849 -487.143463) (xy 70.226936 -487.124756)
			(xy 70.219473 -487.111181) (xy 70.199099 -487.087855) (xy 70.173699 -487.070133) (xy 70.144774 -487.059063)
			(xy 70.114033 -487.055299) (xy 70.083292 -487.059063) (xy 70.054367 -487.070133) (xy 70.028967 -487.087855)
			(xy 70.008593 -487.111181) (xy 70.00113 -487.124756) (xy 69.99121 -487.143459) (xy 69.968701 -487.179319)
			(xy 69.956172 -487.196384) (xy 69.930772 -487.230166) (xy 69.930772 -487.247184) (xy 69.915532 -487.247184)
			(xy 69.879718 -487.277664) (xy 69.854541 -487.298517) (xy 69.799809 -487.334268) (xy 69.740944 -487.362707)
			(xy 69.678919 -487.383362) (xy 69.614757 -487.395893) (xy 69.549518 -487.400093) (xy 69.484279 -487.395893)
			(xy 69.420117 -487.383362) (xy 69.358092 -487.362707) (xy 69.299227 -487.334268) (xy 69.244495 -487.298517)
			(xy 69.219318 -487.277664) (xy 69.183504 -487.247184) (xy 69.168264 -487.247184) (xy 69.168264 -487.230166)
			(xy 69.142864 -487.196384) (xy 69.123618 -487.169907) (xy 69.091392 -487.112932) (xy 69.066754 -487.052288)
			(xy 69.050115 -486.98898) (xy 69.04175 -486.924059) (xy 69.041264 -486.89133) (xy 45.158387 -486.89133)
			(xy 45.176068 -486.919469) (xy 45.207013 -486.983728) (xy 45.23057 -487.051048) (xy 45.24644 -487.120583)
			(xy 45.254426 -487.191457) (xy 45.254926 -487.227118) (xy 45.254426 -487.262779) (xy 45.24644 -487.333653)
			(xy 45.23057 -487.403188) (xy 45.207013 -487.470508) (xy 45.176068 -487.534767) (xy 45.138122 -487.595158)
			(xy 45.093653 -487.65092) (xy 45.04322 -487.701353) (xy 44.987458 -487.745822) (xy 44.927067 -487.783768)
			(xy 44.862808 -487.814713) (xy 44.795488 -487.83827) (xy 44.725953 -487.85414) (xy 44.655079 -487.862126)
			(xy 44.583757 -487.862126) (xy 44.512883 -487.85414) (xy 44.443348 -487.83827) (xy 44.376028 -487.814713)
			(xy 44.311769 -487.783768) (xy 44.251378 -487.745822) (xy 44.195616 -487.701353) (xy 44.145183 -487.65092)
			(xy 44.100714 -487.595158) (xy 44.062768 -487.534767) (xy 44.031823 -487.470508) (xy 44.008266 -487.403188)
			(xy 43.992396 -487.333653) (xy 43.98441 -487.262779) (xy 43.350442 -487.262779) (xy 43.342456 -487.333653)
			(xy 43.326586 -487.403188) (xy 43.303029 -487.470508) (xy 43.272084 -487.534767) (xy 43.234138 -487.595158)
			(xy 43.189669 -487.65092) (xy 43.139236 -487.701353) (xy 43.083474 -487.745822) (xy 43.023083 -487.783768)
			(xy 42.958824 -487.814713) (xy 42.891504 -487.83827) (xy 42.821969 -487.85414) (xy 42.751095 -487.862126)
			(xy 42.679773 -487.862126) (xy 42.608899 -487.85414) (xy 42.539364 -487.83827) (xy 42.472044 -487.814713)
			(xy 42.407785 -487.783768) (xy 42.347394 -487.745822) (xy 42.291632 -487.701353) (xy 42.241199 -487.65092)
			(xy 42.19673 -487.595158) (xy 42.158784 -487.534767) (xy 42.127839 -487.470508) (xy 42.104282 -487.403188)
			(xy 42.088412 -487.333653) (xy 42.080426 -487.262779) (xy 41.1094 -487.262779) (xy 41.101414 -487.333653)
			(xy 41.085544 -487.403188) (xy 41.061987 -487.470508) (xy 41.031042 -487.534767) (xy 40.993096 -487.595158)
			(xy 40.948627 -487.65092) (xy 40.898194 -487.701353) (xy 40.842432 -487.745822) (xy 40.782041 -487.783768)
			(xy 40.717782 -487.814713) (xy 40.650462 -487.83827) (xy 40.580927 -487.85414) (xy 40.510053 -487.862126)
			(xy 40.438731 -487.862126) (xy 40.367857 -487.85414) (xy 40.298322 -487.83827) (xy 40.231002 -487.814713)
			(xy 40.166743 -487.783768) (xy 40.106352 -487.745822) (xy 40.05059 -487.701353) (xy 40.000157 -487.65092)
			(xy 39.955688 -487.595158) (xy 39.917742 -487.534767) (xy 39.886797 -487.470508) (xy 39.86324 -487.403188)
			(xy 39.84737 -487.333653) (xy 39.839384 -487.262779) (xy 39.222688 -487.262779) (xy 39.214702 -487.333653)
			(xy 39.198832 -487.403188) (xy 39.175275 -487.470508) (xy 39.14433 -487.534767) (xy 39.106384 -487.595158)
			(xy 39.061915 -487.65092) (xy 39.011482 -487.701353) (xy 38.95572 -487.745822) (xy 38.895329 -487.783768)
			(xy 38.83107 -487.814713) (xy 38.76375 -487.83827) (xy 38.694215 -487.85414) (xy 38.623341 -487.862126)
			(xy 38.552019 -487.862126) (xy 38.481145 -487.85414) (xy 38.41161 -487.83827) (xy 38.34429 -487.814713)
			(xy 38.280031 -487.783768) (xy 38.21964 -487.745822) (xy 38.163878 -487.701353) (xy 38.113445 -487.65092)
			(xy 38.068976 -487.595158) (xy 38.03103 -487.534767) (xy 38.000085 -487.470508) (xy 37.976528 -487.403188)
			(xy 37.960658 -487.333653) (xy 37.952672 -487.262779) (xy 36.479608 -487.262779) (xy 36.479486 -487.273362)
			(xy 36.471468 -487.359891) (xy 36.4555 -487.445311) (xy 36.431719 -487.528893) (xy 36.400327 -487.609925)
			(xy 36.361593 -487.687714) (xy 36.315846 -487.761598) (xy 36.263477 -487.830945) (xy 36.204933 -487.895165)
			(xy 36.140713 -487.953709) (xy 36.071366 -488.006078) (xy 35.997482 -488.051825) (xy 35.919693 -488.090559)
			(xy 35.838661 -488.121951) (xy 35.755079 -488.145732) (xy 35.669659 -488.1617) (xy 35.58313 -488.169718)
			(xy 35.49623 -488.169718) (xy 35.409701 -488.1617) (xy 35.324281 -488.145732) (xy 35.240699 -488.121951)
			(xy 35.159667 -488.090559) (xy 35.081878 -488.051825) (xy 35.007994 -488.006078) (xy 34.938647 -487.953709)
			(xy 34.874427 -487.895165) (xy 34.815883 -487.830945) (xy 34.763514 -487.761598) (xy 34.717767 -487.687714)
			(xy 34.679033 -487.609925) (xy 34.647641 -487.528893) (xy 34.62386 -487.445311) (xy 34.607892 -487.359891)
			(xy 34.599874 -487.273362) (xy 31.399486 -487.273362) (xy 31.391468 -487.359891) (xy 31.3755 -487.445311)
			(xy 31.351719 -487.528893) (xy 31.320327 -487.609925) (xy 31.281593 -487.687714) (xy 31.235846 -487.761598)
			(xy 31.183477 -487.830945) (xy 31.124933 -487.895165) (xy 31.060713 -487.953709) (xy 30.991366 -488.006078)
			(xy 30.917482 -488.051825) (xy 30.839693 -488.090559) (xy 30.758661 -488.121951) (xy 30.675079 -488.145732)
			(xy 30.589659 -488.1617) (xy 30.50313 -488.169718) (xy 30.41623 -488.169718) (xy 30.329701 -488.1617)
			(xy 30.244281 -488.145732) (xy 30.160699 -488.121951) (xy 30.079667 -488.090559) (xy 30.001878 -488.051825)
			(xy 29.927994 -488.006078) (xy 29.858647 -487.953709) (xy 29.794427 -487.895165) (xy 29.735883 -487.830945)
			(xy 29.683514 -487.761598) (xy 29.637767 -487.687714) (xy 29.599033 -487.609925) (xy 29.567641 -487.528893)
			(xy 29.54386 -487.445311) (xy 29.527892 -487.359891) (xy 29.519874 -487.273362) (xy 16.49825 -487.273362)
			(xy 16.526001 -487.324442) (xy 16.580682 -487.441972) (xy 16.627952 -487.562675) (xy 16.667625 -487.686083)
			(xy 16.69955 -487.811719) (xy 16.723602 -487.939096) (xy 16.739689 -488.067722) (xy 16.747748 -488.1971)
			(xy 16.748252 -488.261914) (xy 16.748019 -488.291886) (xy 86.063326 -488.291886) (xy 86.067397 -488.236264)
			(xy 86.079523 -488.181827) (xy 86.099446 -488.129736) (xy 86.126742 -488.081101) (xy 86.160828 -488.036958)
			(xy 86.200977 -487.998249) (xy 86.246335 -487.965798) (xy 86.295935 -487.940297) (xy 86.348719 -487.92229)
			(xy 86.403562 -487.91216) (xy 86.459296 -487.910123) (xy 86.514733 -487.916223) (xy 86.56869 -487.930329)
			(xy 86.620019 -487.952141) (xy 86.667625 -487.981195) (xy 86.710493 -488.01687) (xy 86.74771 -488.058407)
			(xy 86.778483 -488.10492) (xy 86.802155 -488.155417) (xy 86.818223 -488.208824) (xy 86.821326 -488.22991)
			(xy 87.927686 -488.22991) (xy 87.931757 -488.174288) (xy 87.943883 -488.119851) (xy 87.963806 -488.06776)
			(xy 87.991102 -488.019125) (xy 88.025188 -487.974982) (xy 88.065337 -487.936273) (xy 88.110695 -487.903822)
			(xy 88.160295 -487.878321) (xy 88.213079 -487.860314) (xy 88.267922 -487.850184) (xy 88.323656 -487.848147)
			(xy 88.365216 -487.85272) (xy 90.630754 -487.85272) (xy 90.634825 -487.797098) (xy 90.646951 -487.742661)
			(xy 90.666874 -487.69057) (xy 90.69417 -487.641935) (xy 90.728256 -487.597792) (xy 90.768405 -487.559083)
			(xy 90.813763 -487.526632) (xy 90.863363 -487.501131) (xy 90.916147 -487.483124) (xy 90.97099 -487.472994)
			(xy 91.026724 -487.470957) (xy 91.082161 -487.477057) (xy 91.136118 -487.491163) (xy 91.187447 -487.512975)
			(xy 91.235053 -487.542029) (xy 91.277921 -487.577704) (xy 91.315138 -487.619241) (xy 91.345911 -487.665754)
			(xy 91.369583 -487.716251) (xy 91.385651 -487.769658) (xy 91.393771 -487.824834) (xy 91.39428 -487.85272)
			(xy 91.393771 -487.880606) (xy 91.385651 -487.935782) (xy 91.369583 -487.989189) (xy 91.345911 -488.039686)
			(xy 91.315138 -488.086199) (xy 91.277921 -488.127736) (xy 91.268075 -488.13593) (xy 93.533974 -488.13593)
			(xy 93.538045 -488.080308) (xy 93.550171 -488.025871) (xy 93.570094 -487.97378) (xy 93.59739 -487.925145)
			(xy 93.631476 -487.881002) (xy 93.671625 -487.842293) (xy 93.716983 -487.809842) (xy 93.766583 -487.784341)
			(xy 93.819367 -487.766334) (xy 93.87421 -487.756204) (xy 93.929944 -487.754167) (xy 93.985381 -487.760267)
			(xy 94.039338 -487.774373) (xy 94.090667 -487.796185) (xy 94.138273 -487.825239) (xy 94.181141 -487.860914)
			(xy 94.218358 -487.902451) (xy 94.249131 -487.948964) (xy 94.272803 -487.999461) (xy 94.288871 -488.052868)
			(xy 94.296991 -488.108044) (xy 94.2975 -488.13593) (xy 94.296991 -488.163816) (xy 94.288871 -488.218992)
			(xy 94.272803 -488.272399) (xy 94.249131 -488.322896) (xy 94.218358 -488.369409) (xy 94.181141 -488.410946)
			(xy 94.138273 -488.446621) (xy 94.090667 -488.475675) (xy 94.039338 -488.497487) (xy 93.985381 -488.511593)
			(xy 93.929944 -488.517693) (xy 93.87421 -488.515656) (xy 93.819367 -488.505526) (xy 93.766583 -488.487519)
			(xy 93.716983 -488.462018) (xy 93.671625 -488.429567) (xy 93.631476 -488.390858) (xy 93.59739 -488.346715)
			(xy 93.570094 -488.29808) (xy 93.550171 -488.245989) (xy 93.538045 -488.191552) (xy 93.533974 -488.13593)
			(xy 91.268075 -488.13593) (xy 91.235053 -488.163411) (xy 91.187447 -488.192465) (xy 91.136118 -488.214277)
			(xy 91.082161 -488.228383) (xy 91.026724 -488.234483) (xy 90.97099 -488.232446) (xy 90.916147 -488.222316)
			(xy 90.863363 -488.204309) (xy 90.813763 -488.178808) (xy 90.768405 -488.146357) (xy 90.728256 -488.107648)
			(xy 90.69417 -488.063505) (xy 90.666874 -488.01487) (xy 90.646951 -487.962779) (xy 90.634825 -487.908342)
			(xy 90.630754 -487.85272) (xy 88.365216 -487.85272) (xy 88.379093 -487.854247) (xy 88.43305 -487.868353)
			(xy 88.484379 -487.890165) (xy 88.531985 -487.919219) (xy 88.574853 -487.954894) (xy 88.61207 -487.996431)
			(xy 88.642843 -488.042944) (xy 88.666515 -488.093441) (xy 88.682583 -488.146848) (xy 88.690703 -488.202024)
			(xy 88.691212 -488.22991) (xy 88.690703 -488.257796) (xy 88.682583 -488.312972) (xy 88.666515 -488.366379)
			(xy 88.642843 -488.416876) (xy 88.61207 -488.463389) (xy 88.574853 -488.504926) (xy 88.531985 -488.540601)
			(xy 88.502516 -488.558586) (xy 91.924376 -488.558586) (xy 91.928447 -488.502964) (xy 91.940573 -488.448527)
			(xy 91.960496 -488.396436) (xy 91.987792 -488.347801) (xy 92.021878 -488.303658) (xy 92.062027 -488.264949)
			(xy 92.107385 -488.232498) (xy 92.156985 -488.206997) (xy 92.209769 -488.18899) (xy 92.264612 -488.17886)
			(xy 92.320346 -488.176823) (xy 92.375783 -488.182923) (xy 92.42974 -488.197029) (xy 92.481069 -488.218841)
			(xy 92.528675 -488.247895) (xy 92.571543 -488.28357) (xy 92.60876 -488.325107) (xy 92.639533 -488.37162)
			(xy 92.663205 -488.422117) (xy 92.679273 -488.475524) (xy 92.687393 -488.5307) (xy 92.687902 -488.558586)
			(xy 92.687393 -488.586472) (xy 92.679273 -488.641648) (xy 92.663205 -488.695055) (xy 92.639533 -488.745552)
			(xy 92.60876 -488.792065) (xy 92.571543 -488.833602) (xy 92.528675 -488.869277) (xy 92.481069 -488.898331)
			(xy 92.42974 -488.920143) (xy 92.375783 -488.934249) (xy 92.320346 -488.940349) (xy 92.264612 -488.938312)
			(xy 92.209769 -488.928182) (xy 92.156985 -488.910175) (xy 92.107385 -488.884674) (xy 92.062027 -488.852223)
			(xy 92.021878 -488.813514) (xy 91.987792 -488.769371) (xy 91.960496 -488.720736) (xy 91.940573 -488.668645)
			(xy 91.928447 -488.614208) (xy 91.924376 -488.558586) (xy 88.502516 -488.558586) (xy 88.484379 -488.569655)
			(xy 88.43305 -488.591467) (xy 88.379093 -488.605573) (xy 88.323656 -488.611673) (xy 88.267922 -488.609636)
			(xy 88.213079 -488.599506) (xy 88.160295 -488.581499) (xy 88.110695 -488.555998) (xy 88.065337 -488.523547)
			(xy 88.025188 -488.484838) (xy 87.991102 -488.440695) (xy 87.963806 -488.39206) (xy 87.943883 -488.339969)
			(xy 87.931757 -488.285532) (xy 87.927686 -488.22991) (xy 86.821326 -488.22991) (xy 86.826343 -488.264)
			(xy 86.826852 -488.291886) (xy 86.826343 -488.319772) (xy 86.818223 -488.374948) (xy 86.802155 -488.428355)
			(xy 86.778483 -488.478852) (xy 86.74771 -488.525365) (xy 86.710493 -488.566902) (xy 86.667625 -488.602577)
			(xy 86.620019 -488.631631) (xy 86.56869 -488.653443) (xy 86.514733 -488.667549) (xy 86.459296 -488.673649)
			(xy 86.403562 -488.671612) (xy 86.348719 -488.661482) (xy 86.295935 -488.643475) (xy 86.246335 -488.617974)
			(xy 86.200977 -488.585523) (xy 86.160828 -488.546814) (xy 86.126742 -488.502671) (xy 86.099446 -488.454036)
			(xy 86.079523 -488.401945) (xy 86.067397 -488.347508) (xy 86.063326 -488.291886) (xy 16.748019 -488.291886)
			(xy 16.747748 -488.326728) (xy 16.739689 -488.456106) (xy 16.723602 -488.584732) (xy 16.69955 -488.712109)
			(xy 16.667625 -488.837745) (xy 16.627952 -488.961153) (xy 16.580682 -489.081856) (xy 16.526001 -489.199386)
			(xy 16.464118 -489.31329) (xy 16.395273 -489.423126) (xy 16.319734 -489.528469) (xy 16.237791 -489.628912)
			(xy 16.149762 -489.724067) (xy 16.056201 -489.813362) (xy 29.519874 -489.813362) (xy 29.519874 -489.726462)
			(xy 29.527892 -489.639933) (xy 29.54386 -489.554513) (xy 29.567641 -489.470931) (xy 29.599033 -489.389899)
			(xy 29.637767 -489.31211) (xy 29.683514 -489.238226) (xy 29.735883 -489.168879) (xy 29.794427 -489.104659)
			(xy 29.858647 -489.046115) (xy 29.927994 -488.993746) (xy 30.001878 -488.947999) (xy 30.079667 -488.909265)
			(xy 30.160699 -488.877873) (xy 30.244281 -488.854092) (xy 30.329701 -488.838124) (xy 30.41623 -488.830106)
			(xy 30.50313 -488.830106) (xy 30.589659 -488.838124) (xy 30.675079 -488.854092) (xy 30.758661 -488.877873)
			(xy 30.839693 -488.909265) (xy 30.917482 -488.947999) (xy 30.991366 -488.993746) (xy 31.060713 -489.046115)
			(xy 31.124933 -489.104659) (xy 31.183477 -489.168879) (xy 31.235846 -489.238226) (xy 31.281593 -489.31211)
			(xy 31.320327 -489.389899) (xy 31.351719 -489.470931) (xy 31.3755 -489.554513) (xy 31.391468 -489.639933)
			(xy 31.399486 -489.726462) (xy 31.399988 -489.769912) (xy 31.399486 -489.813362) (xy 34.599874 -489.813362)
			(xy 34.599874 -489.726462) (xy 34.607892 -489.639933) (xy 34.62386 -489.554513) (xy 34.647641 -489.470931)
			(xy 34.679033 -489.389899) (xy 34.717767 -489.31211) (xy 34.763514 -489.238226) (xy 34.815883 -489.168879)
			(xy 34.874427 -489.104659) (xy 34.938647 -489.046115) (xy 35.007994 -488.993746) (xy 35.081878 -488.947999)
			(xy 35.159667 -488.909265) (xy 35.240699 -488.877873) (xy 35.324281 -488.854092) (xy 35.409701 -488.838124)
			(xy 35.49623 -488.830106) (xy 35.58313 -488.830106) (xy 35.669659 -488.838124) (xy 35.755079 -488.854092)
			(xy 35.838661 -488.877873) (xy 35.919693 -488.909265) (xy 35.997482 -488.947999) (xy 36.071366 -488.993746)
			(xy 36.140713 -489.046115) (xy 36.204933 -489.104659) (xy 36.263477 -489.168879) (xy 36.315846 -489.238226)
			(xy 36.361593 -489.31211) (xy 36.400327 -489.389899) (xy 36.40575 -489.403898) (xy 84.047328 -489.403898)
			(xy 84.051399 -489.348276) (xy 84.063525 -489.293839) (xy 84.083448 -489.241748) (xy 84.110744 -489.193113)
			(xy 84.14483 -489.14897) (xy 84.184979 -489.110261) (xy 84.230337 -489.07781) (xy 84.279937 -489.052309)
			(xy 84.332721 -489.034302) (xy 84.387564 -489.024172) (xy 84.443298 -489.022135) (xy 84.498735 -489.028235)
			(xy 84.552692 -489.042341) (xy 84.604021 -489.064153) (xy 84.651627 -489.093207) (xy 84.694495 -489.128882)
			(xy 84.731712 -489.170419) (xy 84.762485 -489.216932) (xy 84.786157 -489.267429) (xy 84.802225 -489.320836)
			(xy 84.810345 -489.376012) (xy 84.810854 -489.403898) (xy 84.810345 -489.431784) (xy 84.802225 -489.48696)
			(xy 84.786157 -489.540367) (xy 84.762485 -489.590864) (xy 84.745695 -489.616242) (xy 85.548468 -489.616242)
			(xy 85.552539 -489.56062) (xy 85.564665 -489.506183) (xy 85.584588 -489.454092) (xy 85.611884 -489.405457)
			(xy 85.64597 -489.361314) (xy 85.686119 -489.322605) (xy 85.731477 -489.290154) (xy 85.781077 -489.264653)
			(xy 85.833861 -489.246646) (xy 85.888704 -489.236516) (xy 85.944438 -489.234479) (xy 85.999875 -489.240579)
			(xy 86.053832 -489.254685) (xy 86.105161 -489.276497) (xy 86.152767 -489.305551) (xy 86.195635 -489.341226)
			(xy 86.232852 -489.382763) (xy 86.263625 -489.429276) (xy 86.287297 -489.479773) (xy 86.303365 -489.53318)
			(xy 86.311485 -489.588356) (xy 86.311994 -489.616242) (xy 86.311485 -489.644128) (xy 86.303365 -489.699304)
			(xy 86.287297 -489.752711) (xy 86.263625 -489.803208) (xy 86.232852 -489.849721) (xy 86.195635 -489.891258)
			(xy 86.152767 -489.926933) (xy 86.105161 -489.955987) (xy 86.053832 -489.977799) (xy 85.999875 -489.991905)
			(xy 85.944438 -489.998005) (xy 85.888704 -489.995968) (xy 85.833861 -489.985838) (xy 85.781077 -489.967831)
			(xy 85.731477 -489.94233) (xy 85.686119 -489.909879) (xy 85.64597 -489.87117) (xy 85.611884 -489.827027)
			(xy 85.584588 -489.778392) (xy 85.564665 -489.726301) (xy 85.552539 -489.671864) (xy 85.548468 -489.616242)
			(xy 84.745695 -489.616242) (xy 84.731712 -489.637377) (xy 84.694495 -489.678914) (xy 84.651627 -489.714589)
			(xy 84.604021 -489.743643) (xy 84.552692 -489.765455) (xy 84.498735 -489.779561) (xy 84.443298 -489.785661)
			(xy 84.387564 -489.783624) (xy 84.332721 -489.773494) (xy 84.279937 -489.755487) (xy 84.230337 -489.729986)
			(xy 84.184979 -489.697535) (xy 84.14483 -489.658826) (xy 84.110744 -489.614683) (xy 84.083448 -489.566048)
			(xy 84.063525 -489.513957) (xy 84.051399 -489.45952) (xy 84.047328 -489.403898) (xy 36.40575 -489.403898)
			(xy 36.431719 -489.470931) (xy 36.4555 -489.554513) (xy 36.471468 -489.639933) (xy 36.479486 -489.726462)
			(xy 36.479988 -489.769912) (xy 36.479486 -489.813362) (xy 36.471468 -489.899891) (xy 36.4555 -489.985311)
			(xy 36.431719 -490.068893) (xy 36.400327 -490.149925) (xy 36.361593 -490.227714) (xy 36.315846 -490.301598)
			(xy 36.263477 -490.370945) (xy 36.204933 -490.435165) (xy 36.140713 -490.493709) (xy 36.071366 -490.546078)
			(xy 35.997482 -490.591825) (xy 35.919693 -490.630559) (xy 35.838661 -490.661951) (xy 35.755079 -490.685732)
			(xy 35.669659 -490.7017) (xy 35.58313 -490.709718) (xy 35.49623 -490.709718) (xy 35.409701 -490.7017)
			(xy 35.324281 -490.685732) (xy 35.240699 -490.661951) (xy 35.159667 -490.630559) (xy 35.081878 -490.591825)
			(xy 35.007994 -490.546078) (xy 34.938647 -490.493709) (xy 34.874427 -490.435165) (xy 34.815883 -490.370945)
			(xy 34.763514 -490.301598) (xy 34.717767 -490.227714) (xy 34.679033 -490.149925) (xy 34.647641 -490.068893)
			(xy 34.62386 -489.985311) (xy 34.607892 -489.899891) (xy 34.599874 -489.813362) (xy 31.399486 -489.813362)
			(xy 31.391468 -489.899891) (xy 31.3755 -489.985311) (xy 31.351719 -490.068893) (xy 31.320327 -490.149925)
			(xy 31.281593 -490.227714) (xy 31.235846 -490.301598) (xy 31.183477 -490.370945) (xy 31.124933 -490.435165)
			(xy 31.060713 -490.493709) (xy 30.991366 -490.546078) (xy 30.917482 -490.591825) (xy 30.839693 -490.630559)
			(xy 30.758661 -490.661951) (xy 30.675079 -490.685732) (xy 30.589659 -490.7017) (xy 30.50313 -490.709718)
			(xy 30.41623 -490.709718) (xy 30.329701 -490.7017) (xy 30.244281 -490.685732) (xy 30.160699 -490.661951)
			(xy 30.079667 -490.630559) (xy 30.001878 -490.591825) (xy 29.927994 -490.546078) (xy 29.858647 -490.493709)
			(xy 29.794427 -490.435165) (xy 29.735883 -490.370945) (xy 29.683514 -490.301598) (xy 29.637767 -490.227714)
			(xy 29.599033 -490.149925) (xy 29.567641 -490.068893) (xy 29.54386 -489.985311) (xy 29.527892 -489.899891)
			(xy 29.519874 -489.813362) (xy 16.056201 -489.813362) (xy 16.055988 -489.813565) (xy 15.956831 -489.89706)
			(xy 15.852675 -489.974229) (xy 15.743923 -490.044773) (xy 15.630995 -490.10842) (xy 15.51433 -490.164923)
			(xy 15.394377 -490.214064) (xy 15.271601 -490.255652) (xy 15.146477 -490.289527) (xy 15.019489 -490.315557)
			(xy 14.891128 -490.333642) (xy 14.761892 -490.343712) (xy 14.632279 -490.345728) (xy 14.502792 -490.339682)
			(xy 14.373931 -490.325598) (xy 14.246195 -490.303529) (xy 14.120078 -490.273562) (xy 13.996068 -490.235813)
			(xy 13.874645 -490.190426) (xy 13.756278 -490.137579) (xy 13.641426 -490.077475) (xy 13.530533 -490.010347)
			(xy 13.424027 -489.936455) (xy 13.322321 -489.856084) (xy 13.225809 -489.769546) (xy 13.134864 -489.677174)
			(xy 13.049837 -489.579328) (xy 12.971057 -489.476385) (xy 12.89883 -489.368743) (xy 12.833435 -489.256819)
			(xy 12.775124 -489.141046) (xy 12.724124 -489.021872) (xy 12.680632 -488.899758) (xy 12.644815 -488.775175)
			(xy 12.616813 -488.648608) (xy 12.596734 -488.520544) (xy 12.584655 -488.39148) (xy 12.580624 -488.261914)
			(xy 5.31869 -488.261914) (xy 5.314669 -488.391308) (xy 5.302622 -488.520203) (xy 5.282595 -488.648101)
			(xy 5.254666 -488.774509) (xy 5.218942 -488.898939) (xy 5.175561 -489.02091) (xy 5.124691 -489.139953)
			(xy 5.066527 -489.255608) (xy 5.001295 -489.367428) (xy 4.929246 -489.474983) (xy 4.850658 -489.577856)
			(xy 4.765834 -489.675651) (xy 4.675102 -489.767991) (xy 4.578812 -489.85452) (xy 4.477334 -489.934902)
			(xy 4.371062 -490.008829) (xy 4.260405 -490.076016) (xy 4.14579 -490.136201) (xy 4.027658 -490.189155)
			(xy 3.906468 -490.234671) (xy 3.782684 -490.272575) (xy 3.656786 -490.30272) (xy 3.52926 -490.32499)
			(xy 3.400597 -490.339299) (xy 3.271293 -490.345592) (xy 3.141848 -490.343845) (xy 3.012762 -490.334063)
			(xy 2.884532 -490.316286) (xy 2.757653 -490.290581) (xy 2.632615 -490.257048) (xy 2.5099 -490.215816)
			(xy 2.389982 -490.167045) (xy 2.273323 -490.110922) (xy 2.160374 -490.047664) (xy 2.051571 -489.977515)
			(xy 1.947334 -489.900746) (xy 1.848064 -489.817653) (xy 1.754144 -489.728556) (xy 1.709674 -489.68152)
			(xy 1.693349 -489.664804) (xy 1.655769 -489.637051) (xy 1.613749 -489.616634) (xy 1.568705 -489.60424)
			(xy 1.522155 -489.600288) (xy 1.475666 -489.604911) (xy 1.430806 -489.617953) (xy 1.389085 -489.638974)
			(xy 1.351908 -489.667267) (xy 1.320529 -489.701877) (xy 1.296005 -489.74164) (xy 1.279161 -489.785216)
			(xy 1.270565 -489.831136) (xy 1.27 -489.854494) (xy 1.27 -492.353362) (xy 29.519874 -492.353362)
			(xy 29.519874 -492.266462) (xy 29.527892 -492.179933) (xy 29.54386 -492.094513) (xy 29.567641 -492.010931)
			(xy 29.599033 -491.929899) (xy 29.637767 -491.85211) (xy 29.683514 -491.778226) (xy 29.735883 -491.708879)
			(xy 29.794427 -491.644659) (xy 29.858647 -491.586115) (xy 29.927994 -491.533746) (xy 30.001878 -491.487999)
			(xy 30.079667 -491.449265) (xy 30.160699 -491.417873) (xy 30.244281 -491.394092) (xy 30.329701 -491.378124)
			(xy 30.41623 -491.370106) (xy 30.50313 -491.370106) (xy 30.589659 -491.378124) (xy 30.675079 -491.394092)
			(xy 30.758661 -491.417873) (xy 30.839693 -491.449265) (xy 30.917482 -491.487999) (xy 30.991366 -491.533746)
			(xy 31.060713 -491.586115) (xy 31.124933 -491.644659) (xy 31.183477 -491.708879) (xy 31.235846 -491.778226)
			(xy 31.281593 -491.85211) (xy 31.320327 -491.929899) (xy 31.351719 -492.010931) (xy 31.3755 -492.094513)
			(xy 31.391468 -492.179933) (xy 31.399486 -492.266462) (xy 31.399988 -492.309912) (xy 31.399486 -492.353362)
			(xy 34.599874 -492.353362) (xy 34.599874 -492.266462) (xy 34.607892 -492.179933) (xy 34.62386 -492.094513)
			(xy 34.647641 -492.010931) (xy 34.679033 -491.929899) (xy 34.717767 -491.85211) (xy 34.763514 -491.778226)
			(xy 34.815883 -491.708879) (xy 34.874427 -491.644659) (xy 34.938647 -491.586115) (xy 35.007994 -491.533746)
			(xy 35.081878 -491.487999) (xy 35.159667 -491.449265) (xy 35.240699 -491.417873) (xy 35.324281 -491.394092)
			(xy 35.409701 -491.378124) (xy 35.49623 -491.370106) (xy 35.58313 -491.370106) (xy 35.669659 -491.378124)
			(xy 35.755079 -491.394092) (xy 35.838661 -491.417873) (xy 35.919693 -491.449265) (xy 35.997482 -491.487999)
			(xy 36.071366 -491.533746) (xy 36.140713 -491.586115) (xy 36.204933 -491.644659) (xy 36.263477 -491.708879)
			(xy 36.315846 -491.778226) (xy 36.361593 -491.85211) (xy 36.400327 -491.929899) (xy 36.431719 -492.010931)
			(xy 36.4555 -492.094513) (xy 36.471468 -492.179933) (xy 36.479486 -492.266462) (xy 36.479988 -492.309912)
			(xy 36.479486 -492.353362) (xy 36.471468 -492.439891) (xy 36.4555 -492.525311) (xy 36.431719 -492.608893)
			(xy 36.400327 -492.689925) (xy 36.361593 -492.767714) (xy 36.315846 -492.841598) (xy 36.263477 -492.910945)
			(xy 36.204933 -492.975165) (xy 36.140713 -493.033709) (xy 36.071366 -493.086078) (xy 35.997482 -493.131825)
			(xy 35.919693 -493.170559) (xy 35.838661 -493.201951) (xy 35.755079 -493.225732) (xy 35.669659 -493.2417)
			(xy 35.58313 -493.249718) (xy 35.49623 -493.249718) (xy 35.409701 -493.2417) (xy 35.324281 -493.225732)
			(xy 35.240699 -493.201951) (xy 35.159667 -493.170559) (xy 35.081878 -493.131825) (xy 35.007994 -493.086078)
			(xy 34.938647 -493.033709) (xy 34.874427 -492.975165) (xy 34.815883 -492.910945) (xy 34.763514 -492.841598)
			(xy 34.717767 -492.767714) (xy 34.679033 -492.689925) (xy 34.647641 -492.608893) (xy 34.62386 -492.525311)
			(xy 34.607892 -492.439891) (xy 34.599874 -492.353362) (xy 31.399486 -492.353362) (xy 31.391468 -492.439891)
			(xy 31.3755 -492.525311) (xy 31.351719 -492.608893) (xy 31.320327 -492.689925) (xy 31.281593 -492.767714)
			(xy 31.235846 -492.841598) (xy 31.183477 -492.910945) (xy 31.124933 -492.975165) (xy 31.060713 -493.033709)
			(xy 30.991366 -493.086078) (xy 30.917482 -493.131825) (xy 30.839693 -493.170559) (xy 30.758661 -493.201951)
			(xy 30.675079 -493.225732) (xy 30.589659 -493.2417) (xy 30.50313 -493.249718) (xy 30.41623 -493.249718)
			(xy 30.329701 -493.2417) (xy 30.244281 -493.225732) (xy 30.160699 -493.201951) (xy 30.079667 -493.170559)
			(xy 30.001878 -493.131825) (xy 29.927994 -493.086078) (xy 29.858647 -493.033709) (xy 29.794427 -492.975165)
			(xy 29.735883 -492.910945) (xy 29.683514 -492.841598) (xy 29.637767 -492.767714) (xy 29.599033 -492.689925)
			(xy 29.567641 -492.608893) (xy 29.54386 -492.525311) (xy 29.527892 -492.439891) (xy 29.519874 -492.353362)
			(xy 1.27 -492.353362) (xy 1.27 -493.78616) (xy 3.678936 -493.78616) (xy 5.330444 -493.78616) (xy 5.330444 -494.652469)
			(xy 6.21918 -494.652469) (xy 6.21918 -494.571359) (xy 6.22713 -494.49064) (xy 6.242953 -494.411089)
			(xy 6.266498 -494.333473) (xy 6.297537 -494.258537) (xy 6.335772 -494.187005) (xy 6.380834 -494.119565)
			(xy 6.432289 -494.056866) (xy 6.489642 -493.999513) (xy 6.552341 -493.948058) (xy 6.619781 -493.902996)
			(xy 6.691313 -493.864761) (xy 6.766249 -493.833722) (xy 6.843865 -493.810177) (xy 6.923416 -493.794354)
			(xy 7.004135 -493.786404) (xy 7.085245 -493.786404) (xy 7.165964 -493.794354) (xy 7.245515 -493.810177)
			(xy 7.323131 -493.833722) (xy 7.398067 -493.864761) (xy 7.469599 -493.902996) (xy 7.537039 -493.948058)
			(xy 7.599738 -493.999513) (xy 7.657091 -494.056866) (xy 7.708546 -494.119565) (xy 7.753608 -494.187005)
			(xy 7.791843 -494.258537) (xy 7.822882 -494.333473) (xy 7.846427 -494.411089) (xy 7.86225 -494.49064)
			(xy 7.8702 -494.571359) (xy 7.870698 -494.611914) (xy 7.8702 -494.652469) (xy 8.75918 -494.652469)
			(xy 8.75918 -494.571359) (xy 8.76713 -494.49064) (xy 8.782953 -494.411089) (xy 8.806498 -494.333473)
			(xy 8.837537 -494.258537) (xy 8.875772 -494.187005) (xy 8.920834 -494.119565) (xy 8.972289 -494.056866)
			(xy 9.029642 -493.999513) (xy 9.092341 -493.948058) (xy 9.159781 -493.902996) (xy 9.231313 -493.864761)
			(xy 9.306249 -493.833722) (xy 9.383865 -493.810177) (xy 9.463416 -493.794354) (xy 9.544135 -493.786404)
			(xy 9.625245 -493.786404) (xy 9.705964 -493.794354) (xy 9.785515 -493.810177) (xy 9.863131 -493.833722)
			(xy 9.938067 -493.864761) (xy 10.009599 -493.902996) (xy 10.077039 -493.948058) (xy 10.139738 -493.999513)
			(xy 10.197091 -494.056866) (xy 10.248546 -494.119565) (xy 10.293608 -494.187005) (xy 10.331843 -494.258537)
			(xy 10.362882 -494.333473) (xy 10.386427 -494.411089) (xy 10.40225 -494.49064) (xy 10.4102 -494.571359)
			(xy 10.410698 -494.611914) (xy 10.4102 -494.652469) (xy 11.29918 -494.652469) (xy 11.29918 -494.571359)
			(xy 11.30713 -494.49064) (xy 11.322953 -494.411089) (xy 11.346498 -494.333473) (xy 11.377537 -494.258537)
			(xy 11.415772 -494.187005) (xy 11.460834 -494.119565) (xy 11.512289 -494.056866) (xy 11.569642 -493.999513)
			(xy 11.632341 -493.948058) (xy 11.699781 -493.902996) (xy 11.771313 -493.864761) (xy 11.846249 -493.833722)
			(xy 11.923865 -493.810177) (xy 12.003416 -493.794354) (xy 12.084135 -493.786404) (xy 12.165245 -493.786404)
			(xy 12.245964 -493.794354) (xy 12.325515 -493.810177) (xy 12.403131 -493.833722) (xy 12.478067 -493.864761)
			(xy 12.549599 -493.902996) (xy 12.617039 -493.948058) (xy 12.679738 -493.999513) (xy 12.737091 -494.056866)
			(xy 12.788546 -494.119565) (xy 12.833608 -494.187005) (xy 12.871843 -494.258537) (xy 12.902882 -494.333473)
			(xy 12.926427 -494.411089) (xy 12.94225 -494.49064) (xy 12.9502 -494.571359) (xy 12.950698 -494.611914)
			(xy 12.9502 -494.652469) (xy 12.94225 -494.733188) (xy 12.926427 -494.812739) (xy 12.902882 -494.890355)
			(xy 12.901636 -494.893362) (xy 29.519874 -494.893362) (xy 29.519874 -494.806462) (xy 29.527892 -494.719933)
			(xy 29.54386 -494.634513) (xy 29.567641 -494.550931) (xy 29.599033 -494.469899) (xy 29.637767 -494.39211)
			(xy 29.683514 -494.318226) (xy 29.735883 -494.248879) (xy 29.794427 -494.184659) (xy 29.858647 -494.126115)
			(xy 29.927994 -494.073746) (xy 30.001878 -494.027999) (xy 30.079667 -493.989265) (xy 30.160699 -493.957873)
			(xy 30.244281 -493.934092) (xy 30.329701 -493.918124) (xy 30.41623 -493.910106) (xy 30.50313 -493.910106)
			(xy 30.589659 -493.918124) (xy 30.675079 -493.934092) (xy 30.758661 -493.957873) (xy 30.839693 -493.989265)
			(xy 30.917482 -494.027999) (xy 30.991366 -494.073746) (xy 31.060713 -494.126115) (xy 31.124933 -494.184659)
			(xy 31.183477 -494.248879) (xy 31.235846 -494.318226) (xy 31.281593 -494.39211) (xy 31.320327 -494.469899)
			(xy 31.351719 -494.550931) (xy 31.3755 -494.634513) (xy 31.391468 -494.719933) (xy 31.399486 -494.806462)
			(xy 31.399988 -494.849912) (xy 31.399486 -494.893362) (xy 34.599874 -494.893362) (xy 34.599874 -494.806462)
			(xy 34.607892 -494.719933) (xy 34.62386 -494.634513) (xy 34.647641 -494.550931) (xy 34.679033 -494.469899)
			(xy 34.717767 -494.39211) (xy 34.763514 -494.318226) (xy 34.815883 -494.248879) (xy 34.874427 -494.184659)
			(xy 34.938647 -494.126115) (xy 35.007994 -494.073746) (xy 35.081878 -494.027999) (xy 35.159667 -493.989265)
			(xy 35.240699 -493.957873) (xy 35.324281 -493.934092) (xy 35.409701 -493.918124) (xy 35.49623 -493.910106)
			(xy 35.58313 -493.910106) (xy 35.669659 -493.918124) (xy 35.755079 -493.934092) (xy 35.838661 -493.957873)
			(xy 35.919693 -493.989265) (xy 35.997482 -494.027999) (xy 36.071366 -494.073746) (xy 36.140713 -494.126115)
			(xy 36.204933 -494.184659) (xy 36.263477 -494.248879) (xy 36.315846 -494.318226) (xy 36.361593 -494.39211)
			(xy 36.400327 -494.469899) (xy 36.431719 -494.550931) (xy 36.4555 -494.634513) (xy 36.471468 -494.719933)
			(xy 36.479486 -494.806462) (xy 36.479988 -494.849912) (xy 36.479486 -494.893362) (xy 36.471468 -494.979891)
			(xy 36.4555 -495.065311) (xy 36.431719 -495.148893) (xy 36.400327 -495.229925) (xy 36.361593 -495.307714)
			(xy 36.315846 -495.381598) (xy 36.263477 -495.450945) (xy 36.204933 -495.515165) (xy 36.140713 -495.573709)
			(xy 36.071366 -495.626078) (xy 35.997482 -495.671825) (xy 35.919693 -495.710559) (xy 35.838661 -495.741951)
			(xy 35.755079 -495.765732) (xy 35.669659 -495.7817) (xy 35.58313 -495.789718) (xy 35.49623 -495.789718)
			(xy 35.409701 -495.7817) (xy 35.324281 -495.765732) (xy 35.240699 -495.741951) (xy 35.159667 -495.710559)
			(xy 35.081878 -495.671825) (xy 35.007994 -495.626078) (xy 34.938647 -495.573709) (xy 34.874427 -495.515165)
			(xy 34.815883 -495.450945) (xy 34.763514 -495.381598) (xy 34.717767 -495.307714) (xy 34.679033 -495.229925)
			(xy 34.647641 -495.148893) (xy 34.62386 -495.065311) (xy 34.607892 -494.979891) (xy 34.599874 -494.893362)
			(xy 31.399486 -494.893362) (xy 31.391468 -494.979891) (xy 31.3755 -495.065311) (xy 31.351719 -495.148893)
			(xy 31.320327 -495.229925) (xy 31.281593 -495.307714) (xy 31.235846 -495.381598) (xy 31.183477 -495.450945)
			(xy 31.124933 -495.515165) (xy 31.060713 -495.573709) (xy 30.991366 -495.626078) (xy 30.917482 -495.671825)
			(xy 30.839693 -495.710559) (xy 30.758661 -495.741951) (xy 30.675079 -495.765732) (xy 30.589659 -495.7817)
			(xy 30.50313 -495.789718) (xy 30.41623 -495.789718) (xy 30.329701 -495.7817) (xy 30.244281 -495.765732)
			(xy 30.160699 -495.741951) (xy 30.079667 -495.710559) (xy 30.001878 -495.671825) (xy 29.927994 -495.626078)
			(xy 29.858647 -495.573709) (xy 29.794427 -495.515165) (xy 29.735883 -495.450945) (xy 29.683514 -495.381598)
			(xy 29.637767 -495.307714) (xy 29.599033 -495.229925) (xy 29.567641 -495.148893) (xy 29.54386 -495.065311)
			(xy 29.527892 -494.979891) (xy 29.519874 -494.893362) (xy 12.901636 -494.893362) (xy 12.871843 -494.965291)
			(xy 12.833608 -495.036823) (xy 12.788546 -495.104263) (xy 12.737091 -495.166962) (xy 12.679738 -495.224315)
			(xy 12.617039 -495.27577) (xy 12.549599 -495.320832) (xy 12.478067 -495.359067) (xy 12.403131 -495.390106)
			(xy 12.325515 -495.413651) (xy 12.245964 -495.429474) (xy 12.165245 -495.437424) (xy 12.084135 -495.437424)
			(xy 12.003416 -495.429474) (xy 11.923865 -495.413651) (xy 11.846249 -495.390106) (xy 11.771313 -495.359067)
			(xy 11.699781 -495.320832) (xy 11.632341 -495.27577) (xy 11.569642 -495.224315) (xy 11.512289 -495.166962)
			(xy 11.460834 -495.104263) (xy 11.415772 -495.036823) (xy 11.377537 -494.965291) (xy 11.346498 -494.890355)
			(xy 11.322953 -494.812739) (xy 11.30713 -494.733188) (xy 11.29918 -494.652469) (xy 10.4102 -494.652469)
			(xy 10.40225 -494.733188) (xy 10.386427 -494.812739) (xy 10.362882 -494.890355) (xy 10.331843 -494.965291)
			(xy 10.293608 -495.036823) (xy 10.248546 -495.104263) (xy 10.197091 -495.166962) (xy 10.139738 -495.224315)
			(xy 10.077039 -495.27577) (xy 10.009599 -495.320832) (xy 9.938067 -495.359067) (xy 9.863131 -495.390106)
			(xy 9.785515 -495.413651) (xy 9.705964 -495.429474) (xy 9.625245 -495.437424) (xy 9.544135 -495.437424)
			(xy 9.463416 -495.429474) (xy 9.383865 -495.413651) (xy 9.306249 -495.390106) (xy 9.231313 -495.359067)
			(xy 9.159781 -495.320832) (xy 9.092341 -495.27577) (xy 9.029642 -495.224315) (xy 8.972289 -495.166962)
			(xy 8.920834 -495.104263) (xy 8.875772 -495.036823) (xy 8.837537 -494.965291) (xy 8.806498 -494.890355)
			(xy 8.782953 -494.812739) (xy 8.76713 -494.733188) (xy 8.75918 -494.652469) (xy 7.8702 -494.652469)
			(xy 7.86225 -494.733188) (xy 7.846427 -494.812739) (xy 7.822882 -494.890355) (xy 7.791843 -494.965291)
			(xy 7.753608 -495.036823) (xy 7.708546 -495.104263) (xy 7.657091 -495.166962) (xy 7.599738 -495.224315)
			(xy 7.537039 -495.27577) (xy 7.469599 -495.320832) (xy 7.398067 -495.359067) (xy 7.323131 -495.390106)
			(xy 7.245515 -495.413651) (xy 7.165964 -495.429474) (xy 7.085245 -495.437424) (xy 7.004135 -495.437424)
			(xy 6.923416 -495.429474) (xy 6.843865 -495.413651) (xy 6.766249 -495.390106) (xy 6.691313 -495.359067)
			(xy 6.619781 -495.320832) (xy 6.552341 -495.27577) (xy 6.489642 -495.224315) (xy 6.432289 -495.166962)
			(xy 6.380834 -495.104263) (xy 6.335772 -495.036823) (xy 6.297537 -494.965291) (xy 6.266498 -494.890355)
			(xy 6.242953 -494.812739) (xy 6.22713 -494.733188) (xy 6.21918 -494.652469) (xy 5.330444 -494.652469)
			(xy 5.330444 -495.437668) (xy 3.678936 -495.437668) (xy 3.678936 -493.78616) (xy 1.27 -493.78616)
			(xy 1.27 -495.86007) (xy 39.818063 -495.86007) (xy 39.82207 -495.744046) (xy 39.834072 -495.628574)
			(xy 39.854012 -495.514206) (xy 39.881795 -495.401486) (xy 39.917289 -495.290952) (xy 39.960324 -495.183129)
			(xy 40.010695 -495.078532) (xy 40.068162 -494.97766) (xy 40.132452 -494.880993) (xy 40.203257 -494.788992)
			(xy 40.280241 -494.702095) (xy 40.363037 -494.620716) (xy 40.45125 -494.545243) (xy 40.54446 -494.476036)
			(xy 40.642223 -494.413424) (xy 40.744072 -494.357707) (xy 40.849522 -494.309149) (xy 40.958071 -494.267981)
			(xy 41.069202 -494.234401) (xy 41.182385 -494.208568) (xy 41.29708 -494.190605) (xy 41.412742 -494.180597)
			(xy 41.528818 -494.178594) (xy 41.644756 -494.184603) (xy 41.760003 -494.198596) (xy 41.874009 -494.220507)
			(xy 41.986233 -494.250232) (xy 42.096139 -494.287628) (xy 42.203202 -494.332517) (xy 42.306914 -494.384686)
			(xy 42.406779 -494.443886) (xy 42.502322 -494.509835) (xy 42.502604 -494.51006) (xy 43.327577 -494.51006)
			(xy 43.331612 -494.434356) (xy 43.343671 -494.359511) (xy 43.363617 -494.28637) (xy 43.391224 -494.215765)
			(xy 43.42618 -494.148494) (xy 43.468088 -494.085319) (xy 43.516474 -494.026957) (xy 43.57079 -493.974069)
			(xy 43.630419 -493.927254) (xy 43.694687 -493.887042) (xy 43.762864 -493.85389) (xy 43.83418 -493.828172)
			(xy 43.907825 -493.81018) (xy 43.982965 -493.800118) (xy 44.058749 -493.798099) (xy 44.134319 -493.804148)
			(xy 44.208817 -493.818195) (xy 44.2814 -493.840081) (xy 44.351246 -493.869558) (xy 44.417563 -493.906293)
			(xy 44.479599 -493.949868) (xy 44.536652 -493.99979) (xy 44.588076 -494.055494) (xy 44.633287 -494.116349)
			(xy 44.671774 -494.181664) (xy 44.7031 -494.2507) (xy 44.72691 -494.322675) (xy 44.742935 -494.396773)
			(xy 44.750994 -494.472154) (xy 44.751498 -494.51006) (xy 45.867577 -494.51006) (xy 45.871612 -494.434356)
			(xy 45.883671 -494.359511) (xy 45.903617 -494.28637) (xy 45.931224 -494.215765) (xy 45.96618 -494.148494)
			(xy 46.008088 -494.085319) (xy 46.056474 -494.026957) (xy 46.11079 -493.974069) (xy 46.170419 -493.927254)
			(xy 46.234687 -493.887042) (xy 46.302864 -493.85389) (xy 46.37418 -493.828172) (xy 46.447825 -493.81018)
			(xy 46.522965 -493.800118) (xy 46.598749 -493.798099) (xy 46.674319 -493.804148) (xy 46.748817 -493.818195)
			(xy 46.8214 -493.840081) (xy 46.891246 -493.869558) (xy 46.957563 -493.906293) (xy 47.019599 -493.949868)
			(xy 47.076652 -493.99979) (xy 47.128076 -494.055494) (xy 47.173287 -494.116349) (xy 47.211774 -494.181664)
			(xy 47.2431 -494.2507) (xy 47.26691 -494.322675) (xy 47.282935 -494.396773) (xy 47.290994 -494.472154)
			(xy 47.291498 -494.51006) (xy 48.407577 -494.51006) (xy 48.411612 -494.434356) (xy 48.423671 -494.359511)
			(xy 48.443617 -494.28637) (xy 48.471224 -494.215765) (xy 48.50618 -494.148494) (xy 48.548088 -494.085319)
			(xy 48.596474 -494.026957) (xy 48.65079 -493.974069) (xy 48.710419 -493.927254) (xy 48.774687 -493.887042)
			(xy 48.842864 -493.85389) (xy 48.91418 -493.828172) (xy 48.987825 -493.81018) (xy 49.062965 -493.800118)
			(xy 49.138749 -493.798099) (xy 49.214319 -493.804148) (xy 49.288817 -493.818195) (xy 49.3614 -493.840081)
			(xy 49.431246 -493.869558) (xy 49.497563 -493.906293) (xy 49.559599 -493.949868) (xy 49.616652 -493.99979)
			(xy 49.668076 -494.055494) (xy 49.713287 -494.116349) (xy 49.751774 -494.181664) (xy 49.7831 -494.2507)
			(xy 49.80691 -494.322675) (xy 49.822935 -494.396773) (xy 49.830994 -494.472154) (xy 49.831498 -494.51006)
			(xy 50.947577 -494.51006) (xy 50.951612 -494.434356) (xy 50.963671 -494.359511) (xy 50.983617 -494.28637)
			(xy 51.011224 -494.215765) (xy 51.04618 -494.148494) (xy 51.088088 -494.085319) (xy 51.136474 -494.026957)
			(xy 51.19079 -493.974069) (xy 51.250419 -493.927254) (xy 51.314687 -493.887042) (xy 51.382864 -493.85389)
			(xy 51.45418 -493.828172) (xy 51.527825 -493.81018) (xy 51.602965 -493.800118) (xy 51.678749 -493.798099)
			(xy 51.754319 -493.804148) (xy 51.828817 -493.818195) (xy 51.9014 -493.840081) (xy 51.971246 -493.869558)
			(xy 52.037563 -493.906293) (xy 52.099599 -493.949868) (xy 52.156652 -493.99979) (xy 52.208076 -494.055494)
			(xy 52.253287 -494.116349) (xy 52.291774 -494.181664) (xy 52.3231 -494.2507) (xy 52.34691 -494.322675)
			(xy 52.362935 -494.396773) (xy 52.370994 -494.472154) (xy 52.371498 -494.51006) (xy 53.487577 -494.51006)
			(xy 53.491612 -494.434356) (xy 53.503671 -494.359511) (xy 53.523617 -494.28637) (xy 53.551224 -494.215765)
			(xy 53.58618 -494.148494) (xy 53.628088 -494.085319) (xy 53.676474 -494.026957) (xy 53.73079 -493.974069)
			(xy 53.790419 -493.927254) (xy 53.854687 -493.887042) (xy 53.922864 -493.85389) (xy 53.99418 -493.828172)
			(xy 54.067825 -493.81018) (xy 54.142965 -493.800118) (xy 54.218749 -493.798099) (xy 54.294319 -493.804148)
			(xy 54.368817 -493.818195) (xy 54.4414 -493.840081) (xy 54.511246 -493.869558) (xy 54.577563 -493.906293)
			(xy 54.639599 -493.949868) (xy 54.696652 -493.99979) (xy 54.748076 -494.055494) (xy 54.793287 -494.116349)
			(xy 54.831774 -494.181664) (xy 54.8631 -494.2507) (xy 54.88691 -494.322675) (xy 54.902935 -494.396773)
			(xy 54.910994 -494.472154) (xy 54.911498 -494.51006) (xy 56.027577 -494.51006) (xy 56.031612 -494.434356)
			(xy 56.043671 -494.359511) (xy 56.063617 -494.28637) (xy 56.091224 -494.215765) (xy 56.12618 -494.148494)
			(xy 56.168088 -494.085319) (xy 56.216474 -494.026957) (xy 56.27079 -493.974069) (xy 56.330419 -493.927254)
			(xy 56.394687 -493.887042) (xy 56.462864 -493.85389) (xy 56.53418 -493.828172) (xy 56.607825 -493.81018)
			(xy 56.682965 -493.800118) (xy 56.758749 -493.798099) (xy 56.834319 -493.804148) (xy 56.908817 -493.818195)
			(xy 56.9814 -493.840081) (xy 57.051246 -493.869558) (xy 57.117563 -493.906293) (xy 57.179599 -493.949868)
			(xy 57.236652 -493.99979) (xy 57.288076 -494.055494) (xy 57.333287 -494.116349) (xy 57.371774 -494.181664)
			(xy 57.4031 -494.2507) (xy 57.42691 -494.322675) (xy 57.442935 -494.396773) (xy 57.450994 -494.472154)
			(xy 57.451498 -494.51006) (xy 58.567577 -494.51006) (xy 58.571612 -494.434356) (xy 58.583671 -494.359511)
			(xy 58.603617 -494.28637) (xy 58.631224 -494.215765) (xy 58.66618 -494.148494) (xy 58.708088 -494.085319)
			(xy 58.756474 -494.026957) (xy 58.81079 -493.974069) (xy 58.870419 -493.927254) (xy 58.934687 -493.887042)
			(xy 59.002864 -493.85389) (xy 59.07418 -493.828172) (xy 59.147825 -493.81018) (xy 59.222965 -493.800118)
			(xy 59.298749 -493.798099) (xy 59.374319 -493.804148) (xy 59.448817 -493.818195) (xy 59.5214 -493.840081)
			(xy 59.591246 -493.869558) (xy 59.657563 -493.906293) (xy 59.719599 -493.949868) (xy 59.776652 -493.99979)
			(xy 59.828076 -494.055494) (xy 59.873287 -494.116349) (xy 59.911774 -494.181664) (xy 59.9431 -494.2507)
			(xy 59.96691 -494.322675) (xy 59.982935 -494.396773) (xy 59.990994 -494.472154) (xy 59.991498 -494.51006)
			(xy 61.107577 -494.51006) (xy 61.111612 -494.434356) (xy 61.123671 -494.359511) (xy 61.143617 -494.28637)
			(xy 61.171224 -494.215765) (xy 61.20618 -494.148494) (xy 61.248088 -494.085319) (xy 61.296474 -494.026957)
			(xy 61.35079 -493.974069) (xy 61.410419 -493.927254) (xy 61.474687 -493.887042) (xy 61.542864 -493.85389)
			(xy 61.61418 -493.828172) (xy 61.687825 -493.81018) (xy 61.762965 -493.800118) (xy 61.838749 -493.798099)
			(xy 61.914319 -493.804148) (xy 61.988817 -493.818195) (xy 62.0614 -493.840081) (xy 62.131246 -493.869558)
			(xy 62.197563 -493.906293) (xy 62.259599 -493.949868) (xy 62.265544 -493.95507) (xy 86.197697 -493.95507)
			(xy 86.201732 -493.879366) (xy 86.213791 -493.804521) (xy 86.233737 -493.73138) (xy 86.261344 -493.660775)
			(xy 86.2963 -493.593504) (xy 86.338208 -493.530329) (xy 86.386594 -493.471967) (xy 86.44091 -493.419079)
			(xy 86.500539 -493.372264) (xy 86.564807 -493.332052) (xy 86.632984 -493.2989) (xy 86.7043 -493.273182)
			(xy 86.777945 -493.25519) (xy 86.853085 -493.245128) (xy 86.928869 -493.243109) (xy 87.004439 -493.249158)
			(xy 87.078937 -493.263205) (xy 87.15152 -493.285091) (xy 87.221366 -493.314568) (xy 87.287683 -493.351303)
			(xy 87.349719 -493.394878) (xy 87.406772 -493.4448) (xy 87.458196 -493.500504) (xy 87.503407 -493.561359)
			(xy 87.541894 -493.626674) (xy 87.57322 -493.69571) (xy 87.59703 -493.767685) (xy 87.613055 -493.841783)
			(xy 87.621114 -493.917164) (xy 87.621618 -493.95507) (xy 88.737697 -493.95507) (xy 88.741732 -493.879366)
			(xy 88.753791 -493.804521) (xy 88.773737 -493.73138) (xy 88.801344 -493.660775) (xy 88.8363 -493.593504)
			(xy 88.878208 -493.530329) (xy 88.926594 -493.471967) (xy 88.98091 -493.419079) (xy 89.040539 -493.372264)
			(xy 89.104807 -493.332052) (xy 89.172984 -493.2989) (xy 89.2443 -493.273182) (xy 89.317945 -493.25519)
			(xy 89.393085 -493.245128) (xy 89.468869 -493.243109) (xy 89.544439 -493.249158) (xy 89.618937 -493.263205)
			(xy 89.69152 -493.285091) (xy 89.761366 -493.314568) (xy 89.827683 -493.351303) (xy 89.889719 -493.394878)
			(xy 89.946772 -493.4448) (xy 89.998196 -493.500504) (xy 90.043407 -493.561359) (xy 90.081894 -493.626674)
			(xy 90.11322 -493.69571) (xy 90.13703 -493.767685) (xy 90.153055 -493.841783) (xy 90.161114 -493.917164)
			(xy 90.161618 -493.95507) (xy 91.277697 -493.95507) (xy 91.281732 -493.879366) (xy 91.293791 -493.804521)
			(xy 91.313737 -493.73138) (xy 91.341344 -493.660775) (xy 91.3763 -493.593504) (xy 91.418208 -493.530329)
			(xy 91.466594 -493.471967) (xy 91.52091 -493.419079) (xy 91.580539 -493.372264) (xy 91.644807 -493.332052)
			(xy 91.712984 -493.2989) (xy 91.7843 -493.273182) (xy 91.857945 -493.25519) (xy 91.933085 -493.245128)
			(xy 92.008869 -493.243109) (xy 92.084439 -493.249158) (xy 92.158937 -493.263205) (xy 92.23152 -493.285091)
			(xy 92.301366 -493.314568) (xy 92.367683 -493.351303) (xy 92.429719 -493.394878) (xy 92.486772 -493.4448)
			(xy 92.538196 -493.500504) (xy 92.583407 -493.561359) (xy 92.621894 -493.626674) (xy 92.65322 -493.69571)
			(xy 92.67703 -493.767685) (xy 92.693055 -493.841783) (xy 92.701114 -493.917164) (xy 92.701618 -493.95507)
			(xy 92.701114 -493.992976) (xy 92.693055 -494.068357) (xy 92.67703 -494.142455) (xy 92.65322 -494.21443)
			(xy 92.621894 -494.283466) (xy 92.583407 -494.348781) (xy 92.538196 -494.409636) (xy 92.486772 -494.46534)
			(xy 92.429719 -494.515262) (xy 92.367683 -494.558837) (xy 92.301366 -494.595572) (xy 92.23152 -494.625049)
			(xy 92.158937 -494.646935) (xy 92.084439 -494.660982) (xy 92.008869 -494.667031) (xy 91.933085 -494.665012)
			(xy 91.857945 -494.65495) (xy 91.7843 -494.636958) (xy 91.712984 -494.61124) (xy 91.644807 -494.578088)
			(xy 91.580539 -494.537876) (xy 91.52091 -494.491061) (xy 91.466594 -494.438173) (xy 91.418208 -494.379811)
			(xy 91.3763 -494.316636) (xy 91.341344 -494.249365) (xy 91.313737 -494.17876) (xy 91.293791 -494.105619)
			(xy 91.281732 -494.030774) (xy 91.277697 -493.95507) (xy 90.161618 -493.95507) (xy 90.161114 -493.992976)
			(xy 90.153055 -494.068357) (xy 90.13703 -494.142455) (xy 90.11322 -494.21443) (xy 90.081894 -494.283466)
			(xy 90.043407 -494.348781) (xy 89.998196 -494.409636) (xy 89.946772 -494.46534) (xy 89.889719 -494.515262)
			(xy 89.827683 -494.558837) (xy 89.761366 -494.595572) (xy 89.69152 -494.625049) (xy 89.618937 -494.646935)
			(xy 89.544439 -494.660982) (xy 89.468869 -494.667031) (xy 89.393085 -494.665012) (xy 89.317945 -494.65495)
			(xy 89.2443 -494.636958) (xy 89.172984 -494.61124) (xy 89.104807 -494.578088) (xy 89.040539 -494.537876)
			(xy 88.98091 -494.491061) (xy 88.926594 -494.438173) (xy 88.878208 -494.379811) (xy 88.8363 -494.316636)
			(xy 88.801344 -494.249365) (xy 88.773737 -494.17876) (xy 88.753791 -494.105619) (xy 88.741732 -494.030774)
			(xy 88.737697 -493.95507) (xy 87.621618 -493.95507) (xy 87.621114 -493.992976) (xy 87.613055 -494.068357)
			(xy 87.59703 -494.142455) (xy 87.57322 -494.21443) (xy 87.541894 -494.283466) (xy 87.503407 -494.348781)
			(xy 87.458196 -494.409636) (xy 87.406772 -494.46534) (xy 87.349719 -494.515262) (xy 87.287683 -494.558837)
			(xy 87.221366 -494.595572) (xy 87.15152 -494.625049) (xy 87.078937 -494.646935) (xy 87.004439 -494.660982)
			(xy 86.928869 -494.667031) (xy 86.853085 -494.665012) (xy 86.777945 -494.65495) (xy 86.7043 -494.636958)
			(xy 86.632984 -494.61124) (xy 86.564807 -494.578088) (xy 86.500539 -494.537876) (xy 86.44091 -494.491061)
			(xy 86.386594 -494.438173) (xy 86.338208 -494.379811) (xy 86.2963 -494.316636) (xy 86.261344 -494.249365)
			(xy 86.233737 -494.17876) (xy 86.213791 -494.105619) (xy 86.201732 -494.030774) (xy 86.197697 -493.95507)
			(xy 62.265544 -493.95507) (xy 62.316652 -493.99979) (xy 62.368076 -494.055494) (xy 62.413287 -494.116349)
			(xy 62.451774 -494.181664) (xy 62.4831 -494.2507) (xy 62.50691 -494.322675) (xy 62.522935 -494.396773)
			(xy 62.530994 -494.472154) (xy 62.531498 -494.51006) (xy 62.530994 -494.547966) (xy 62.522935 -494.623347)
			(xy 62.50691 -494.697445) (xy 62.4831 -494.76942) (xy 62.451774 -494.838456) (xy 62.413287 -494.903771)
			(xy 62.368076 -494.964626) (xy 62.316652 -495.02033) (xy 62.259599 -495.070252) (xy 62.197563 -495.113827)
			(xy 62.131246 -495.150562) (xy 62.0614 -495.180039) (xy 61.988817 -495.201925) (xy 61.914319 -495.215972)
			(xy 61.838749 -495.222021) (xy 61.762965 -495.220002) (xy 61.687825 -495.20994) (xy 61.61418 -495.191948)
			(xy 61.542864 -495.16623) (xy 61.474687 -495.133078) (xy 61.410419 -495.092866) (xy 61.35079 -495.046051)
			(xy 61.296474 -494.993163) (xy 61.248088 -494.934801) (xy 61.20618 -494.871626) (xy 61.171224 -494.804355)
			(xy 61.143617 -494.73375) (xy 61.123671 -494.660609) (xy 61.111612 -494.585764) (xy 61.107577 -494.51006)
			(xy 59.991498 -494.51006) (xy 59.990994 -494.547966) (xy 59.982935 -494.623347) (xy 59.96691 -494.697445)
			(xy 59.9431 -494.76942) (xy 59.911774 -494.838456) (xy 59.873287 -494.903771) (xy 59.828076 -494.964626)
			(xy 59.776652 -495.02033) (xy 59.719599 -495.070252) (xy 59.657563 -495.113827) (xy 59.591246 -495.150562)
			(xy 59.5214 -495.180039) (xy 59.448817 -495.201925) (xy 59.374319 -495.215972) (xy 59.298749 -495.222021)
			(xy 59.222965 -495.220002) (xy 59.147825 -495.20994) (xy 59.07418 -495.191948) (xy 59.002864 -495.16623)
			(xy 58.934687 -495.133078) (xy 58.870419 -495.092866) (xy 58.81079 -495.046051) (xy 58.756474 -494.993163)
			(xy 58.708088 -494.934801) (xy 58.66618 -494.871626) (xy 58.631224 -494.804355) (xy 58.603617 -494.73375)
			(xy 58.583671 -494.660609) (xy 58.571612 -494.585764) (xy 58.567577 -494.51006) (xy 57.451498 -494.51006)
			(xy 57.450994 -494.547966) (xy 57.442935 -494.623347) (xy 57.42691 -494.697445) (xy 57.4031 -494.76942)
			(xy 57.371774 -494.838456) (xy 57.333287 -494.903771) (xy 57.288076 -494.964626) (xy 57.236652 -495.02033)
			(xy 57.179599 -495.070252) (xy 57.117563 -495.113827) (xy 57.051246 -495.150562) (xy 56.9814 -495.180039)
			(xy 56.908817 -495.201925) (xy 56.834319 -495.215972) (xy 56.758749 -495.222021) (xy 56.682965 -495.220002)
			(xy 56.607825 -495.20994) (xy 56.53418 -495.191948) (xy 56.462864 -495.16623) (xy 56.394687 -495.133078)
			(xy 56.330419 -495.092866) (xy 56.27079 -495.046051) (xy 56.216474 -494.993163) (xy 56.168088 -494.934801)
			(xy 56.12618 -494.871626) (xy 56.091224 -494.804355) (xy 56.063617 -494.73375) (xy 56.043671 -494.660609)
			(xy 56.031612 -494.585764) (xy 56.027577 -494.51006) (xy 54.911498 -494.51006) (xy 54.910994 -494.547966)
			(xy 54.902935 -494.623347) (xy 54.88691 -494.697445) (xy 54.8631 -494.76942) (xy 54.831774 -494.838456)
			(xy 54.793287 -494.903771) (xy 54.748076 -494.964626) (xy 54.696652 -495.02033) (xy 54.639599 -495.070252)
			(xy 54.577563 -495.113827) (xy 54.511246 -495.150562) (xy 54.4414 -495.180039) (xy 54.368817 -495.201925)
			(xy 54.294319 -495.215972) (xy 54.218749 -495.222021) (xy 54.142965 -495.220002) (xy 54.067825 -495.20994)
			(xy 53.99418 -495.191948) (xy 53.922864 -495.16623) (xy 53.854687 -495.133078) (xy 53.790419 -495.092866)
			(xy 53.73079 -495.046051) (xy 53.676474 -494.993163) (xy 53.628088 -494.934801) (xy 53.58618 -494.871626)
			(xy 53.551224 -494.804355) (xy 53.523617 -494.73375) (xy 53.503671 -494.660609) (xy 53.491612 -494.585764)
			(xy 53.487577 -494.51006) (xy 52.371498 -494.51006) (xy 52.370994 -494.547966) (xy 52.362935 -494.623347)
			(xy 52.34691 -494.697445) (xy 52.3231 -494.76942) (xy 52.291774 -494.838456) (xy 52.253287 -494.903771)
			(xy 52.208076 -494.964626) (xy 52.156652 -495.02033) (xy 52.099599 -495.070252) (xy 52.037563 -495.113827)
			(xy 51.971246 -495.150562) (xy 51.9014 -495.180039) (xy 51.828817 -495.201925) (xy 51.754319 -495.215972)
			(xy 51.678749 -495.222021) (xy 51.602965 -495.220002) (xy 51.527825 -495.20994) (xy 51.45418 -495.191948)
			(xy 51.382864 -495.16623) (xy 51.314687 -495.133078) (xy 51.250419 -495.092866) (xy 51.19079 -495.046051)
			(xy 51.136474 -494.993163) (xy 51.088088 -494.934801) (xy 51.04618 -494.871626) (xy 51.011224 -494.804355)
			(xy 50.983617 -494.73375) (xy 50.963671 -494.660609) (xy 50.951612 -494.585764) (xy 50.947577 -494.51006)
			(xy 49.831498 -494.51006) (xy 49.830994 -494.547966) (xy 49.822935 -494.623347) (xy 49.80691 -494.697445)
			(xy 49.7831 -494.76942) (xy 49.751774 -494.838456) (xy 49.713287 -494.903771) (xy 49.668076 -494.964626)
			(xy 49.616652 -495.02033) (xy 49.559599 -495.070252) (xy 49.497563 -495.113827) (xy 49.431246 -495.150562)
			(xy 49.3614 -495.180039) (xy 49.288817 -495.201925) (xy 49.214319 -495.215972) (xy 49.138749 -495.222021)
			(xy 49.062965 -495.220002) (xy 48.987825 -495.20994) (xy 48.91418 -495.191948) (xy 48.842864 -495.16623)
			(xy 48.774687 -495.133078) (xy 48.710419 -495.092866) (xy 48.65079 -495.046051) (xy 48.596474 -494.993163)
			(xy 48.548088 -494.934801) (xy 48.50618 -494.871626) (xy 48.471224 -494.804355) (xy 48.443617 -494.73375)
			(xy 48.423671 -494.660609) (xy 48.411612 -494.585764) (xy 48.407577 -494.51006) (xy 47.291498 -494.51006)
			(xy 47.290994 -494.547966) (xy 47.282935 -494.623347) (xy 47.26691 -494.697445) (xy 47.2431 -494.76942)
			(xy 47.211774 -494.838456) (xy 47.173287 -494.903771) (xy 47.128076 -494.964626) (xy 47.076652 -495.02033)
			(xy 47.019599 -495.070252) (xy 46.957563 -495.113827) (xy 46.891246 -495.150562) (xy 46.8214 -495.180039)
			(xy 46.748817 -495.201925) (xy 46.674319 -495.215972) (xy 46.598749 -495.222021) (xy 46.522965 -495.220002)
			(xy 46.447825 -495.20994) (xy 46.37418 -495.191948) (xy 46.302864 -495.16623) (xy 46.234687 -495.133078)
			(xy 46.170419 -495.092866) (xy 46.11079 -495.046051) (xy 46.056474 -494.993163) (xy 46.008088 -494.934801)
			(xy 45.96618 -494.871626) (xy 45.931224 -494.804355) (xy 45.903617 -494.73375) (xy 45.883671 -494.660609)
			(xy 45.871612 -494.585764) (xy 45.867577 -494.51006) (xy 44.751498 -494.51006) (xy 44.750994 -494.547966)
			(xy 44.742935 -494.623347) (xy 44.72691 -494.697445) (xy 44.7031 -494.76942) (xy 44.671774 -494.838456)
			(xy 44.633287 -494.903771) (xy 44.588076 -494.964626) (xy 44.536652 -495.02033) (xy 44.479599 -495.070252)
			(xy 44.417563 -495.113827) (xy 44.351246 -495.150562) (xy 44.2814 -495.180039) (xy 44.208817 -495.201925)
			(xy 44.134319 -495.215972) (xy 44.058749 -495.222021) (xy 43.982965 -495.220002) (xy 43.907825 -495.20994)
			(xy 43.83418 -495.191948) (xy 43.762864 -495.16623) (xy 43.694687 -495.133078) (xy 43.630419 -495.092866)
			(xy 43.57079 -495.046051) (xy 43.516474 -494.993163) (xy 43.468088 -494.934801) (xy 43.42618 -494.871626)
			(xy 43.391224 -494.804355) (xy 43.363617 -494.73375) (xy 43.343671 -494.660609) (xy 43.331612 -494.585764)
			(xy 43.327577 -494.51006) (xy 42.502604 -494.51006) (xy 42.593088 -494.582218) (xy 42.678643 -494.660691)
			(xy 42.758581 -494.744879) (xy 42.83252 -494.834381) (xy 42.900108 -494.928772) (xy 42.961022 -495.0276)
			(xy 43.014974 -495.130396) (xy 43.056604 -495.22507) (xy 84.927697 -495.22507) (xy 84.931732 -495.149366)
			(xy 84.943791 -495.074521) (xy 84.963737 -495.00138) (xy 84.991344 -494.930775) (xy 85.0263 -494.863504)
			(xy 85.068208 -494.800329) (xy 85.116594 -494.741967) (xy 85.17091 -494.689079) (xy 85.230539 -494.642264)
			(xy 85.294807 -494.602052) (xy 85.362984 -494.5689) (xy 85.4343 -494.543182) (xy 85.507945 -494.52519)
			(xy 85.583085 -494.515128) (xy 85.658869 -494.513109) (xy 85.734439 -494.519158) (xy 85.808937 -494.533205)
			(xy 85.88152 -494.555091) (xy 85.951366 -494.584568) (xy 86.017683 -494.621303) (xy 86.079719 -494.664878)
			(xy 86.136772 -494.7148) (xy 86.188196 -494.770504) (xy 86.233407 -494.831359) (xy 86.271894 -494.896674)
			(xy 86.30322 -494.96571) (xy 86.32703 -495.037685) (xy 86.343055 -495.111783) (xy 86.351114 -495.187164)
			(xy 86.351618 -495.22507) (xy 87.467697 -495.22507) (xy 87.471732 -495.149366) (xy 87.483791 -495.074521)
			(xy 87.503737 -495.00138) (xy 87.531344 -494.930775) (xy 87.5663 -494.863504) (xy 87.608208 -494.800329)
			(xy 87.656594 -494.741967) (xy 87.71091 -494.689079) (xy 87.770539 -494.642264) (xy 87.834807 -494.602052)
			(xy 87.902984 -494.5689) (xy 87.9743 -494.543182) (xy 88.047945 -494.52519) (xy 88.123085 -494.515128)
			(xy 88.198869 -494.513109) (xy 88.274439 -494.519158) (xy 88.348937 -494.533205) (xy 88.42152 -494.555091)
			(xy 88.491366 -494.584568) (xy 88.557683 -494.621303) (xy 88.619719 -494.664878) (xy 88.676772 -494.7148)
			(xy 88.728196 -494.770504) (xy 88.773407 -494.831359) (xy 88.811894 -494.896674) (xy 88.84322 -494.96571)
			(xy 88.86703 -495.037685) (xy 88.883055 -495.111783) (xy 88.891114 -495.187164) (xy 88.891618 -495.22507)
			(xy 90.007697 -495.22507) (xy 90.011732 -495.149366) (xy 90.023791 -495.074521) (xy 90.043737 -495.00138)
			(xy 90.071344 -494.930775) (xy 90.1063 -494.863504) (xy 90.148208 -494.800329) (xy 90.196594 -494.741967)
			(xy 90.25091 -494.689079) (xy 90.310539 -494.642264) (xy 90.374807 -494.602052) (xy 90.442984 -494.5689)
			(xy 90.5143 -494.543182) (xy 90.587945 -494.52519) (xy 90.663085 -494.515128) (xy 90.738869 -494.513109)
			(xy 90.814439 -494.519158) (xy 90.888937 -494.533205) (xy 90.96152 -494.555091) (xy 91.031366 -494.584568)
			(xy 91.097683 -494.621303) (xy 91.159719 -494.664878) (xy 91.216772 -494.7148) (xy 91.268196 -494.770504)
			(xy 91.313407 -494.831359) (xy 91.351894 -494.896674) (xy 91.38322 -494.96571) (xy 91.40703 -495.037685)
			(xy 91.423055 -495.111783) (xy 91.431114 -495.187164) (xy 91.431618 -495.22507) (xy 91.431114 -495.262976)
			(xy 91.423055 -495.338357) (xy 91.40703 -495.412455) (xy 91.38322 -495.48443) (xy 91.351894 -495.553466)
			(xy 91.313407 -495.618781) (xy 91.268196 -495.679636) (xy 91.216772 -495.73534) (xy 91.159719 -495.785262)
			(xy 91.097683 -495.828837) (xy 91.031366 -495.865572) (xy 90.96152 -495.895049) (xy 90.888937 -495.916935)
			(xy 90.814439 -495.930982) (xy 90.738869 -495.937031) (xy 90.663085 -495.935012) (xy 90.587945 -495.92495)
			(xy 90.5143 -495.906958) (xy 90.442984 -495.88124) (xy 90.374807 -495.848088) (xy 90.310539 -495.807876)
			(xy 90.25091 -495.761061) (xy 90.196594 -495.708173) (xy 90.148208 -495.649811) (xy 90.1063 -495.586636)
			(xy 90.071344 -495.519365) (xy 90.043737 -495.44876) (xy 90.023791 -495.375619) (xy 90.011732 -495.300774)
			(xy 90.007697 -495.22507) (xy 88.891618 -495.22507) (xy 88.891114 -495.262976) (xy 88.883055 -495.338357)
			(xy 88.86703 -495.412455) (xy 88.84322 -495.48443) (xy 88.811894 -495.553466) (xy 88.773407 -495.618781)
			(xy 88.728196 -495.679636) (xy 88.676772 -495.73534) (xy 88.619719 -495.785262) (xy 88.557683 -495.828837)
			(xy 88.491366 -495.865572) (xy 88.42152 -495.895049) (xy 88.348937 -495.916935) (xy 88.274439 -495.930982)
			(xy 88.198869 -495.937031) (xy 88.123085 -495.935012) (xy 88.047945 -495.92495) (xy 87.9743 -495.906958)
			(xy 87.902984 -495.88124) (xy 87.834807 -495.848088) (xy 87.770539 -495.807876) (xy 87.71091 -495.761061)
			(xy 87.656594 -495.708173) (xy 87.608208 -495.649811) (xy 87.5663 -495.586636) (xy 87.531344 -495.519365)
			(xy 87.503737 -495.44876) (xy 87.483791 -495.375619) (xy 87.471732 -495.300774) (xy 87.467697 -495.22507)
			(xy 86.351618 -495.22507) (xy 86.351114 -495.262976) (xy 86.343055 -495.338357) (xy 86.32703 -495.412455)
			(xy 86.30322 -495.48443) (xy 86.271894 -495.553466) (xy 86.233407 -495.618781) (xy 86.188196 -495.679636)
			(xy 86.136772 -495.73534) (xy 86.079719 -495.785262) (xy 86.017683 -495.828837) (xy 85.951366 -495.865572)
			(xy 85.88152 -495.895049) (xy 85.808937 -495.916935) (xy 85.734439 -495.930982) (xy 85.658869 -495.937031)
			(xy 85.583085 -495.935012) (xy 85.507945 -495.92495) (xy 85.4343 -495.906958) (xy 85.362984 -495.88124)
			(xy 85.294807 -495.848088) (xy 85.230539 -495.807876) (xy 85.17091 -495.761061) (xy 85.116594 -495.708173)
			(xy 85.068208 -495.649811) (xy 85.0263 -495.586636) (xy 84.991344 -495.519365) (xy 84.963737 -495.44876)
			(xy 84.943791 -495.375619) (xy 84.931732 -495.300774) (xy 84.927697 -495.22507) (xy 43.056604 -495.22507)
			(xy 43.061704 -495.236669) (xy 43.100992 -495.345913) (xy 43.132649 -495.457606) (xy 43.156525 -495.571218)
			(xy 43.172506 -495.686206) (xy 43.180515 -495.802023) (xy 43.181016 -495.86007) (xy 43.180515 -495.918117)
			(xy 43.172506 -496.033934) (xy 43.156525 -496.148922) (xy 43.132649 -496.262534) (xy 43.100992 -496.374227)
			(xy 43.061704 -496.483471) (xy 43.056604 -496.49507) (xy 86.197697 -496.49507) (xy 86.201732 -496.419366)
			(xy 86.213791 -496.344521) (xy 86.233737 -496.27138) (xy 86.261344 -496.200775) (xy 86.2963 -496.133504)
			(xy 86.338208 -496.070329) (xy 86.386594 -496.011967) (xy 86.44091 -495.959079) (xy 86.500539 -495.912264)
			(xy 86.564807 -495.872052) (xy 86.632984 -495.8389) (xy 86.7043 -495.813182) (xy 86.777945 -495.79519)
			(xy 86.853085 -495.785128) (xy 86.928869 -495.783109) (xy 87.004439 -495.789158) (xy 87.078937 -495.803205)
			(xy 87.15152 -495.825091) (xy 87.221366 -495.854568) (xy 87.287683 -495.891303) (xy 87.349719 -495.934878)
			(xy 87.406772 -495.9848) (xy 87.458196 -496.040504) (xy 87.503407 -496.101359) (xy 87.541894 -496.166674)
			(xy 87.57322 -496.23571) (xy 87.59703 -496.307685) (xy 87.613055 -496.381783) (xy 87.621114 -496.457164)
			(xy 87.621618 -496.49507) (xy 88.737697 -496.49507) (xy 88.741732 -496.419366) (xy 88.753791 -496.344521)
			(xy 88.773737 -496.27138) (xy 88.801344 -496.200775) (xy 88.8363 -496.133504) (xy 88.878208 -496.070329)
			(xy 88.926594 -496.011967) (xy 88.98091 -495.959079) (xy 89.040539 -495.912264) (xy 89.104807 -495.872052)
			(xy 89.172984 -495.8389) (xy 89.2443 -495.813182) (xy 89.317945 -495.79519) (xy 89.393085 -495.785128)
			(xy 89.468869 -495.783109) (xy 89.544439 -495.789158) (xy 89.618937 -495.803205) (xy 89.69152 -495.825091)
			(xy 89.761366 -495.854568) (xy 89.827683 -495.891303) (xy 89.889719 -495.934878) (xy 89.946772 -495.9848)
			(xy 89.998196 -496.040504) (xy 90.043407 -496.101359) (xy 90.081894 -496.166674) (xy 90.11322 -496.23571)
			(xy 90.13703 -496.307685) (xy 90.153055 -496.381783) (xy 90.161114 -496.457164) (xy 90.161618 -496.49507)
			(xy 91.277697 -496.49507) (xy 91.281732 -496.419366) (xy 91.293791 -496.344521) (xy 91.313737 -496.27138)
			(xy 91.341344 -496.200775) (xy 91.3763 -496.133504) (xy 91.418208 -496.070329) (xy 91.466594 -496.011967)
			(xy 91.52091 -495.959079) (xy 91.580539 -495.912264) (xy 91.644807 -495.872052) (xy 91.712984 -495.8389)
			(xy 91.7843 -495.813182) (xy 91.857945 -495.79519) (xy 91.933085 -495.785128) (xy 92.008869 -495.783109)
			(xy 92.084439 -495.789158) (xy 92.158937 -495.803205) (xy 92.23152 -495.825091) (xy 92.301366 -495.854568)
			(xy 92.367683 -495.891303) (xy 92.429719 -495.934878) (xy 92.486772 -495.9848) (xy 92.538196 -496.040504)
			(xy 92.583407 -496.101359) (xy 92.621894 -496.166674) (xy 92.65322 -496.23571) (xy 92.67703 -496.307685)
			(xy 92.693055 -496.381783) (xy 92.701114 -496.457164) (xy 92.701618 -496.49507) (xy 92.701114 -496.532976)
			(xy 92.693055 -496.608357) (xy 92.67703 -496.682455) (xy 92.65322 -496.75443) (xy 92.621894 -496.823466)
			(xy 92.583407 -496.888781) (xy 92.538196 -496.949636) (xy 92.486772 -497.00534) (xy 92.429719 -497.055262)
			(xy 92.367683 -497.098837) (xy 92.301366 -497.135572) (xy 92.23152 -497.165049) (xy 92.158937 -497.186935)
			(xy 92.084439 -497.200982) (xy 92.008869 -497.207031) (xy 91.933085 -497.205012) (xy 91.857945 -497.19495)
			(xy 91.7843 -497.176958) (xy 91.712984 -497.15124) (xy 91.644807 -497.118088) (xy 91.580539 -497.077876)
			(xy 91.52091 -497.031061) (xy 91.466594 -496.978173) (xy 91.418208 -496.919811) (xy 91.3763 -496.856636)
			(xy 91.341344 -496.789365) (xy 91.313737 -496.71876) (xy 91.293791 -496.645619) (xy 91.281732 -496.570774)
			(xy 91.277697 -496.49507) (xy 90.161618 -496.49507) (xy 90.161114 -496.532976) (xy 90.153055 -496.608357)
			(xy 90.13703 -496.682455) (xy 90.11322 -496.75443) (xy 90.081894 -496.823466) (xy 90.043407 -496.888781)
			(xy 89.998196 -496.949636) (xy 89.946772 -497.00534) (xy 89.889719 -497.055262) (xy 89.827683 -497.098837)
			(xy 89.761366 -497.135572) (xy 89.69152 -497.165049) (xy 89.618937 -497.186935) (xy 89.544439 -497.200982)
			(xy 89.468869 -497.207031) (xy 89.393085 -497.205012) (xy 89.317945 -497.19495) (xy 89.2443 -497.176958)
			(xy 89.172984 -497.15124) (xy 89.104807 -497.118088) (xy 89.040539 -497.077876) (xy 88.98091 -497.031061)
			(xy 88.926594 -496.978173) (xy 88.878208 -496.919811) (xy 88.8363 -496.856636) (xy 88.801344 -496.789365)
			(xy 88.773737 -496.71876) (xy 88.753791 -496.645619) (xy 88.741732 -496.570774) (xy 88.737697 -496.49507)
			(xy 87.621618 -496.49507) (xy 87.621114 -496.532976) (xy 87.613055 -496.608357) (xy 87.59703 -496.682455)
			(xy 87.57322 -496.75443) (xy 87.541894 -496.823466) (xy 87.503407 -496.888781) (xy 87.458196 -496.949636)
			(xy 87.406772 -497.00534) (xy 87.349719 -497.055262) (xy 87.287683 -497.098837) (xy 87.221366 -497.135572)
			(xy 87.15152 -497.165049) (xy 87.078937 -497.186935) (xy 87.004439 -497.200982) (xy 86.928869 -497.207031)
			(xy 86.853085 -497.205012) (xy 86.777945 -497.19495) (xy 86.7043 -497.176958) (xy 86.632984 -497.15124)
			(xy 86.564807 -497.118088) (xy 86.500539 -497.077876) (xy 86.44091 -497.031061) (xy 86.386594 -496.978173)
			(xy 86.338208 -496.919811) (xy 86.2963 -496.856636) (xy 86.261344 -496.789365) (xy 86.233737 -496.71876)
			(xy 86.213791 -496.645619) (xy 86.201732 -496.570774) (xy 86.197697 -496.49507) (xy 43.056604 -496.49507)
			(xy 43.055152 -496.498372) (xy 43.328336 -496.498372) (xy 44.751244 -496.498372) (xy 44.751244 -497.21008)
			(xy 45.867577 -497.21008) (xy 45.871612 -497.134376) (xy 45.883671 -497.059531) (xy 45.903617 -496.98639)
			(xy 45.931224 -496.915785) (xy 45.96618 -496.848514) (xy 46.008088 -496.785339) (xy 46.056474 -496.726977)
			(xy 46.11079 -496.674089) (xy 46.170419 -496.627274) (xy 46.234687 -496.587062) (xy 46.302864 -496.55391)
			(xy 46.37418 -496.528192) (xy 46.447825 -496.5102) (xy 46.522965 -496.500138) (xy 46.598749 -496.498119)
			(xy 46.674319 -496.504168) (xy 46.748817 -496.518215) (xy 46.8214 -496.540101) (xy 46.891246 -496.569578)
			(xy 46.957563 -496.606313) (xy 47.019599 -496.649888) (xy 47.076652 -496.69981) (xy 47.128076 -496.755514)
			(xy 47.173287 -496.816369) (xy 47.211774 -496.881684) (xy 47.2431 -496.95072) (xy 47.26691 -497.022695)
			(xy 47.282935 -497.096793) (xy 47.290994 -497.172174) (xy 47.291498 -497.21008) (xy 48.407577 -497.21008)
			(xy 48.411612 -497.134376) (xy 48.423671 -497.059531) (xy 48.443617 -496.98639) (xy 48.471224 -496.915785)
			(xy 48.50618 -496.848514) (xy 48.548088 -496.785339) (xy 48.596474 -496.726977) (xy 48.65079 -496.674089)
			(xy 48.710419 -496.627274) (xy 48.774687 -496.587062) (xy 48.842864 -496.55391) (xy 48.91418 -496.528192)
			(xy 48.987825 -496.5102) (xy 49.062965 -496.500138) (xy 49.138749 -496.498119) (xy 49.214319 -496.504168)
			(xy 49.288817 -496.518215) (xy 49.3614 -496.540101) (xy 49.431246 -496.569578) (xy 49.497563 -496.606313)
			(xy 49.559599 -496.649888) (xy 49.616652 -496.69981) (xy 49.668076 -496.755514) (xy 49.713287 -496.816369)
			(xy 49.751774 -496.881684) (xy 49.7831 -496.95072) (xy 49.80691 -497.022695) (xy 49.822935 -497.096793)
			(xy 49.830994 -497.172174) (xy 49.831498 -497.21008) (xy 50.947577 -497.21008) (xy 50.951612 -497.134376)
			(xy 50.963671 -497.059531) (xy 50.983617 -496.98639) (xy 51.011224 -496.915785) (xy 51.04618 -496.848514)
			(xy 51.088088 -496.785339) (xy 51.136474 -496.726977) (xy 51.19079 -496.674089) (xy 51.250419 -496.627274)
			(xy 51.314687 -496.587062) (xy 51.382864 -496.55391) (xy 51.45418 -496.528192) (xy 51.527825 -496.5102)
			(xy 51.602965 -496.500138) (xy 51.678749 -496.498119) (xy 51.754319 -496.504168) (xy 51.828817 -496.518215)
			(xy 51.9014 -496.540101) (xy 51.971246 -496.569578) (xy 52.037563 -496.606313) (xy 52.099599 -496.649888)
			(xy 52.156652 -496.69981) (xy 52.208076 -496.755514) (xy 52.253287 -496.816369) (xy 52.291774 -496.881684)
			(xy 52.3231 -496.95072) (xy 52.34691 -497.022695) (xy 52.362935 -497.096793) (xy 52.370994 -497.172174)
			(xy 52.371498 -497.21008) (xy 53.487577 -497.21008) (xy 53.491612 -497.134376) (xy 53.503671 -497.059531)
			(xy 53.523617 -496.98639) (xy 53.551224 -496.915785) (xy 53.58618 -496.848514) (xy 53.628088 -496.785339)
			(xy 53.676474 -496.726977) (xy 53.73079 -496.674089) (xy 53.790419 -496.627274) (xy 53.854687 -496.587062)
			(xy 53.922864 -496.55391) (xy 53.99418 -496.528192) (xy 54.067825 -496.5102) (xy 54.142965 -496.500138)
			(xy 54.218749 -496.498119) (xy 54.294319 -496.504168) (xy 54.368817 -496.518215) (xy 54.4414 -496.540101)
			(xy 54.511246 -496.569578) (xy 54.577563 -496.606313) (xy 54.639599 -496.649888) (xy 54.696652 -496.69981)
			(xy 54.748076 -496.755514) (xy 54.793287 -496.816369) (xy 54.831774 -496.881684) (xy 54.8631 -496.95072)
			(xy 54.88691 -497.022695) (xy 54.902935 -497.096793) (xy 54.910994 -497.172174) (xy 54.911498 -497.21008)
			(xy 56.027577 -497.21008) (xy 56.031612 -497.134376) (xy 56.043671 -497.059531) (xy 56.063617 -496.98639)
			(xy 56.091224 -496.915785) (xy 56.12618 -496.848514) (xy 56.168088 -496.785339) (xy 56.216474 -496.726977)
			(xy 56.27079 -496.674089) (xy 56.330419 -496.627274) (xy 56.394687 -496.587062) (xy 56.462864 -496.55391)
			(xy 56.53418 -496.528192) (xy 56.607825 -496.5102) (xy 56.682965 -496.500138) (xy 56.758749 -496.498119)
			(xy 56.834319 -496.504168) (xy 56.908817 -496.518215) (xy 56.9814 -496.540101) (xy 57.051246 -496.569578)
			(xy 57.117563 -496.606313) (xy 57.179599 -496.649888) (xy 57.236652 -496.69981) (xy 57.288076 -496.755514)
			(xy 57.333287 -496.816369) (xy 57.371774 -496.881684) (xy 57.4031 -496.95072) (xy 57.42691 -497.022695)
			(xy 57.442935 -497.096793) (xy 57.450994 -497.172174) (xy 57.451498 -497.21008) (xy 58.567577 -497.21008)
			(xy 58.571612 -497.134376) (xy 58.583671 -497.059531) (xy 58.603617 -496.98639) (xy 58.631224 -496.915785)
			(xy 58.66618 -496.848514) (xy 58.708088 -496.785339) (xy 58.756474 -496.726977) (xy 58.81079 -496.674089)
			(xy 58.870419 -496.627274) (xy 58.934687 -496.587062) (xy 59.002864 -496.55391) (xy 59.07418 -496.528192)
			(xy 59.147825 -496.5102) (xy 59.222965 -496.500138) (xy 59.298749 -496.498119) (xy 59.374319 -496.504168)
			(xy 59.448817 -496.518215) (xy 59.5214 -496.540101) (xy 59.591246 -496.569578) (xy 59.657563 -496.606313)
			(xy 59.719599 -496.649888) (xy 59.776652 -496.69981) (xy 59.828076 -496.755514) (xy 59.873287 -496.816369)
			(xy 59.911774 -496.881684) (xy 59.9431 -496.95072) (xy 59.96691 -497.022695) (xy 59.982935 -497.096793)
			(xy 59.990994 -497.172174) (xy 59.991498 -497.21008) (xy 61.107577 -497.21008) (xy 61.111612 -497.134376)
			(xy 61.123671 -497.059531) (xy 61.143617 -496.98639) (xy 61.171224 -496.915785) (xy 61.20618 -496.848514)
			(xy 61.248088 -496.785339) (xy 61.296474 -496.726977) (xy 61.35079 -496.674089) (xy 61.410419 -496.627274)
			(xy 61.474687 -496.587062) (xy 61.542864 -496.55391) (xy 61.61418 -496.528192) (xy 61.687825 -496.5102)
			(xy 61.762965 -496.500138) (xy 61.838749 -496.498119) (xy 61.914319 -496.504168) (xy 61.988817 -496.518215)
			(xy 62.0614 -496.540101) (xy 62.131246 -496.569578) (xy 62.197563 -496.606313) (xy 62.259599 -496.649888)
			(xy 62.316652 -496.69981) (xy 62.368076 -496.755514) (xy 62.413287 -496.816369) (xy 62.451774 -496.881684)
			(xy 62.4831 -496.95072) (xy 62.50691 -497.022695) (xy 62.522935 -497.096793) (xy 62.530994 -497.172174)
			(xy 62.531498 -497.21008) (xy 62.530994 -497.247986) (xy 62.522935 -497.323367) (xy 62.50691 -497.397465)
			(xy 62.4831 -497.46944) (xy 62.451774 -497.538476) (xy 62.413287 -497.603791) (xy 62.368076 -497.664646)
			(xy 62.316652 -497.72035) (xy 62.265544 -497.76507) (xy 84.927697 -497.76507) (xy 84.931732 -497.689366)
			(xy 84.943791 -497.614521) (xy 84.963737 -497.54138) (xy 84.991344 -497.470775) (xy 85.0263 -497.403504)
			(xy 85.068208 -497.340329) (xy 85.116594 -497.281967) (xy 85.17091 -497.229079) (xy 85.230539 -497.182264)
			(xy 85.294807 -497.142052) (xy 85.362984 -497.1089) (xy 85.4343 -497.083182) (xy 85.507945 -497.06519)
			(xy 85.583085 -497.055128) (xy 85.658869 -497.053109) (xy 85.734439 -497.059158) (xy 85.808937 -497.073205)
			(xy 85.88152 -497.095091) (xy 85.951366 -497.124568) (xy 86.017683 -497.161303) (xy 86.079719 -497.204878)
			(xy 86.136772 -497.2548) (xy 86.188196 -497.310504) (xy 86.233407 -497.371359) (xy 86.271894 -497.436674)
			(xy 86.30322 -497.50571) (xy 86.32703 -497.577685) (xy 86.343055 -497.651783) (xy 86.351114 -497.727164)
			(xy 86.351618 -497.76507) (xy 87.467697 -497.76507) (xy 87.471732 -497.689366) (xy 87.483791 -497.614521)
			(xy 87.503737 -497.54138) (xy 87.531344 -497.470775) (xy 87.5663 -497.403504) (xy 87.608208 -497.340329)
			(xy 87.656594 -497.281967) (xy 87.71091 -497.229079) (xy 87.770539 -497.182264) (xy 87.834807 -497.142052)
			(xy 87.902984 -497.1089) (xy 87.9743 -497.083182) (xy 88.047945 -497.06519) (xy 88.123085 -497.055128)
			(xy 88.198869 -497.053109) (xy 88.274439 -497.059158) (xy 88.348937 -497.073205) (xy 88.42152 -497.095091)
			(xy 88.491366 -497.124568) (xy 88.557683 -497.161303) (xy 88.619719 -497.204878) (xy 88.676772 -497.2548)
			(xy 88.728196 -497.310504) (xy 88.773407 -497.371359) (xy 88.811894 -497.436674) (xy 88.84322 -497.50571)
			(xy 88.86703 -497.577685) (xy 88.883055 -497.651783) (xy 88.891114 -497.727164) (xy 88.891618 -497.76507)
			(xy 90.007697 -497.76507) (xy 90.011732 -497.689366) (xy 90.023791 -497.614521) (xy 90.043737 -497.54138)
			(xy 90.071344 -497.470775) (xy 90.1063 -497.403504) (xy 90.148208 -497.340329) (xy 90.196594 -497.281967)
			(xy 90.25091 -497.229079) (xy 90.310539 -497.182264) (xy 90.374807 -497.142052) (xy 90.442984 -497.1089)
			(xy 90.5143 -497.083182) (xy 90.587945 -497.06519) (xy 90.663085 -497.055128) (xy 90.738869 -497.053109)
			(xy 90.814439 -497.059158) (xy 90.888937 -497.073205) (xy 90.96152 -497.095091) (xy 91.031366 -497.124568)
			(xy 91.097683 -497.161303) (xy 91.159719 -497.204878) (xy 91.165664 -497.21008) (xy 93.154506 -497.21008)
			(xy 93.158522 -497.09381) (xy 93.170549 -496.978095) (xy 93.190531 -496.863485) (xy 93.218373 -496.750526)
			(xy 93.253942 -496.639758) (xy 93.297068 -496.531707) (xy 93.347545 -496.426889) (xy 93.405134 -496.325804)
			(xy 93.46956 -496.228932) (xy 93.540515 -496.136736) (xy 93.617662 -496.049655) (xy 93.700633 -495.968104)
			(xy 93.789033 -495.892472) (xy 93.88244 -495.823118) (xy 93.980409 -495.760375) (xy 94.082473 -495.704539)
			(xy 94.188147 -495.655878) (xy 94.296926 -495.614624) (xy 94.408291 -495.580973) (xy 94.521714 -495.555085)
			(xy 94.636651 -495.537084) (xy 94.752557 -495.527055) (xy 94.868879 -495.525047) (xy 94.985062 -495.531069)
			(xy 95.100553 -495.545092) (xy 95.214801 -495.56705) (xy 95.327262 -495.596837) (xy 95.4374 -495.634312)
			(xy 95.54469 -495.679297) (xy 95.648621 -495.731576) (xy 95.748697 -495.790901) (xy 95.844443 -495.856989)
			(xy 95.9354 -495.929525) (xy 96.021136 -496.008164) (xy 96.101243 -496.09253) (xy 96.175339 -496.182222)
			(xy 96.243069 -496.276812) (xy 96.304113 -496.37585) (xy 96.358178 -496.478863) (xy 96.405008 -496.58536)
			(xy 96.444379 -496.694835) (xy 96.476103 -496.806765) (xy 96.500029 -496.920617) (xy 96.516043 -497.035849)
			(xy 96.52407 -497.151911) (xy 96.524572 -497.21008) (xy 96.52407 -497.268249) (xy 96.516043 -497.384311)
			(xy 96.500029 -497.499543) (xy 96.476103 -497.613395) (xy 96.444379 -497.725325) (xy 96.405008 -497.8348)
			(xy 96.358178 -497.941297) (xy 96.304113 -498.04431) (xy 96.243069 -498.143348) (xy 96.175339 -498.237938)
			(xy 96.101243 -498.32763) (xy 96.021136 -498.411996) (xy 95.9354 -498.490635) (xy 95.844443 -498.563171)
			(xy 95.748697 -498.629259) (xy 95.648621 -498.688584) (xy 95.54469 -498.740863) (xy 95.4374 -498.785848)
			(xy 95.327262 -498.823323) (xy 95.214801 -498.85311) (xy 95.100553 -498.875068) (xy 94.985062 -498.889091)
			(xy 94.868879 -498.895113) (xy 94.752557 -498.893105) (xy 94.636651 -498.883076) (xy 94.521714 -498.865075)
			(xy 94.408291 -498.839187) (xy 94.296926 -498.805536) (xy 94.188147 -498.764282) (xy 94.082473 -498.715621)
			(xy 93.980409 -498.659785) (xy 93.88244 -498.597042) (xy 93.789033 -498.527688) (xy 93.700633 -498.452056)
			(xy 93.617662 -498.370505) (xy 93.540515 -498.283424) (xy 93.46956 -498.191228) (xy 93.405134 -498.094356)
			(xy 93.347545 -497.993271) (xy 93.297068 -497.888453) (xy 93.253942 -497.780402) (xy 93.218373 -497.669634)
			(xy 93.190531 -497.556675) (xy 93.170549 -497.442065) (xy 93.158522 -497.32635) (xy 93.154506 -497.21008)
			(xy 91.165664 -497.21008) (xy 91.216772 -497.2548) (xy 91.268196 -497.310504) (xy 91.313407 -497.371359)
			(xy 91.351894 -497.436674) (xy 91.38322 -497.50571) (xy 91.40703 -497.577685) (xy 91.423055 -497.651783)
			(xy 91.431114 -497.727164) (xy 91.431618 -497.76507) (xy 91.431114 -497.802976) (xy 91.423055 -497.878357)
			(xy 91.40703 -497.952455) (xy 91.38322 -498.02443) (xy 91.351894 -498.093466) (xy 91.313407 -498.158781)
			(xy 91.268196 -498.219636) (xy 91.216772 -498.27534) (xy 91.159719 -498.325262) (xy 91.097683 -498.368837)
			(xy 91.031366 -498.405572) (xy 90.96152 -498.435049) (xy 90.888937 -498.456935) (xy 90.814439 -498.470982)
			(xy 90.738869 -498.477031) (xy 90.663085 -498.475012) (xy 90.587945 -498.46495) (xy 90.5143 -498.446958)
			(xy 90.442984 -498.42124) (xy 90.374807 -498.388088) (xy 90.310539 -498.347876) (xy 90.25091 -498.301061)
			(xy 90.196594 -498.248173) (xy 90.148208 -498.189811) (xy 90.1063 -498.126636) (xy 90.071344 -498.059365)
			(xy 90.043737 -497.98876) (xy 90.023791 -497.915619) (xy 90.011732 -497.840774) (xy 90.007697 -497.76507)
			(xy 88.891618 -497.76507) (xy 88.891114 -497.802976) (xy 88.883055 -497.878357) (xy 88.86703 -497.952455)
			(xy 88.84322 -498.02443) (xy 88.811894 -498.093466) (xy 88.773407 -498.158781) (xy 88.728196 -498.219636)
			(xy 88.676772 -498.27534) (xy 88.619719 -498.325262) (xy 88.557683 -498.368837) (xy 88.491366 -498.405572)
			(xy 88.42152 -498.435049) (xy 88.348937 -498.456935) (xy 88.274439 -498.470982) (xy 88.198869 -498.477031)
			(xy 88.123085 -498.475012) (xy 88.047945 -498.46495) (xy 87.9743 -498.446958) (xy 87.902984 -498.42124)
			(xy 87.834807 -498.388088) (xy 87.770539 -498.347876) (xy 87.71091 -498.301061) (xy 87.656594 -498.248173)
			(xy 87.608208 -498.189811) (xy 87.5663 -498.126636) (xy 87.531344 -498.059365) (xy 87.503737 -497.98876)
			(xy 87.483791 -497.915619) (xy 87.471732 -497.840774) (xy 87.467697 -497.76507) (xy 86.351618 -497.76507)
			(xy 86.351114 -497.802976) (xy 86.343055 -497.878357) (xy 86.32703 -497.952455) (xy 86.30322 -498.02443)
			(xy 86.271894 -498.093466) (xy 86.233407 -498.158781) (xy 86.188196 -498.219636) (xy 86.136772 -498.27534)
			(xy 86.079719 -498.325262) (xy 86.017683 -498.368837) (xy 85.951366 -498.405572) (xy 85.88152 -498.435049)
			(xy 85.808937 -498.456935) (xy 85.734439 -498.470982) (xy 85.658869 -498.477031) (xy 85.583085 -498.475012)
			(xy 85.507945 -498.46495) (xy 85.4343 -498.446958) (xy 85.362984 -498.42124) (xy 85.294807 -498.388088)
			(xy 85.230539 -498.347876) (xy 85.17091 -498.301061) (xy 85.116594 -498.248173) (xy 85.068208 -498.189811)
			(xy 85.0263 -498.126636) (xy 84.991344 -498.059365) (xy 84.963737 -497.98876) (xy 84.943791 -497.915619)
			(xy 84.931732 -497.840774) (xy 84.927697 -497.76507) (xy 62.265544 -497.76507) (xy 62.259599 -497.770272)
			(xy 62.197563 -497.813847) (xy 62.131246 -497.850582) (xy 62.0614 -497.880059) (xy 61.988817 -497.901945)
			(xy 61.914319 -497.915992) (xy 61.838749 -497.922041) (xy 61.762965 -497.920022) (xy 61.687825 -497.90996)
			(xy 61.61418 -497.891968) (xy 61.542864 -497.86625) (xy 61.474687 -497.833098) (xy 61.410419 -497.792886)
			(xy 61.35079 -497.746071) (xy 61.296474 -497.693183) (xy 61.248088 -497.634821) (xy 61.20618 -497.571646)
			(xy 61.171224 -497.504375) (xy 61.143617 -497.43377) (xy 61.123671 -497.360629) (xy 61.111612 -497.285784)
			(xy 61.107577 -497.21008) (xy 59.991498 -497.21008) (xy 59.990994 -497.247986) (xy 59.982935 -497.323367)
			(xy 59.96691 -497.397465) (xy 59.9431 -497.46944) (xy 59.911774 -497.538476) (xy 59.873287 -497.603791)
			(xy 59.828076 -497.664646) (xy 59.776652 -497.72035) (xy 59.719599 -497.770272) (xy 59.657563 -497.813847)
			(xy 59.591246 -497.850582) (xy 59.5214 -497.880059) (xy 59.448817 -497.901945) (xy 59.374319 -497.915992)
			(xy 59.298749 -497.922041) (xy 59.222965 -497.920022) (xy 59.147825 -497.90996) (xy 59.07418 -497.891968)
			(xy 59.002864 -497.86625) (xy 58.934687 -497.833098) (xy 58.870419 -497.792886) (xy 58.81079 -497.746071)
			(xy 58.756474 -497.693183) (xy 58.708088 -497.634821) (xy 58.66618 -497.571646) (xy 58.631224 -497.504375)
			(xy 58.603617 -497.43377) (xy 58.583671 -497.360629) (xy 58.571612 -497.285784) (xy 58.567577 -497.21008)
			(xy 57.451498 -497.21008) (xy 57.450994 -497.247986) (xy 57.442935 -497.323367) (xy 57.42691 -497.397465)
			(xy 57.4031 -497.46944) (xy 57.371774 -497.538476) (xy 57.333287 -497.603791) (xy 57.288076 -497.664646)
			(xy 57.236652 -497.72035) (xy 57.179599 -497.770272) (xy 57.117563 -497.813847) (xy 57.051246 -497.850582)
			(xy 56.9814 -497.880059) (xy 56.908817 -497.901945) (xy 56.834319 -497.915992) (xy 56.758749 -497.922041)
			(xy 56.682965 -497.920022) (xy 56.607825 -497.90996) (xy 56.53418 -497.891968) (xy 56.462864 -497.86625)
			(xy 56.394687 -497.833098) (xy 56.330419 -497.792886) (xy 56.27079 -497.746071) (xy 56.216474 -497.693183)
			(xy 56.168088 -497.634821) (xy 56.12618 -497.571646) (xy 56.091224 -497.504375) (xy 56.063617 -497.43377)
			(xy 56.043671 -497.360629) (xy 56.031612 -497.285784) (xy 56.027577 -497.21008) (xy 54.911498 -497.21008)
			(xy 54.910994 -497.247986) (xy 54.902935 -497.323367) (xy 54.88691 -497.397465) (xy 54.8631 -497.46944)
			(xy 54.831774 -497.538476) (xy 54.793287 -497.603791) (xy 54.748076 -497.664646) (xy 54.696652 -497.72035)
			(xy 54.639599 -497.770272) (xy 54.577563 -497.813847) (xy 54.511246 -497.850582) (xy 54.4414 -497.880059)
			(xy 54.368817 -497.901945) (xy 54.294319 -497.915992) (xy 54.218749 -497.922041) (xy 54.142965 -497.920022)
			(xy 54.067825 -497.90996) (xy 53.99418 -497.891968) (xy 53.922864 -497.86625) (xy 53.854687 -497.833098)
			(xy 53.790419 -497.792886) (xy 53.73079 -497.746071) (xy 53.676474 -497.693183) (xy 53.628088 -497.634821)
			(xy 53.58618 -497.571646) (xy 53.551224 -497.504375) (xy 53.523617 -497.43377) (xy 53.503671 -497.360629)
			(xy 53.491612 -497.285784) (xy 53.487577 -497.21008) (xy 52.371498 -497.21008) (xy 52.370994 -497.247986)
			(xy 52.362935 -497.323367) (xy 52.34691 -497.397465) (xy 52.3231 -497.46944) (xy 52.291774 -497.538476)
			(xy 52.253287 -497.603791) (xy 52.208076 -497.664646) (xy 52.156652 -497.72035) (xy 52.099599 -497.770272)
			(xy 52.037563 -497.813847) (xy 51.971246 -497.850582) (xy 51.9014 -497.880059) (xy 51.828817 -497.901945)
			(xy 51.754319 -497.915992) (xy 51.678749 -497.922041) (xy 51.602965 -497.920022) (xy 51.527825 -497.90996)
			(xy 51.45418 -497.891968) (xy 51.382864 -497.86625) (xy 51.314687 -497.833098) (xy 51.250419 -497.792886)
			(xy 51.19079 -497.746071) (xy 51.136474 -497.693183) (xy 51.088088 -497.634821) (xy 51.04618 -497.571646)
			(xy 51.011224 -497.504375) (xy 50.983617 -497.43377) (xy 50.963671 -497.360629) (xy 50.951612 -497.285784)
			(xy 50.947577 -497.21008) (xy 49.831498 -497.21008) (xy 49.830994 -497.247986) (xy 49.822935 -497.323367)
			(xy 49.80691 -497.397465) (xy 49.7831 -497.46944) (xy 49.751774 -497.538476) (xy 49.713287 -497.603791)
			(xy 49.668076 -497.664646) (xy 49.616652 -497.72035) (xy 49.559599 -497.770272) (xy 49.497563 -497.813847)
			(xy 49.431246 -497.850582) (xy 49.3614 -497.880059) (xy 49.288817 -497.901945) (xy 49.214319 -497.915992)
			(xy 49.138749 -497.922041) (xy 49.062965 -497.920022) (xy 48.987825 -497.90996) (xy 48.91418 -497.891968)
			(xy 48.842864 -497.86625) (xy 48.774687 -497.833098) (xy 48.710419 -497.792886) (xy 48.65079 -497.746071)
			(xy 48.596474 -497.693183) (xy 48.548088 -497.634821) (xy 48.50618 -497.571646) (xy 48.471224 -497.504375)
			(xy 48.443617 -497.43377) (xy 48.423671 -497.360629) (xy 48.411612 -497.285784) (xy 48.407577 -497.21008)
			(xy 47.291498 -497.21008) (xy 47.290994 -497.247986) (xy 47.282935 -497.323367) (xy 47.26691 -497.397465)
			(xy 47.2431 -497.46944) (xy 47.211774 -497.538476) (xy 47.173287 -497.603791) (xy 47.128076 -497.664646)
			(xy 47.076652 -497.72035) (xy 47.019599 -497.770272) (xy 46.957563 -497.813847) (xy 46.891246 -497.850582)
			(xy 46.8214 -497.880059) (xy 46.748817 -497.901945) (xy 46.674319 -497.915992) (xy 46.598749 -497.922041)
			(xy 46.522965 -497.920022) (xy 46.447825 -497.90996) (xy 46.37418 -497.891968) (xy 46.302864 -497.86625)
			(xy 46.234687 -497.833098) (xy 46.170419 -497.792886) (xy 46.11079 -497.746071) (xy 46.056474 -497.693183)
			(xy 46.008088 -497.634821) (xy 45.96618 -497.571646) (xy 45.931224 -497.504375) (xy 45.903617 -497.43377)
			(xy 45.883671 -497.360629) (xy 45.871612 -497.285784) (xy 45.867577 -497.21008) (xy 44.751244 -497.21008)
			(xy 44.751244 -497.921788) (xy 43.328336 -497.921788) (xy 43.328336 -496.498372) (xy 43.055152 -496.498372)
			(xy 43.014974 -496.589744) (xy 42.961022 -496.69254) (xy 42.900108 -496.791368) (xy 42.83252 -496.885759)
			(xy 42.758581 -496.975261) (xy 42.678643 -497.059449) (xy 42.593088 -497.137922) (xy 42.502322 -497.210305)
			(xy 42.406779 -497.276254) (xy 42.306914 -497.335454) (xy 42.203202 -497.387623) (xy 42.096139 -497.432512)
			(xy 41.986233 -497.469908) (xy 41.874009 -497.499633) (xy 41.760003 -497.521544) (xy 41.644756 -497.535537)
			(xy 41.528818 -497.541546) (xy 41.412742 -497.539543) (xy 41.29708 -497.529535) (xy 41.182385 -497.511572)
			(xy 41.069202 -497.485739) (xy 40.958071 -497.452159) (xy 40.849522 -497.410991) (xy 40.744072 -497.362433)
			(xy 40.642223 -497.306716) (xy 40.54446 -497.244104) (xy 40.45125 -497.174897) (xy 40.363037 -497.099424)
			(xy 40.280241 -497.018045) (xy 40.203257 -496.931148) (xy 40.132452 -496.839147) (xy 40.068162 -496.74248)
			(xy 40.010695 -496.641608) (xy 39.960324 -496.537011) (xy 39.917289 -496.429188) (xy 39.881795 -496.318654)
			(xy 39.854012 -496.205934) (xy 39.834072 -496.091566) (xy 39.82207 -495.976094) (xy 39.818063 -495.86007)
			(xy 1.27 -495.86007) (xy 1.27 -497.192469) (xy 4.94918 -497.192469) (xy 4.94918 -497.111359) (xy 4.95713 -497.03064)
			(xy 4.972953 -496.951089) (xy 4.996498 -496.873473) (xy 5.027537 -496.798537) (xy 5.065772 -496.727005)
			(xy 5.110834 -496.659565) (xy 5.162289 -496.596866) (xy 5.219642 -496.539513) (xy 5.282341 -496.488058)
			(xy 5.349781 -496.442996) (xy 5.421313 -496.404761) (xy 5.496249 -496.373722) (xy 5.573865 -496.350177)
			(xy 5.653416 -496.334354) (xy 5.734135 -496.326404) (xy 5.815245 -496.326404) (xy 5.895964 -496.334354)
			(xy 5.975515 -496.350177) (xy 6.053131 -496.373722) (xy 6.128067 -496.404761) (xy 6.199599 -496.442996)
			(xy 6.267039 -496.488058) (xy 6.329738 -496.539513) (xy 6.387091 -496.596866) (xy 6.438546 -496.659565)
			(xy 6.483608 -496.727005) (xy 6.521843 -496.798537) (xy 6.552882 -496.873473) (xy 6.576427 -496.951089)
			(xy 6.59225 -497.03064) (xy 6.6002 -497.111359) (xy 6.600698 -497.151914) (xy 6.6002 -497.192469)
			(xy 7.48918 -497.192469) (xy 7.48918 -497.111359) (xy 7.49713 -497.03064) (xy 7.512953 -496.951089)
			(xy 7.536498 -496.873473) (xy 7.567537 -496.798537) (xy 7.605772 -496.727005) (xy 7.650834 -496.659565)
			(xy 7.702289 -496.596866) (xy 7.759642 -496.539513) (xy 7.822341 -496.488058) (xy 7.889781 -496.442996)
			(xy 7.961313 -496.404761) (xy 8.036249 -496.373722) (xy 8.113865 -496.350177) (xy 8.193416 -496.334354)
			(xy 8.274135 -496.326404) (xy 8.355245 -496.326404) (xy 8.435964 -496.334354) (xy 8.515515 -496.350177)
			(xy 8.593131 -496.373722) (xy 8.668067 -496.404761) (xy 8.739599 -496.442996) (xy 8.807039 -496.488058)
			(xy 8.869738 -496.539513) (xy 8.927091 -496.596866) (xy 8.978546 -496.659565) (xy 9.023608 -496.727005)
			(xy 9.061843 -496.798537) (xy 9.092882 -496.873473) (xy 9.116427 -496.951089) (xy 9.13225 -497.03064)
			(xy 9.1402 -497.111359) (xy 9.140698 -497.151914) (xy 9.1402 -497.192469) (xy 10.02918 -497.192469)
			(xy 10.02918 -497.111359) (xy 10.03713 -497.03064) (xy 10.052953 -496.951089) (xy 10.076498 -496.873473)
			(xy 10.107537 -496.798537) (xy 10.145772 -496.727005) (xy 10.190834 -496.659565) (xy 10.242289 -496.596866)
			(xy 10.299642 -496.539513) (xy 10.362341 -496.488058) (xy 10.429781 -496.442996) (xy 10.501313 -496.404761)
			(xy 10.576249 -496.373722) (xy 10.653865 -496.350177) (xy 10.733416 -496.334354) (xy 10.814135 -496.326404)
			(xy 10.895245 -496.326404) (xy 10.975964 -496.334354) (xy 11.055515 -496.350177) (xy 11.133131 -496.373722)
			(xy 11.208067 -496.404761) (xy 11.279599 -496.442996) (xy 11.347039 -496.488058) (xy 11.409738 -496.539513)
			(xy 11.467091 -496.596866) (xy 11.518546 -496.659565) (xy 11.563608 -496.727005) (xy 11.601843 -496.798537)
			(xy 11.632882 -496.873473) (xy 11.656427 -496.951089) (xy 11.67225 -497.03064) (xy 11.6802 -497.111359)
			(xy 11.680698 -497.151914) (xy 11.6802 -497.192469) (xy 12.56918 -497.192469) (xy 12.56918 -497.111359)
			(xy 12.57713 -497.03064) (xy 12.592953 -496.951089) (xy 12.616498 -496.873473) (xy 12.647537 -496.798537)
			(xy 12.685772 -496.727005) (xy 12.730834 -496.659565) (xy 12.782289 -496.596866) (xy 12.839642 -496.539513)
			(xy 12.902341 -496.488058) (xy 12.969781 -496.442996) (xy 13.041313 -496.404761) (xy 13.116249 -496.373722)
			(xy 13.193865 -496.350177) (xy 13.273416 -496.334354) (xy 13.354135 -496.326404) (xy 13.435245 -496.326404)
			(xy 13.515964 -496.334354) (xy 13.595515 -496.350177) (xy 13.673131 -496.373722) (xy 13.748067 -496.404761)
			(xy 13.819599 -496.442996) (xy 13.887039 -496.488058) (xy 13.949738 -496.539513) (xy 14.007091 -496.596866)
			(xy 14.058546 -496.659565) (xy 14.103608 -496.727005) (xy 14.141843 -496.798537) (xy 14.172882 -496.873473)
			(xy 14.196427 -496.951089) (xy 14.21225 -497.03064) (xy 14.2202 -497.111359) (xy 14.220698 -497.151914)
			(xy 14.2202 -497.192469) (xy 14.21225 -497.273188) (xy 14.196427 -497.352739) (xy 14.172882 -497.430355)
			(xy 14.141843 -497.505291) (xy 14.103608 -497.576823) (xy 14.058546 -497.644263) (xy 14.007091 -497.706962)
			(xy 13.949738 -497.764315) (xy 13.887039 -497.81577) (xy 13.819599 -497.860832) (xy 13.748067 -497.899067)
			(xy 13.673131 -497.930106) (xy 13.595515 -497.953651) (xy 13.515964 -497.969474) (xy 13.435245 -497.977424)
			(xy 13.354135 -497.977424) (xy 13.273416 -497.969474) (xy 13.193865 -497.953651) (xy 13.116249 -497.930106)
			(xy 13.041313 -497.899067) (xy 12.969781 -497.860832) (xy 12.902341 -497.81577) (xy 12.839642 -497.764315)
			(xy 12.782289 -497.706962) (xy 12.730834 -497.644263) (xy 12.685772 -497.576823) (xy 12.647537 -497.505291)
			(xy 12.616498 -497.430355) (xy 12.592953 -497.352739) (xy 12.57713 -497.273188) (xy 12.56918 -497.192469)
			(xy 11.6802 -497.192469) (xy 11.67225 -497.273188) (xy 11.656427 -497.352739) (xy 11.632882 -497.430355)
			(xy 11.601843 -497.505291) (xy 11.563608 -497.576823) (xy 11.518546 -497.644263) (xy 11.467091 -497.706962)
			(xy 11.409738 -497.764315) (xy 11.347039 -497.81577) (xy 11.279599 -497.860832) (xy 11.208067 -497.899067)
			(xy 11.133131 -497.930106) (xy 11.055515 -497.953651) (xy 10.975964 -497.969474) (xy 10.895245 -497.977424)
			(xy 10.814135 -497.977424) (xy 10.733416 -497.969474) (xy 10.653865 -497.953651) (xy 10.576249 -497.930106)
			(xy 10.501313 -497.899067) (xy 10.429781 -497.860832) (xy 10.362341 -497.81577) (xy 10.299642 -497.764315)
			(xy 10.242289 -497.706962) (xy 10.190834 -497.644263) (xy 10.145772 -497.576823) (xy 10.107537 -497.505291)
			(xy 10.076498 -497.430355) (xy 10.052953 -497.352739) (xy 10.03713 -497.273188) (xy 10.02918 -497.192469)
			(xy 9.1402 -497.192469) (xy 9.13225 -497.273188) (xy 9.116427 -497.352739) (xy 9.092882 -497.430355)
			(xy 9.061843 -497.505291) (xy 9.023608 -497.576823) (xy 8.978546 -497.644263) (xy 8.927091 -497.706962)
			(xy 8.869738 -497.764315) (xy 8.807039 -497.81577) (xy 8.739599 -497.860832) (xy 8.668067 -497.899067)
			(xy 8.593131 -497.930106) (xy 8.515515 -497.953651) (xy 8.435964 -497.969474) (xy 8.355245 -497.977424)
			(xy 8.274135 -497.977424) (xy 8.193416 -497.969474) (xy 8.113865 -497.953651) (xy 8.036249 -497.930106)
			(xy 7.961313 -497.899067) (xy 7.889781 -497.860832) (xy 7.822341 -497.81577) (xy 7.759642 -497.764315)
			(xy 7.702289 -497.706962) (xy 7.650834 -497.644263) (xy 7.605772 -497.576823) (xy 7.567537 -497.505291)
			(xy 7.536498 -497.430355) (xy 7.512953 -497.352739) (xy 7.49713 -497.273188) (xy 7.48918 -497.192469)
			(xy 6.6002 -497.192469) (xy 6.59225 -497.273188) (xy 6.576427 -497.352739) (xy 6.552882 -497.430355)
			(xy 6.521843 -497.505291) (xy 6.483608 -497.576823) (xy 6.438546 -497.644263) (xy 6.387091 -497.706962)
			(xy 6.329738 -497.764315) (xy 6.267039 -497.81577) (xy 6.199599 -497.860832) (xy 6.128067 -497.899067)
			(xy 6.053131 -497.930106) (xy 5.975515 -497.953651) (xy 5.895964 -497.969474) (xy 5.815245 -497.977424)
			(xy 5.734135 -497.977424) (xy 5.653416 -497.969474) (xy 5.573865 -497.953651) (xy 5.496249 -497.930106)
			(xy 5.421313 -497.899067) (xy 5.349781 -497.860832) (xy 5.282341 -497.81577) (xy 5.219642 -497.764315)
			(xy 5.162289 -497.706962) (xy 5.110834 -497.644263) (xy 5.065772 -497.576823) (xy 5.027537 -497.505291)
			(xy 4.996498 -497.430355) (xy 4.972953 -497.352739) (xy 4.95713 -497.273188) (xy 4.94918 -497.192469)
			(xy 1.27 -497.192469) (xy 1.27 -506.498098) (xy 79.39024 -506.498098) (xy 79.39024 -505.309378) (xy 79.390919 -505.273311)
			(xy 79.40125 -505.20192) (xy 79.410814 -505.167138) (xy 79.41564 -505.149612) (xy 79.41564 -504.775724)
			(xy 80.381856 -504.775724) (xy 80.381856 -505.149612) (xy 80.386682 -505.167138) (xy 80.396226 -505.201924)
			(xy 80.406552 -505.273313) (xy 80.407256 -505.309378) (xy 80.407256 -505.51461) (xy 80.783176 -505.51461)
			(xy 80.783176 -504.705874) (xy 80.783661 -504.673147) (xy 80.792059 -504.608234) (xy 80.808713 -504.544935)
			(xy 80.833348 -504.484294) (xy 80.865556 -504.427313) (xy 80.884776 -504.40082) (xy 80.910176 -504.367038)
			(xy 80.910176 -504.35002) (xy 80.925416 -504.35002) (xy 80.96123 -504.31954) (xy 80.986407 -504.298687)
			(xy 81.041139 -504.262936) (xy 81.100004 -504.234497) (xy 81.162029 -504.213842) (xy 81.226191 -504.201311)
			(xy 81.29143 -504.197111) (xy 81.356669 -504.201311) (xy 81.420831 -504.213842) (xy 81.482856 -504.234497)
			(xy 81.541721 -504.262936) (xy 81.596453 -504.298687) (xy 81.62163 -504.31954) (xy 81.657444 -504.35002)
			(xy 81.672684 -504.35002) (xy 81.672684 -504.367038) (xy 81.698084 -504.40082) (xy 81.714513 -504.423362)
			(xy 81.742882 -504.47139) (xy 81.765818 -504.522238) (xy 81.774792 -504.548648) (xy 81.780158 -504.56374)
			(xy 81.797289 -504.590795) (xy 81.820616 -504.612734) (xy 81.84867 -504.628175) (xy 81.879685 -504.636146)
			(xy 81.911707 -504.636146) (xy 81.942722 -504.628175) (xy 81.970776 -504.612734) (xy 81.994103 -504.590795)
			(xy 82.011234 -504.56374) (xy 82.0166 -504.548648) (xy 82.025572 -504.522237) (xy 82.048514 -504.471393)
			(xy 82.076883 -504.423364) (xy 82.093308 -504.40082) (xy 82.118708 -504.367038) (xy 82.118708 -504.35002)
			(xy 82.133948 -504.35002) (xy 82.169762 -504.31954) (xy 82.194939 -504.298687) (xy 82.249671 -504.262936)
			(xy 82.308536 -504.234497) (xy 82.370561 -504.213842) (xy 82.434723 -504.201311) (xy 82.499962 -504.197111)
			(xy 82.565201 -504.201311) (xy 82.629363 -504.213842) (xy 82.691388 -504.234497) (xy 82.750253 -504.262936)
			(xy 82.804985 -504.298687) (xy 82.830162 -504.31954) (xy 82.865976 -504.35002) (xy 82.881216 -504.35002)
			(xy 82.881216 -504.367038) (xy 82.906616 -504.40082) (xy 82.925875 -504.427288) (xy 82.958097 -504.484266)
			(xy 82.982731 -504.544913) (xy 82.999367 -504.608222) (xy 83.00773 -504.673144) (xy 83.008216 -504.705874)
			(xy 83.008216 -505.529088) (xy 83.007656 -505.560842) (xy 82.999758 -505.623858) (xy 82.984069 -505.685398)
			(xy 82.960836 -505.744504) (xy 82.930419 -505.800255) (xy 82.893294 -505.851782) (xy 82.850038 -505.898282)
			(xy 82.801325 -505.93903) (xy 82.747915 -505.973392) (xy 82.69064 -506.000831) (xy 82.630393 -506.020921)
			(xy 82.568112 -506.033348) (xy 82.504768 -506.037918) (xy 82.441349 -506.034561) (xy 82.378842 -506.023328)
			(xy 82.318221 -506.004395) (xy 82.260431 -505.978057) (xy 82.206374 -505.944724) (xy 82.15689 -505.904915)
			(xy 82.112752 -505.859252) (xy 82.093308 -505.834142) (xy 82.078982 -505.81581) (xy 82.044749 -505.784307)
			(xy 82.005354 -505.759559) (xy 81.962114 -505.742394) (xy 81.916472 -505.733385) (xy 81.869952 -505.732832)
			(xy 81.824109 -505.740754) (xy 81.780473 -505.756887) (xy 81.740502 -505.780691) (xy 81.705529 -505.811372)
			(xy 81.690718 -505.829316) (xy 81.670807 -505.853662) (xy 81.626068 -505.897865) (xy 81.576218 -505.936211)
			(xy 81.522018 -505.968114) (xy 81.464296 -505.993087) (xy 81.403934 -506.010749) (xy 81.341855 -506.020829)
			(xy 81.279006 -506.023173) (xy 81.216348 -506.017746) (xy 81.154838 -506.004631) (xy 81.095416 -505.984027)
			(xy 81.03899 -505.95625) (xy 80.986422 -505.921724) (xy 80.938514 -505.880977) (xy 80.896 -505.834631)
			(xy 80.859527 -505.783394) (xy 80.829655 -505.728049) (xy 80.806838 -505.669441) (xy 80.791425 -505.608467)
			(xy 80.783653 -505.546056) (xy 80.783176 -505.51461) (xy 80.407256 -505.51461) (xy 80.407256 -506.498098)
			(xy 80.406754 -506.530059) (xy 80.398743 -506.593477) (xy 80.382846 -506.655391) (xy 80.359314 -506.714824)
			(xy 80.32852 -506.770839) (xy 80.290947 -506.822554) (xy 80.24719 -506.869151) (xy 80.197937 -506.909896)
			(xy 80.143966 -506.944147) (xy 80.086127 -506.971364) (xy 80.025334 -506.991117) (xy 79.962544 -507.003095)
			(xy 79.898748 -507.007109) (xy 79.834952 -507.003095) (xy 79.772162 -506.991117) (xy 79.711369 -506.971364)
			(xy 79.65353 -506.944147) (xy 79.599559 -506.909896) (xy 79.550306 -506.869151) (xy 79.506549 -506.822554)
			(xy 79.468976 -506.770839) (xy 79.438182 -506.714824) (xy 79.41465 -506.655391) (xy 79.398753 -506.593477)
			(xy 79.390742 -506.530059) (xy 79.39024 -506.498098) (xy 1.27 -506.498098) (xy 1.27 -507.717975)
			(xy 47.97424 -507.717975) (xy 47.97424 -507.636865) (xy 47.98219 -507.556146) (xy 47.998013 -507.476595)
			(xy 48.021558 -507.398979) (xy 48.052597 -507.324043) (xy 48.090832 -507.252511) (xy 48.135894 -507.185071)
			(xy 48.187349 -507.122372) (xy 48.244702 -507.065019) (xy 48.307401 -507.013564) (xy 48.374841 -506.968502)
			(xy 48.446373 -506.930267) (xy 48.521309 -506.899228) (xy 48.598925 -506.875683) (xy 48.678476 -506.85986)
			(xy 48.759195 -506.85191) (xy 48.840305 -506.85191) (xy 48.921024 -506.85986) (xy 49.000575 -506.875683)
			(xy 49.078191 -506.899228) (xy 49.153127 -506.930267) (xy 49.224659 -506.968502) (xy 49.292099 -507.013564)
			(xy 49.354798 -507.065019) (xy 49.412151 -507.122372) (xy 49.463606 -507.185071) (xy 49.508668 -507.252511)
			(xy 49.546903 -507.324043) (xy 49.577942 -507.398979) (xy 49.601487 -507.476595) (xy 49.61731 -507.556146)
			(xy 49.62526 -507.636865) (xy 49.625758 -507.67742) (xy 49.62526 -507.717975) (xy 49.61731 -507.798694)
			(xy 49.601487 -507.878245) (xy 49.577942 -507.955861) (xy 49.546903 -508.030797) (xy 49.508668 -508.102329)
			(xy 49.463606 -508.169769) (xy 49.412151 -508.232468) (xy 49.354798 -508.289821) (xy 49.292099 -508.341276)
			(xy 49.224659 -508.386338) (xy 49.153127 -508.424573) (xy 49.078191 -508.455612) (xy 49.000575 -508.479157)
			(xy 48.921024 -508.49498) (xy 48.840305 -508.50293) (xy 48.759195 -508.50293) (xy 48.678476 -508.49498)
			(xy 48.598925 -508.479157) (xy 48.521309 -508.455612) (xy 48.446373 -508.424573) (xy 48.374841 -508.386338)
			(xy 48.307401 -508.341276) (xy 48.244702 -508.289821) (xy 48.187349 -508.232468) (xy 48.135894 -508.169769)
			(xy 48.090832 -508.102329) (xy 48.052597 -508.030797) (xy 48.021558 -507.955861) (xy 47.998013 -507.878245)
			(xy 47.98219 -507.798694) (xy 47.97424 -507.717975) (xy 1.27 -507.717975) (xy 1.27 -508.96012) (xy 86.39887 -508.96012)
			(xy 86.402874 -508.760022) (xy 86.414881 -508.560244) (xy 86.434872 -508.361107) (xy 86.462814 -508.162929)
			(xy 86.498662 -507.966027) (xy 86.54236 -507.770718) (xy 86.593837 -507.577313) (xy 86.653011 -507.386123)
			(xy 86.719787 -507.197453) (xy 86.794059 -507.011606) (xy 86.875706 -506.828879) (xy 86.964599 -506.649566)
			(xy 87.060595 -506.473952) (xy 87.16354 -506.30232) (xy 87.27327 -506.134944) (xy 87.389608 -505.972093)
			(xy 87.512369 -505.814026) (xy 87.641356 -505.660998) (xy 87.776363 -505.513253) (xy 87.917172 -505.371027)
			(xy 88.063559 -505.23455) (xy 88.215289 -505.104038) (xy 88.37212 -504.979702) (xy 88.533799 -504.86174)
			(xy 88.700069 -504.750341) (xy 88.870662 -504.645684) (xy 89.045306 -504.547936) (xy 89.223722 -504.457253)
			(xy 89.405622 -504.373782) (xy 89.590717 -504.297655) (xy 89.778709 -504.228995) (xy 89.969298 -504.167911)
			(xy 90.162178 -504.114501) (xy 90.35704 -504.068852) (xy 90.553573 -504.031035) (xy 90.751462 -504.001111)
			(xy 90.950389 -503.979129) (xy 91.150037 -503.965124) (xy 91.350085 -503.959118) (xy 91.550213 -503.96112)
			(xy 91.750101 -503.971128) (xy 91.949428 -503.989125) (xy 92.147876 -504.015083) (xy 92.345126 -504.04896)
			(xy 92.540863 -504.090702) (xy 92.734773 -504.140241) (xy 92.926546 -504.197499) (xy 93.115875 -504.262384)
			(xy 93.302455 -504.334792) (xy 93.48599 -504.414608) (xy 93.666184 -504.501702) (xy 93.842749 -504.595936)
			(xy 94.015402 -504.697159) (xy 94.183867 -504.805209) (xy 94.347875 -504.919912) (xy 94.507162 -505.041086)
			(xy 94.661473 -505.168535) (xy 94.810561 -505.302056) (xy 94.954188 -505.441436) (xy 95.092124 -505.58645)
			(xy 95.224147 -505.736867) (xy 95.350046 -505.892445) (xy 95.367266 -505.915557) (xy 96.320598 -505.915557)
			(xy 96.320598 -505.802003) (xy 96.328519 -505.688727) (xy 96.344322 -505.576279) (xy 96.367931 -505.465208)
			(xy 96.399231 -505.356053) (xy 96.438068 -505.249348) (xy 96.484254 -505.145613) (xy 96.537564 -505.045351)
			(xy 96.597738 -504.949053) (xy 96.664483 -504.857187) (xy 96.737473 -504.7702) (xy 96.816354 -504.688517)
			(xy 96.90074 -504.612535) (xy 96.990221 -504.542625) (xy 97.084361 -504.479127) (xy 97.182701 -504.42235)
			(xy 97.284761 -504.372572) (xy 97.390046 -504.330034) (xy 97.498041 -504.294944) (xy 97.608221 -504.267473)
			(xy 97.720049 -504.247755) (xy 97.83298 -504.235885) (xy 97.946464 -504.231923) (xy 98.059948 -504.235885)
			(xy 98.172879 -504.247755) (xy 98.284707 -504.267473) (xy 98.394887 -504.294944) (xy 98.502882 -504.330034)
			(xy 98.608167 -504.372572) (xy 98.710227 -504.42235) (xy 98.808567 -504.479127) (xy 98.902707 -504.542625)
			(xy 98.992188 -504.612535) (xy 99.076574 -504.688517) (xy 99.155455 -504.7702) (xy 99.228445 -504.857187)
			(xy 99.29519 -504.949053) (xy 99.355364 -505.045351) (xy 99.408674 -505.145613) (xy 99.45486 -505.249348)
			(xy 99.493697 -505.356053) (xy 99.524997 -505.465208) (xy 99.548606 -505.576279) (xy 99.564409 -505.688727)
			(xy 99.57233 -505.802003) (xy 99.572826 -505.85878) (xy 99.57233 -505.915557) (xy 99.564409 -506.028833)
			(xy 99.548606 -506.141281) (xy 99.524997 -506.252352) (xy 99.493697 -506.361507) (xy 99.45486 -506.468212)
			(xy 99.408674 -506.571947) (xy 99.355364 -506.672209) (xy 99.29519 -506.768507) (xy 99.228445 -506.860373)
			(xy 99.155455 -506.94736) (xy 99.076574 -507.029043) (xy 98.992188 -507.105025) (xy 98.902707 -507.174935)
			(xy 98.808567 -507.238433) (xy 98.710227 -507.29521) (xy 98.608167 -507.344988) (xy 98.502882 -507.387526)
			(xy 98.394887 -507.422616) (xy 98.284707 -507.450087) (xy 98.172879 -507.469805) (xy 98.059948 -507.481675)
			(xy 97.946464 -507.485638) (xy 97.83298 -507.481675) (xy 97.720049 -507.469805) (xy 97.608221 -507.450087)
			(xy 97.498041 -507.422616) (xy 97.390046 -507.387526) (xy 97.284761 -507.344988) (xy 97.182701 -507.29521)
			(xy 97.084361 -507.238433) (xy 96.990221 -507.174935) (xy 96.90074 -507.105025) (xy 96.816354 -507.029043)
			(xy 96.737473 -506.94736) (xy 96.664483 -506.860373) (xy 96.597738 -506.768507) (xy 96.537564 -506.672209)
			(xy 96.484254 -506.571947) (xy 96.438068 -506.468212) (xy 96.399231 -506.361507) (xy 96.367931 -506.252352)
			(xy 96.344322 -506.141281) (xy 96.328519 -506.028833) (xy 96.320598 -505.915557) (xy 95.367266 -505.915557)
			(xy 95.46962 -506.052937) (xy 95.582676 -506.218083) (xy 95.689035 -506.387621) (xy 95.788526 -506.561279)
			(xy 95.880989 -506.738778) (xy 95.966276 -506.919834) (xy 96.044251 -507.104158) (xy 96.114788 -507.291454)
			(xy 96.177776 -507.481422) (xy 96.233113 -507.673758) (xy 96.28071 -507.868154) (xy 96.320491 -508.064299)
			(xy 96.352393 -508.261878) (xy 96.376364 -508.460575) (xy 96.392366 -508.660073) (xy 96.400373 -508.860051)
			(xy 96.400874 -508.96012) (xy 96.400373 -509.060189) (xy 96.392366 -509.260167) (xy 96.376364 -509.459665)
			(xy 96.352393 -509.658362) (xy 96.320491 -509.855941) (xy 96.28071 -510.052086) (xy 96.233113 -510.246482)
			(xy 96.177776 -510.438818) (xy 96.114788 -510.628786) (xy 96.044251 -510.816082) (xy 95.966276 -511.000406)
			(xy 95.880989 -511.181462) (xy 95.788526 -511.358961) (xy 95.689035 -511.532619) (xy 95.582676 -511.702157)
			(xy 95.46962 -511.867303) (xy 95.350046 -512.027795) (xy 95.224147 -512.183373) (xy 95.092124 -512.33379)
			(xy 94.954188 -512.478804) (xy 94.810561 -512.618184) (xy 94.661473 -512.751705) (xy 94.507162 -512.879154)
			(xy 94.347875 -513.000328) (xy 94.183867 -513.115031) (xy 94.015402 -513.223081) (xy 93.842749 -513.324304)
			(xy 93.666184 -513.418538) (xy 93.48599 -513.505632) (xy 93.302455 -513.585448) (xy 93.115875 -513.657856)
			(xy 92.926546 -513.722741) (xy 92.734773 -513.779999) (xy 92.540863 -513.829538) (xy 92.345126 -513.87128)
			(xy 92.147876 -513.905157) (xy 91.949428 -513.931115) (xy 91.750101 -513.949112) (xy 91.550213 -513.95912)
			(xy 91.350085 -513.961122) (xy 91.150037 -513.955116) (xy 90.950389 -513.941111) (xy 90.751462 -513.919129)
			(xy 90.553573 -513.889205) (xy 90.35704 -513.851388) (xy 90.162178 -513.805739) (xy 89.969298 -513.752329)
			(xy 89.778709 -513.691245) (xy 89.590717 -513.622585) (xy 89.405622 -513.546458) (xy 89.223722 -513.462987)
			(xy 89.045306 -513.372304) (xy 88.870662 -513.274556) (xy 88.700069 -513.169899) (xy 88.533799 -513.0585)
			(xy 88.37212 -512.940538) (xy 88.215289 -512.816202) (xy 88.063559 -512.68569) (xy 87.917172 -512.549213)
			(xy 87.776363 -512.406987) (xy 87.641356 -512.259242) (xy 87.512369 -512.106214) (xy 87.389608 -511.948147)
			(xy 87.27327 -511.785296) (xy 87.16354 -511.61792) (xy 87.060595 -511.446288) (xy 86.964599 -511.270674)
			(xy 86.875706 -511.091361) (xy 86.794059 -510.908634) (xy 86.719787 -510.722787) (xy 86.653011 -510.534117)
			(xy 86.593837 -510.342927) (xy 86.54236 -510.149522) (xy 86.498662 -509.954213) (xy 86.462814 -509.757311)
			(xy 86.434872 -509.559133) (xy 86.414881 -509.359996) (xy 86.402874 -509.160218) (xy 86.39887 -508.96012)
			(xy 1.27 -508.96012) (xy 1.27 -513.179314) (xy 1.270551 -513.202676) (xy 1.279134 -513.248607) (xy 1.29597 -513.292194)
			(xy 1.320492 -513.331969) (xy 1.351871 -513.36659) (xy 1.389052 -513.39489) (xy 1.430779 -513.415916)
			(xy 1.475648 -513.428958) (xy 1.522145 -513.433578) (xy 1.568703 -513.429618) (xy 1.613752 -513.417214)
			(xy 1.655774 -513.396782) (xy 1.693352 -513.369012) (xy 1.709674 -513.352288) (xy 1.754144 -513.305252)
			(xy 1.848064 -513.216155) (xy 1.947334 -513.133062) (xy 2.051571 -513.056293) (xy 2.160374 -512.986144)
			(xy 2.273323 -512.922886) (xy 2.389982 -512.866763) (xy 2.5099 -512.817992) (xy 2.632615 -512.77676)
			(xy 2.757653 -512.743227) (xy 2.884532 -512.717522) (xy 3.012762 -512.699745) (xy 3.141848 -512.689963)
			(xy 3.271293 -512.688216) (xy 3.400597 -512.694509) (xy 3.52926 -512.708818) (xy 3.656786 -512.731088)
			(xy 3.782684 -512.761233) (xy 3.906468 -512.799137) (xy 4.027658 -512.844653) (xy 4.14579 -512.897607)
			(xy 4.260405 -512.957792) (xy 4.371062 -513.024979) (xy 4.477334 -513.098906) (xy 4.578812 -513.179288)
			(xy 4.675102 -513.265817) (xy 4.765834 -513.358157) (xy 4.850658 -513.455952) (xy 4.929246 -513.558825)
			(xy 5.001295 -513.66638) (xy 5.066527 -513.7782) (xy 5.124691 -513.893855) (xy 5.175561 -514.012898)
			(xy 5.218942 -514.134869) (xy 5.254666 -514.259299) (xy 5.282595 -514.385707) (xy 5.302622 -514.513605)
			(xy 5.314669 -514.6425) (xy 5.31869 -514.771894) (xy 12.580624 -514.771894) (xy 12.584655 -514.642328)
			(xy 12.596734 -514.513264) (xy 12.616813 -514.3852) (xy 12.644815 -514.258633) (xy 12.680632 -514.13405)
			(xy 12.724124 -514.011936) (xy 12.775124 -513.892762) (xy 12.833435 -513.776989) (xy 12.89883 -513.665065)
			(xy 12.971057 -513.557423) (xy 13.049837 -513.45448) (xy 13.134864 -513.356634) (xy 13.225809 -513.264262)
			(xy 13.322321 -513.177724) (xy 13.424027 -513.097353) (xy 13.530533 -513.023461) (xy 13.641426 -512.956333)
			(xy 13.756278 -512.896229) (xy 13.874645 -512.843382) (xy 13.996068 -512.797995) (xy 14.120078 -512.760246)
			(xy 14.246195 -512.730279) (xy 14.373931 -512.70821) (xy 14.502792 -512.694126) (xy 14.632279 -512.68808)
			(xy 14.761892 -512.690096) (xy 14.891128 -512.700166) (xy 15.019489 -512.718251) (xy 15.146477 -512.744281)
			(xy 15.271601 -512.778156) (xy 15.394377 -512.819744) (xy 15.51433 -512.868885) (xy 15.630995 -512.925388)
			(xy 15.743923 -512.989035) (xy 15.852675 -513.059579) (xy 15.956831 -513.136748) (xy 16.055988 -513.220243)
			(xy 16.149762 -513.309741) (xy 16.237791 -513.404896) (xy 16.319734 -513.505339) (xy 16.395273 -513.610682)
			(xy 16.464118 -513.720518) (xy 16.526001 -513.834422) (xy 16.580682 -513.951952) (xy 16.627952 -514.072655)
			(xy 16.667625 -514.196063) (xy 16.69955 -514.321699) (xy 16.723602 -514.449076) (xy 16.739689 -514.577702)
			(xy 16.747748 -514.70708) (xy 16.748252 -514.771894) (xy 16.747748 -514.836708) (xy 16.739689 -514.966086)
			(xy 16.723602 -515.094712) (xy 16.69955 -515.222089) (xy 16.667625 -515.347725) (xy 16.627952 -515.471133)
			(xy 16.580682 -515.591836) (xy 16.526001 -515.709366) (xy 16.464118 -515.82327) (xy 16.395273 -515.933106)
			(xy 16.319734 -516.038449) (xy 16.237791 -516.138892) (xy 16.149762 -516.234047) (xy 16.055988 -516.323545)
			(xy 15.956831 -516.40704) (xy 15.852675 -516.484209) (xy 15.743923 -516.554753) (xy 15.630995 -516.6184)
			(xy 15.51433 -516.674903) (xy 15.394377 -516.724044) (xy 15.271601 -516.765632) (xy 15.146477 -516.799507)
			(xy 15.019489 -516.825537) (xy 14.891128 -516.843622) (xy 14.761892 -516.853692) (xy 14.632279 -516.855708)
			(xy 14.502792 -516.849662) (xy 14.373931 -516.835578) (xy 14.246195 -516.813509) (xy 14.120078 -516.783542)
			(xy 13.996068 -516.745793) (xy 13.874645 -516.700406) (xy 13.756278 -516.647559) (xy 13.641426 -516.587455)
			(xy 13.530533 -516.520327) (xy 13.424027 -516.446435) (xy 13.322321 -516.366064) (xy 13.225809 -516.279526)
			(xy 13.134864 -516.187154) (xy 13.049837 -516.089308) (xy 12.971057 -515.986365) (xy 12.89883 -515.878723)
			(xy 12.833435 -515.766799) (xy 12.775124 -515.651026) (xy 12.724124 -515.531852) (xy 12.680632 -515.409738)
			(xy 12.644815 -515.285155) (xy 12.616813 -515.158588) (xy 12.596734 -515.030524) (xy 12.584655 -514.90146)
			(xy 12.580624 -514.771894) (xy 5.31869 -514.771894) (xy 5.314669 -514.901288) (xy 5.302622 -515.030183)
			(xy 5.282595 -515.158081) (xy 5.254666 -515.284489) (xy 5.218942 -515.408919) (xy 5.175561 -515.53089)
			(xy 5.124691 -515.649933) (xy 5.066527 -515.765588) (xy 5.001295 -515.877408) (xy 4.929246 -515.984963)
			(xy 4.850658 -516.087836) (xy 4.765834 -516.185631) (xy 4.675102 -516.277971) (xy 4.578812 -516.3645)
			(xy 4.477334 -516.444882) (xy 4.371062 -516.518809) (xy 4.260405 -516.585996) (xy 4.14579 -516.646181)
			(xy 4.027658 -516.699135) (xy 3.906468 -516.744651) (xy 3.782684 -516.782555) (xy 3.656786 -516.8127)
			(xy 3.52926 -516.83497) (xy 3.400597 -516.849279) (xy 3.271293 -516.855572) (xy 3.141848 -516.853825)
			(xy 3.012762 -516.844043) (xy 2.884532 -516.826266) (xy 2.757653 -516.800561) (xy 2.632615 -516.767028)
			(xy 2.5099 -516.725796) (xy 2.389982 -516.677025) (xy 2.273323 -516.620902) (xy 2.160374 -516.557644)
			(xy 2.051571 -516.487495) (xy 1.947334 -516.410726) (xy 1.848064 -516.327633) (xy 1.754144 -516.238536)
			(xy 1.709674 -516.1915) (xy 1.693349 -516.174784) (xy 1.655769 -516.147031) (xy 1.613749 -516.126614)
			(xy 1.568705 -516.11422) (xy 1.522155 -516.110268) (xy 1.475666 -516.114891) (xy 1.430806 -516.127933)
			(xy 1.389085 -516.148954) (xy 1.351908 -516.177247) (xy 1.320529 -516.211857) (xy 1.296005 -516.25162)
			(xy 1.279161 -516.295196) (xy 1.270565 -516.341116) (xy 1.27 -516.364474) (xy 1.27 -519.061107) (xy 47.82311 -519.061107)
			(xy 47.82311 -518.979997) (xy 47.83106 -518.899278) (xy 47.846883 -518.819727) (xy 47.870428 -518.742111)
			(xy 47.901467 -518.667175) (xy 47.939702 -518.595643) (xy 47.984764 -518.528203) (xy 48.036219 -518.465504)
			(xy 48.093572 -518.408151) (xy 48.156271 -518.356696) (xy 48.223711 -518.311634) (xy 48.295243 -518.273399)
			(xy 48.370179 -518.24236) (xy 48.447795 -518.218815) (xy 48.527346 -518.202992) (xy 48.608065 -518.195042)
			(xy 48.689175 -518.195042) (xy 48.769894 -518.202992) (xy 48.849445 -518.218815) (xy 48.927061 -518.24236)
			(xy 49.001997 -518.273399) (xy 49.073529 -518.311634) (xy 49.140969 -518.356696) (xy 49.203668 -518.408151)
			(xy 49.261021 -518.465504) (xy 49.312476 -518.528203) (xy 49.357538 -518.595643) (xy 49.395773 -518.667175)
			(xy 49.426812 -518.742111) (xy 49.450357 -518.819727) (xy 49.46618 -518.899278) (xy 49.47413 -518.979997)
			(xy 49.474628 -519.020552) (xy 49.474269 -519.049762) (xy 69.997838 -519.049762) (xy 70.001826 -518.797142)
			(xy 70.013787 -518.544774) (xy 70.033709 -518.29291) (xy 70.061573 -518.0418) (xy 70.097349 -517.791694)
			(xy 70.141003 -517.542843) (xy 70.192492 -517.295494) (xy 70.251763 -517.049893) (xy 70.318758 -516.806286)
			(xy 70.393409 -516.564916) (xy 70.475644 -516.326022) (xy 70.565378 -516.089844) (xy 70.662524 -515.856616)
			(xy 70.766984 -515.62657) (xy 70.878655 -515.399938) (xy 70.997424 -515.176943) (xy 71.123173 -514.957809)
			(xy 71.255778 -514.742754) (xy 71.395105 -514.531992) (xy 71.541017 -514.325734) (xy 71.693367 -514.124185)
			(xy 71.852003 -513.927545) (xy 72.016768 -513.736012) (xy 72.187498 -513.549775) (xy 72.364022 -513.369021)
			(xy 72.546164 -513.19393) (xy 72.733742 -513.024676) (xy 72.92657 -512.861427) (xy 73.124455 -512.704348)
			(xy 73.327201 -512.553593) (xy 73.534605 -512.409315) (xy 73.74646 -512.271655) (xy 73.962555 -512.140752)
			(xy 74.182675 -512.016736) (xy 74.4066 -511.899731) (xy 74.634107 -511.789853) (xy 74.864969 -511.687212)
			(xy 75.098957 -511.59191) (xy 75.335836 -511.504043) (xy 75.575372 -511.423696) (xy 75.817324 -511.350952)
			(xy 76.061452 -511.285882) (xy 76.307513 -511.228552) (xy 76.555261 -511.179018) (xy 76.804449 -511.137329)
			(xy 77.054829 -511.103528) (xy 77.306151 -511.077647) (xy 77.558165 -511.059714) (xy 77.810619 -511.049745)
			(xy 78.063263 -511.047751) (xy 78.315843 -511.053733) (xy 78.568109 -511.067686) (xy 78.819808 -511.089596)
			(xy 79.070691 -511.11944) (xy 79.320506 -511.15719) (xy 79.569005 -511.202807) (xy 79.81594 -511.256246)
			(xy 80.061065 -511.317454) (xy 80.304135 -511.386369) (xy 80.544909 -511.462924) (xy 80.783146 -511.547041)
			(xy 81.018609 -511.638638) (xy 81.251063 -511.737622) (xy 81.480277 -511.843894) (xy 81.706021 -511.95735)
			(xy 81.928071 -512.077875) (xy 82.146205 -512.205351) (xy 82.360207 -512.339649) (xy 82.569863 -512.480635)
			(xy 82.774963 -512.62817) (xy 82.975303 -512.782106) (xy 83.170684 -512.94229) (xy 83.360911 -513.108562)
			(xy 83.545794 -513.280757) (xy 83.72515 -513.458701) (xy 83.898798 -513.64222) (xy 84.066566 -513.831128)
			(xy 84.228287 -514.025239) (xy 84.3838 -514.224358) (xy 84.532949 -514.428287) (xy 84.675586 -514.636823)
			(xy 84.811569 -514.849758) (xy 84.940762 -515.06688) (xy 85.063037 -515.287972) (xy 85.178271 -515.512813)
			(xy 85.28635 -515.741181) (xy 85.387165 -515.972846) (xy 85.480617 -516.207579) (xy 85.566612 -516.445144)
			(xy 85.645065 -516.685306) (xy 85.715897 -516.927825) (xy 85.779038 -517.17246) (xy 85.834425 -517.418965)
			(xy 85.882002 -517.667096) (xy 85.921722 -517.916606) (xy 85.953546 -518.167245) (xy 85.977442 -518.418763)
			(xy 85.993386 -518.670911) (xy 86.001361 -518.923436) (xy 86.00186 -519.049762) (xy 86.001361 -519.176088)
			(xy 85.993386 -519.428613) (xy 85.977442 -519.680761) (xy 85.953546 -519.932279) (xy 85.921722 -520.182918)
			(xy 85.882002 -520.432428) (xy 85.834425 -520.680559) (xy 85.779038 -520.927064) (xy 85.715897 -521.171699)
			(xy 85.645065 -521.414218) (xy 85.566612 -521.65438) (xy 85.480617 -521.891945) (xy 85.387165 -522.126678)
			(xy 85.28635 -522.358343) (xy 85.178271 -522.586711) (xy 85.063037 -522.811552) (xy 84.940762 -523.032644)
			(xy 84.811569 -523.249766) (xy 84.675586 -523.462701) (xy 84.532949 -523.671237) (xy 84.3838 -523.875166)
			(xy 84.228287 -524.074285) (xy 84.066566 -524.268396) (xy 83.898798 -524.457304) (xy 83.72515 -524.640823)
			(xy 83.545794 -524.818767) (xy 83.360911 -524.990962) (xy 83.170684 -525.157234) (xy 82.975303 -525.317418)
			(xy 82.774963 -525.471354) (xy 82.569863 -525.618889) (xy 82.360207 -525.759875) (xy 82.146205 -525.894173)
			(xy 81.928071 -526.021649) (xy 81.706021 -526.142174) (xy 81.480277 -526.25563) (xy 81.251063 -526.361902)
			(xy 81.018609 -526.460886) (xy 80.783146 -526.552483) (xy 80.544909 -526.6366) (xy 80.304135 -526.713155)
			(xy 80.061065 -526.78207) (xy 79.81594 -526.843278) (xy 79.569005 -526.896717) (xy 79.320506 -526.942334)
			(xy 79.070691 -526.980084) (xy 78.819808 -527.009928) (xy 78.568109 -527.031838) (xy 78.315843 -527.045791)
			(xy 78.063263 -527.051773) (xy 77.810619 -527.049779) (xy 77.558165 -527.03981) (xy 77.306151 -527.021877)
			(xy 77.054829 -526.995996) (xy 76.804449 -526.962195) (xy 76.555261 -526.920506) (xy 76.307513 -526.870972)
			(xy 76.061452 -526.813642) (xy 75.817324 -526.748572) (xy 75.575372 -526.675828) (xy 75.335836 -526.595481)
			(xy 75.098957 -526.507614) (xy 74.864969 -526.412312) (xy 74.634107 -526.309671) (xy 74.4066 -526.199793)
			(xy 74.182675 -526.082788) (xy 73.962555 -525.958772) (xy 73.74646 -525.827869) (xy 73.534605 -525.690209)
			(xy 73.327201 -525.545931) (xy 73.124455 -525.395176) (xy 72.92657 -525.238097) (xy 72.733742 -525.074848)
			(xy 72.546164 -524.905594) (xy 72.364022 -524.730503) (xy 72.187498 -524.549749) (xy 72.016768 -524.363512)
			(xy 71.852003 -524.171979) (xy 71.693367 -523.975339) (xy 71.541017 -523.77379) (xy 71.395105 -523.567532)
			(xy 71.255778 -523.35677) (xy 71.123173 -523.141715) (xy 70.997424 -522.922581) (xy 70.878655 -522.699586)
			(xy 70.766984 -522.472954) (xy 70.662524 -522.242908) (xy 70.565378 -522.00968) (xy 70.475644 -521.773502)
			(xy 70.393409 -521.534608) (xy 70.318758 -521.293238) (xy 70.251763 -521.049631) (xy 70.192492 -520.80403)
			(xy 70.141003 -520.556681) (xy 70.097349 -520.30783) (xy 70.061573 -520.057724) (xy 70.033709 -519.806614)
			(xy 70.013787 -519.55475) (xy 70.001826 -519.302382) (xy 69.997838 -519.049762) (xy 49.474269 -519.049762)
			(xy 49.47413 -519.061107) (xy 49.46618 -519.141826) (xy 49.450357 -519.221377) (xy 49.426812 -519.298993)
			(xy 49.395773 -519.373929) (xy 49.357538 -519.445461) (xy 49.312476 -519.512901) (xy 49.261021 -519.5756)
			(xy 49.203668 -519.632953) (xy 49.140969 -519.684408) (xy 49.073529 -519.72947) (xy 49.001997 -519.767705)
			(xy 48.927061 -519.798744) (xy 48.849445 -519.822289) (xy 48.769894 -519.838112) (xy 48.689175 -519.846062)
			(xy 48.608065 -519.846062) (xy 48.527346 -519.838112) (xy 48.447795 -519.822289) (xy 48.370179 -519.798744)
			(xy 48.295243 -519.767705) (xy 48.223711 -519.72947) (xy 48.156271 -519.684408) (xy 48.093572 -519.632953)
			(xy 48.036219 -519.5756) (xy 47.984764 -519.512901) (xy 47.939702 -519.445461) (xy 47.901467 -519.373929)
			(xy 47.870428 -519.298993) (xy 47.846883 -519.221377) (xy 47.83106 -519.141826) (xy 47.82311 -519.061107)
			(xy 1.27 -519.061107) (xy 1.27 -520.29614) (xy 3.678936 -520.29614) (xy 5.330444 -520.29614) (xy 5.330444 -521.162449)
			(xy 6.21918 -521.162449) (xy 6.21918 -521.081339) (xy 6.22713 -521.00062) (xy 6.242953 -520.921069)
			(xy 6.266498 -520.843453) (xy 6.297537 -520.768517) (xy 6.335772 -520.696985) (xy 6.380834 -520.629545)
			(xy 6.432289 -520.566846) (xy 6.489642 -520.509493) (xy 6.552341 -520.458038) (xy 6.619781 -520.412976)
			(xy 6.691313 -520.374741) (xy 6.766249 -520.343702) (xy 6.843865 -520.320157) (xy 6.923416 -520.304334)
			(xy 7.004135 -520.296384) (xy 7.085245 -520.296384) (xy 7.165964 -520.304334) (xy 7.245515 -520.320157)
			(xy 7.323131 -520.343702) (xy 7.398067 -520.374741) (xy 7.469599 -520.412976) (xy 7.537039 -520.458038)
			(xy 7.599738 -520.509493) (xy 7.657091 -520.566846) (xy 7.708546 -520.629545) (xy 7.753608 -520.696985)
			(xy 7.791843 -520.768517) (xy 7.822882 -520.843453) (xy 7.846427 -520.921069) (xy 7.86225 -521.00062)
			(xy 7.8702 -521.081339) (xy 7.870698 -521.121894) (xy 7.8702 -521.162449) (xy 8.75918 -521.162449)
			(xy 8.75918 -521.081339) (xy 8.76713 -521.00062) (xy 8.782953 -520.921069) (xy 8.806498 -520.843453)
			(xy 8.837537 -520.768517) (xy 8.875772 -520.696985) (xy 8.920834 -520.629545) (xy 8.972289 -520.566846)
			(xy 9.029642 -520.509493) (xy 9.092341 -520.458038) (xy 9.159781 -520.412976) (xy 9.231313 -520.374741)
			(xy 9.306249 -520.343702) (xy 9.383865 -520.320157) (xy 9.463416 -520.304334) (xy 9.544135 -520.296384)
			(xy 9.625245 -520.296384) (xy 9.705964 -520.304334) (xy 9.785515 -520.320157) (xy 9.863131 -520.343702)
			(xy 9.938067 -520.374741) (xy 10.009599 -520.412976) (xy 10.077039 -520.458038) (xy 10.139738 -520.509493)
			(xy 10.197091 -520.566846) (xy 10.248546 -520.629545) (xy 10.293608 -520.696985) (xy 10.331843 -520.768517)
			(xy 10.362882 -520.843453) (xy 10.386427 -520.921069) (xy 10.40225 -521.00062) (xy 10.4102 -521.081339)
			(xy 10.410698 -521.121894) (xy 10.4102 -521.162449) (xy 11.29918 -521.162449) (xy 11.29918 -521.081339)
			(xy 11.30713 -521.00062) (xy 11.322953 -520.921069) (xy 11.346498 -520.843453) (xy 11.377537 -520.768517)
			(xy 11.415772 -520.696985) (xy 11.460834 -520.629545) (xy 11.512289 -520.566846) (xy 11.569642 -520.509493)
			(xy 11.632341 -520.458038) (xy 11.699781 -520.412976) (xy 11.771313 -520.374741) (xy 11.846249 -520.343702)
			(xy 11.923865 -520.320157) (xy 12.003416 -520.304334) (xy 12.084135 -520.296384) (xy 12.165245 -520.296384)
			(xy 12.245964 -520.304334) (xy 12.325515 -520.320157) (xy 12.403131 -520.343702) (xy 12.478067 -520.374741)
			(xy 12.549599 -520.412976) (xy 12.617039 -520.458038) (xy 12.679738 -520.509493) (xy 12.737091 -520.566846)
			(xy 12.788546 -520.629545) (xy 12.833608 -520.696985) (xy 12.871843 -520.768517) (xy 12.902882 -520.843453)
			(xy 12.926427 -520.921069) (xy 12.94225 -521.00062) (xy 12.9502 -521.081339) (xy 12.950698 -521.121894)
			(xy 12.9502 -521.162449) (xy 12.94225 -521.243168) (xy 12.926427 -521.322719) (xy 12.902882 -521.400335)
			(xy 12.871843 -521.475271) (xy 12.833608 -521.546803) (xy 12.788546 -521.614243) (xy 12.737091 -521.676942)
			(xy 12.679738 -521.734295) (xy 12.617039 -521.78575) (xy 12.549599 -521.830812) (xy 12.478067 -521.869047)
			(xy 12.403131 -521.900086) (xy 12.325515 -521.923631) (xy 12.245964 -521.939454) (xy 12.165245 -521.947404)
			(xy 12.084135 -521.947404) (xy 12.003416 -521.939454) (xy 11.923865 -521.923631) (xy 11.846249 -521.900086)
			(xy 11.771313 -521.869047) (xy 11.699781 -521.830812) (xy 11.632341 -521.78575) (xy 11.569642 -521.734295)
			(xy 11.512289 -521.676942) (xy 11.460834 -521.614243) (xy 11.415772 -521.546803) (xy 11.377537 -521.475271)
			(xy 11.346498 -521.400335) (xy 11.322953 -521.322719) (xy 11.30713 -521.243168) (xy 11.29918 -521.162449)
			(xy 10.4102 -521.162449) (xy 10.40225 -521.243168) (xy 10.386427 -521.322719) (xy 10.362882 -521.400335)
			(xy 10.331843 -521.475271) (xy 10.293608 -521.546803) (xy 10.248546 -521.614243) (xy 10.197091 -521.676942)
			(xy 10.139738 -521.734295) (xy 10.077039 -521.78575) (xy 10.009599 -521.830812) (xy 9.938067 -521.869047)
			(xy 9.863131 -521.900086) (xy 9.785515 -521.923631) (xy 9.705964 -521.939454) (xy 9.625245 -521.947404)
			(xy 9.544135 -521.947404) (xy 9.463416 -521.939454) (xy 9.383865 -521.923631) (xy 9.306249 -521.900086)
			(xy 9.231313 -521.869047) (xy 9.159781 -521.830812) (xy 9.092341 -521.78575) (xy 9.029642 -521.734295)
			(xy 8.972289 -521.676942) (xy 8.920834 -521.614243) (xy 8.875772 -521.546803) (xy 8.837537 -521.475271)
			(xy 8.806498 -521.400335) (xy 8.782953 -521.322719) (xy 8.76713 -521.243168) (xy 8.75918 -521.162449)
			(xy 7.8702 -521.162449) (xy 7.86225 -521.243168) (xy 7.846427 -521.322719) (xy 7.822882 -521.400335)
			(xy 7.791843 -521.475271) (xy 7.753608 -521.546803) (xy 7.708546 -521.614243) (xy 7.657091 -521.676942)
			(xy 7.599738 -521.734295) (xy 7.537039 -521.78575) (xy 7.469599 -521.830812) (xy 7.398067 -521.869047)
			(xy 7.323131 -521.900086) (xy 7.245515 -521.923631) (xy 7.165964 -521.939454) (xy 7.085245 -521.947404)
			(xy 7.004135 -521.947404) (xy 6.923416 -521.939454) (xy 6.843865 -521.923631) (xy 6.766249 -521.900086)
			(xy 6.691313 -521.869047) (xy 6.619781 -521.830812) (xy 6.552341 -521.78575) (xy 6.489642 -521.734295)
			(xy 6.432289 -521.676942) (xy 6.380834 -521.614243) (xy 6.335772 -521.546803) (xy 6.297537 -521.475271)
			(xy 6.266498 -521.400335) (xy 6.242953 -521.322719) (xy 6.22713 -521.243168) (xy 6.21918 -521.162449)
			(xy 5.330444 -521.162449) (xy 5.330444 -521.947648) (xy 3.678936 -521.947648) (xy 3.678936 -520.29614)
			(xy 1.27 -520.29614) (xy 1.27 -524.500094) (xy 1.270491 -524.522717) (xy 1.279274 -524.567101) (xy 1.296561 -524.608912)
			(xy 1.321687 -524.646539) (xy 1.33731 -524.662908) (xy 1.351283 -524.676324) (xy 1.382867 -524.698746)
			(xy 1.41776 -524.715561) (xy 1.454976 -524.726295) (xy 1.493465 -524.730644) (xy 1.512824 -524.729964)
			(xy 5.065014 -524.729964) (xy 5.087016 -524.729503) (xy 5.130364 -524.721933) (xy 5.171759 -524.707005)
			(xy 5.209961 -524.685166) (xy 5.243827 -524.65707) (xy 5.272344 -524.623556) (xy 5.294658 -524.585629)
			(xy 5.310101 -524.544424) (xy 5.31821 -524.501174) (xy 5.318744 -524.457173) (xy 5.311686 -524.413739)
			(xy 5.297247 -524.372171) (xy 5.27586 -524.333714) (xy 5.248164 -524.299519) (xy 5.231892 -524.284702)
			(xy 5.201393 -524.257461) (xy 5.145352 -524.197901) (xy 5.095471 -524.133095) (xy 5.052237 -524.063678)
			(xy 5.016073 -523.990328) (xy 4.987333 -523.913764) (xy 4.9663 -523.834735) (xy 4.953177 -523.754015)
			(xy 4.948095 -523.672393) (xy 4.951103 -523.590668) (xy 4.962171 -523.50964) (xy 4.98119 -523.430103)
			(xy 5.007976 -523.352833) (xy 5.042265 -523.278589) (xy 5.083722 -523.208096) (xy 5.131942 -523.142044)
			(xy 5.186452 -523.08108) (xy 5.246719 -523.0258) (xy 5.312153 -522.976745) (xy 5.382114 -522.934396)
			(xy 5.455917 -522.899167) (xy 5.53284 -522.871402) (xy 5.612129 -522.851374) (xy 5.69301 -522.839278)
			(xy 5.77469 -522.835233) (xy 5.85637 -522.839278) (xy 5.937251 -522.851374) (xy 6.01654 -522.871402)
			(xy 6.093463 -522.899167) (xy 6.167266 -522.934396) (xy 6.237227 -522.976745) (xy 6.302661 -523.0258)
			(xy 6.362928 -523.08108) (xy 6.417438 -523.142044) (xy 6.465658 -523.208096) (xy 6.507115 -523.278589)
			(xy 6.541404 -523.352833) (xy 6.56819 -523.430103) (xy 6.587209 -523.50964) (xy 6.598277 -523.590668)
			(xy 6.601285 -523.672393) (xy 6.596203 -523.754015) (xy 6.58308 -523.834735) (xy 6.562047 -523.913764)
			(xy 6.533307 -523.990328) (xy 6.497143 -524.063678) (xy 6.453909 -524.133095) (xy 6.404028 -524.197901)
			(xy 6.347987 -524.257461) (xy 6.317488 -524.284702) (xy 6.301228 -524.299518) (xy 6.273571 -524.333721)
			(xy 6.252218 -524.372176) (xy 6.237807 -524.413734) (xy 6.230769 -524.457153) (xy 6.231315 -524.501136)
			(xy 6.239428 -524.544367) (xy 6.254865 -524.585555) (xy 6.277165 -524.623468) (xy 6.305663 -524.656974)
			(xy 6.339505 -524.685072) (xy 6.377681 -524.70692) (xy 6.419049 -524.721867) (xy 6.462373 -524.729466)
			(xy 6.484366 -524.729964) (xy 7.605014 -524.729964) (xy 7.627016 -524.729503) (xy 7.670364 -524.721933)
			(xy 7.711759 -524.707005) (xy 7.749961 -524.685166) (xy 7.783827 -524.65707) (xy 7.812344 -524.623556)
			(xy 7.834658 -524.585629) (xy 7.850101 -524.544424) (xy 7.85821 -524.501174) (xy 7.858744 -524.457173)
			(xy 7.851686 -524.413739) (xy 7.837247 -524.372171) (xy 7.81586 -524.333714) (xy 7.788164 -524.299519)
			(xy 7.771892 -524.284702) (xy 7.741393 -524.257461) (xy 7.685352 -524.197901) (xy 7.635471 -524.133095)
			(xy 7.592237 -524.063678) (xy 7.556073 -523.990328) (xy 7.527333 -523.913764) (xy 7.5063 -523.834735)
			(xy 7.493177 -523.754015) (xy 7.488095 -523.672393) (xy 7.491103 -523.590668) (xy 7.502171 -523.50964)
			(xy 7.52119 -523.430103) (xy 7.547976 -523.352833) (xy 7.582265 -523.278589) (xy 7.623722 -523.208096)
			(xy 7.671942 -523.142044) (xy 7.726452 -523.08108) (xy 7.786719 -523.0258) (xy 7.852153 -522.976745)
			(xy 7.922114 -522.934396) (xy 7.995917 -522.899167) (xy 8.07284 -522.871402) (xy 8.152129 -522.851374)
			(xy 8.23301 -522.839278) (xy 8.31469 -522.835233) (xy 8.39637 -522.839278) (xy 8.477251 -522.851374)
			(xy 8.55654 -522.871402) (xy 8.633463 -522.899167) (xy 8.707266 -522.934396) (xy 8.777227 -522.976745)
			(xy 8.842661 -523.0258) (xy 8.902928 -523.08108) (xy 8.957438 -523.142044) (xy 9.005658 -523.208096)
			(xy 9.047115 -523.278589) (xy 9.081404 -523.352833) (xy 9.10819 -523.430103) (xy 9.127209 -523.50964)
			(xy 9.138277 -523.590668) (xy 9.141285 -523.672393) (xy 9.136203 -523.754015) (xy 9.12308 -523.834735)
			(xy 9.102047 -523.913764) (xy 9.073307 -523.990328) (xy 9.037143 -524.063678) (xy 8.993909 -524.133095)
			(xy 8.944028 -524.197901) (xy 8.887987 -524.257461) (xy 8.857488 -524.284702) (xy 8.841228 -524.299518)
			(xy 8.813571 -524.333721) (xy 8.792218 -524.372176) (xy 8.777807 -524.413734) (xy 8.770769 -524.457153)
			(xy 8.771315 -524.501136) (xy 8.779428 -524.544367) (xy 8.794865 -524.585555) (xy 8.817165 -524.623468)
			(xy 8.845663 -524.656974) (xy 8.879505 -524.685072) (xy 8.917681 -524.70692) (xy 8.959049 -524.721867)
			(xy 9.002373 -524.729466) (xy 9.024366 -524.729964) (xy 10.145014 -524.729964) (xy 10.167016 -524.729503)
			(xy 10.210364 -524.721933) (xy 10.251759 -524.707005) (xy 10.289961 -524.685166) (xy 10.323827 -524.65707)
			(xy 10.352344 -524.623556) (xy 10.374658 -524.585629) (xy 10.390101 -524.544424) (xy 10.39821 -524.501174)
			(xy 10.398744 -524.457173) (xy 10.391686 -524.413739) (xy 10.377247 -524.372171) (xy 10.35586 -524.333714)
			(xy 10.328164 -524.299519) (xy 10.311892 -524.284702) (xy 10.281393 -524.257461) (xy 10.225352 -524.197901)
			(xy 10.175471 -524.133095) (xy 10.132237 -524.063678) (xy 10.096073 -523.990328) (xy 10.067333 -523.913764)
			(xy 10.0463 -523.834735) (xy 10.033177 -523.754015) (xy 10.028095 -523.672393) (xy 10.031103 -523.590668)
			(xy 10.042171 -523.50964) (xy 10.06119 -523.430103) (xy 10.087976 -523.352833) (xy 10.122265 -523.278589)
			(xy 10.163722 -523.208096) (xy 10.211942 -523.142044) (xy 10.266452 -523.08108) (xy 10.326719 -523.0258)
			(xy 10.392153 -522.976745) (xy 10.462114 -522.934396) (xy 10.535917 -522.899167) (xy 10.61284 -522.871402)
			(xy 10.692129 -522.851374) (xy 10.77301 -522.839278) (xy 10.85469 -522.835233) (xy 10.93637 -522.839278)
			(xy 11.017251 -522.851374) (xy 11.09654 -522.871402) (xy 11.173463 -522.899167) (xy 11.247266 -522.934396)
			(xy 11.317227 -522.976745) (xy 11.382661 -523.0258) (xy 11.442928 -523.08108) (xy 11.497438 -523.142044)
			(xy 11.545658 -523.208096) (xy 11.587115 -523.278589) (xy 11.621404 -523.352833) (xy 11.64819 -523.430103)
			(xy 11.667209 -523.50964) (xy 11.678277 -523.590668) (xy 11.681285 -523.672393) (xy 11.676203 -523.754015)
			(xy 11.66308 -523.834735) (xy 11.642047 -523.913764) (xy 11.613307 -523.990328) (xy 11.577143 -524.063678)
			(xy 11.533909 -524.133095) (xy 11.484028 -524.197901) (xy 11.427987 -524.257461) (xy 11.397488 -524.284702)
			(xy 11.381228 -524.299518) (xy 11.353571 -524.333721) (xy 11.332218 -524.372176) (xy 11.317807 -524.413734)
			(xy 11.310769 -524.457153) (xy 11.311315 -524.501136) (xy 11.319428 -524.544367) (xy 11.334865 -524.585555)
			(xy 11.357165 -524.623468) (xy 11.385663 -524.656974) (xy 11.419505 -524.685072) (xy 11.457681 -524.70692)
			(xy 11.499049 -524.721867) (xy 11.542373 -524.729466) (xy 11.564366 -524.729964) (xy 12.685014 -524.729964)
			(xy 12.707016 -524.729503) (xy 12.750364 -524.721933) (xy 12.791759 -524.707005) (xy 12.829961 -524.685166)
			(xy 12.863827 -524.65707) (xy 12.892344 -524.623556) (xy 12.914658 -524.585629) (xy 12.930101 -524.544424)
			(xy 12.93821 -524.501174) (xy 12.938744 -524.457173) (xy 12.931686 -524.413739) (xy 12.917247 -524.372171)
			(xy 12.89586 -524.333714) (xy 12.868164 -524.299519) (xy 12.851892 -524.284702) (xy 12.821393 -524.257461)
			(xy 12.765352 -524.197901) (xy 12.715471 -524.133095) (xy 12.672237 -524.063678) (xy 12.636073 -523.990328)
			(xy 12.607333 -523.913764) (xy 12.5863 -523.834735) (xy 12.573177 -523.754015) (xy 12.568095 -523.672393)
			(xy 12.571103 -523.590668) (xy 12.582171 -523.50964) (xy 12.60119 -523.430103) (xy 12.627976 -523.352833)
			(xy 12.662265 -523.278589) (xy 12.703722 -523.208096) (xy 12.751942 -523.142044) (xy 12.806452 -523.08108)
			(xy 12.866719 -523.0258) (xy 12.932153 -522.976745) (xy 13.002114 -522.934396) (xy 13.075917 -522.899167)
			(xy 13.15284 -522.871402) (xy 13.232129 -522.851374) (xy 13.31301 -522.839278) (xy 13.39469 -522.835233)
			(xy 13.47637 -522.839278) (xy 13.557251 -522.851374) (xy 13.63654 -522.871402) (xy 13.713463 -522.899167)
			(xy 13.787266 -522.934396) (xy 13.857227 -522.976745) (xy 13.922661 -523.0258) (xy 13.982928 -523.08108)
			(xy 14.037438 -523.142044) (xy 14.085658 -523.208096) (xy 14.127115 -523.278589) (xy 14.161404 -523.352833)
			(xy 14.18819 -523.430103) (xy 14.207209 -523.50964) (xy 14.218277 -523.590668) (xy 14.221285 -523.672393)
			(xy 14.216203 -523.754015) (xy 14.20308 -523.834735) (xy 14.182047 -523.913764) (xy 14.153307 -523.990328)
			(xy 14.117143 -524.063678) (xy 14.073909 -524.133095) (xy 14.024028 -524.197901) (xy 13.967987 -524.257461)
			(xy 13.937488 -524.284702) (xy 13.921228 -524.299518) (xy 13.893571 -524.333721) (xy 13.872218 -524.372176)
			(xy 13.857807 -524.413734) (xy 13.850769 -524.457153) (xy 13.851315 -524.501136) (xy 13.859428 -524.544367)
			(xy 13.874865 -524.585555) (xy 13.897165 -524.623468) (xy 13.925663 -524.656974) (xy 13.959505 -524.685072)
			(xy 13.997681 -524.70692) (xy 14.039049 -524.721867) (xy 14.082373 -524.729466) (xy 14.104366 -524.729964)
			(xy 23.50008 -524.729964) (xy 23.573919 -524.730454) (xy 23.721386 -524.738334) (xy 23.868223 -524.754063)
			(xy 24.014014 -524.777595) (xy 24.158343 -524.808865) (xy 24.3008 -524.847782) (xy 24.440981 -524.894237)
			(xy 24.578486 -524.948096) (xy 24.712926 -525.009208) (xy 24.843917 -525.077399) (xy 24.907748 -525.11452)
			(xy 24.966553 -525.14976) (xy 25.081002 -525.22526) (xy 25.191578 -525.306326) (xy 25.24506 -525.349216)
			(xy 25.300556 -525.394839) (xy 25.407289 -525.491027) (xy 25.45842 -525.541494) (xy 25.505855 -525.589483)
			(xy 25.596538 -525.689422) (xy 25.682246 -525.79366) (xy 25.722834 -525.847564) (xy 25.766299 -525.906856)
			(xy 25.847621 -526.029349) (xy 25.885394 -526.09242) (xy 25.922502 -526.156255) (xy 25.990667 -526.287252)
			(xy 26.051754 -526.421695) (xy 26.105588 -526.559203) (xy 26.152017 -526.699385) (xy 26.190908 -526.841842)
			(xy 26.222152 -526.98617) (xy 26.245659 -527.131958) (xy 26.261362 -527.278791) (xy 26.269217 -527.426253)
			(xy 26.269696 -527.500088) (xy 26.269696 -528.500086) (xy 26.270243 -528.52202) (xy 26.278593 -528.565086)
			(xy 26.294935 -528.605797) (xy 26.318682 -528.642682) (xy 26.348976 -528.674412) (xy 26.384723 -528.69984)
			(xy 26.424634 -528.718049) (xy 26.467268 -528.728382) (xy 26.489152 -528.729956)
		)
		(stroke
			(width 0)
			(type solid)
		)
		(fill yes)
		(layer "F.Cu")
		(net "P12V")
	)
	(gr_poly
		(pts
			(arc
				(start 28.274264 -210.935062)
				(mid 28.431145 -211.169762)
				(end 28.708096 -211.11464)
			)
			(xy 29.67228 -210.150456) (xy 36.09467 -210.150456) (xy 36.572444 -209.672682)
			(arc
				(start 36.572444 -208.741772)
				(mid 36.535157 -208.652134)
				(end 36.445444 -208.614772)
			)
			(xy 29.392118 -208.614772) (xy 28.274264 -209.732626)
		)
		(stroke
			(width 0)
			(type solid)
		)
		(fill yes)
		(layer "B.Cu")
		(net "GND")
	)
	(gr_poly
		(pts
			(arc
				(start 25.574244 -108.661962)
				(mid 25.731125 -108.896662)
				(end 26.008076 -108.84154)
			)
			(xy 26.4541 -108.395516)
			(arc
				(start 26.4541 -104.010968)
				(mid 26.297219 -103.776268)
				(end 26.020268 -103.83139)
			)
			(xy 25.574244 -104.277414)
		)
		(stroke
			(width 0)
			(type solid)
		)
		(fill yes)
		(layer "B.Cu")
		(net "GND")
	)
	(gr_poly
		(pts
			(arc
				(start 27.534362 -208.49336)
				(mid 27.69116 -208.728025)
				(end 27.96794 -208.672938)
			)
			(xy 28.991814 -207.649064) (xy 36.239196 -207.649064)
			(arc
				(start 37.440616 -206.447644)
				(mid 37.495868 -206.170639)
				(end 37.261038 -206.013812)
			)
			(xy 29.471874 -206.013812) (xy 27.534108 -207.951578)
		)
		(stroke
			(width 0)
			(type solid)
		)
		(fill yes)
		(layer "B.Cu")
		(net "GND")
	)
	(gr_poly
		(pts
			(arc
				(start 28.572968 -293.89832)
				(mid 28.729849 -294.13302)
				(end 29.0068 -294.077898)
			)
			(xy 29.681678 -293.40302) (xy 37.14242 -293.40302)
			(arc
				(start 38.244018 -292.301422)
				(mid 38.29927 -292.024417)
				(end 38.06444 -291.86759)
			)
			(xy 30.092396 -291.86759) (xy 28.572968 -293.387018)
		)
		(stroke
			(width 0)
			(type solid)
		)
		(fill yes)
		(layer "B.Cu")
		(net "GND")
	)
	(gr_poly
		(pts
			(arc
				(start 27.955748 -114.835432)
				(mid 28.112546 -115.070097)
				(end 28.389326 -115.01501)
			)
			(xy 29.294836 -114.1095) (xy 39.739062 -114.1095)
			(arc
				(start 40.44061 -113.407952)
				(mid 40.495862 -113.130947)
				(end 40.261032 -112.97412)
			)
			(xy 38.858698 -112.97412) (xy 38.448488 -112.564164) (xy 29.755338 -112.564164) (xy 27.955748 -114.363754)
		)
		(stroke
			(width 0)
			(type solid)
		)
		(fill yes)
		(layer "B.Cu")
		(net "GND")
	)
	(gr_poly
		(pts
			(arc
				(start 29.054806 -212.694774)
				(mid 29.211687 -212.929474)
				(end 29.488638 -212.874352)
			)
			(xy 29.752036 -212.6107) (xy 36.255452 -212.6107) (xy 37.572696 -211.293456)
			(arc
				(start 37.572696 -210.651598)
				(mid 37.415898 -210.416933)
				(end 37.139118 -210.47202)
			)
			(xy 36.494974 -211.116164) (xy 30.072584 -211.116164) (xy 29.05506 -212.133942)
		)
		(stroke
			(width 0)
			(type solid)
		)
		(fill yes)
		(layer "B.Cu")
		(net "GND")
	)
	(gr_poly
		(pts
			(arc
				(start 16.89354 -409.202636)
				(mid 17.050338 -409.437301)
				(end 17.327118 -409.382214)
			)
			(xy 18.763996 -407.94559) (xy 18.763996 -397.021558)
			(arc
				(start 17.327118 -395.584934)
				(mid 17.050353 -395.529882)
				(end 16.89354 -395.764512)
			)
			(xy 16.89354 -402.728938)
			(arc
				(start 16.899382 -402.74748)
				(mid 16.991938 -403.349968)
				(end 16.899382 -403.952456)
			)
			(xy 16.89354 -403.970998)
		)
		(stroke
			(width 0)
			(type solid)
		)
		(fill yes)
		(layer "B.Cu")
		(net "GND")
	)
	(gr_poly
		(pts
			(arc
				(start 7.457948 -327.487026)
				(mid 7.683635 -327.557189)
				(end 7.869428 -327.41108)
			)
			(arc
				(start 7.869428 -327.41108)
				(mid 7.91178 -327.331737)
				(end 7.964932 -327.259188)
			)
			(xy 7.996936 -327.221088) (xy 7.992872 -327.122282) (xy 7.246112 -326.375268) (xy 7.246112 -325.933562)
			(xy 6.626098 -325.313548) (xy 6.569456 -325.294752)
			(arc
				(start 6.539738 -325.29907)
				(mid 6.281888 -325.282767)
				(end 6.051804 -325.165212)
			)
			(arc
				(start 6.051804 -325.165212)
				(mid 5.782934 -325.134284)
				(end 5.6388 -325.363332)
			)
			(xy 5.6388 -326.490838) (xy 6.385306 -327.237344) (xy 7.208266 -327.237344)
		)
		(stroke
			(width 0)
			(type solid)
		)
		(fill yes)
		(layer "B.Cu")
		(net "GND")
	)
	(gr_poly
		(pts
			(arc
				(start 4.669536 -435.59603)
				(mid 4.833772 -435.83364)
				(end 5.114036 -435.763924)
			)
			(arc
				(start 5.114036 -435.763924)
				(mid 5.700495 -435.415696)
				(end 6.379718 -435.47792)
			)
			(xy 6.415532 -435.493414) (xy 6.491986 -435.478682) (xy 7.11962 -434.851048) (xy 7.11962 -425.536868)
			(xy 6.491986 -424.909234) (xy 6.415532 -424.894502)
			(arc
				(start 6.379718 -424.909996)
				(mid 5.700485 -424.972263)
				(end 5.114036 -424.623992)
			)
			(arc
				(start 5.114036 -424.623992)
				(mid 4.833798 -424.554345)
				(end 4.669536 -424.791886)
			)
		)
		(stroke
			(width 0)
			(type solid)
		)
		(fill yes)
		(layer "B.Cu")
		(net "GND")
	)
	(gr_poly
		(pts
			(arc
				(start 4.543806 -325.642478)
				(mid 4.820571 -325.69753)
				(end 4.977384 -325.4629)
			)
			(xy 4.977384 -324.554596) (xy 6.185154 -323.34708) (xy 6.561582 -323.34708) (xy 7.36092 -322.547742)
			(xy 7.36092 -322.291456) (xy 7.806182 -321.846194) (xy 7.824978 -321.789552)
			(arc
				(start 7.82066 -321.759834)
				(mid 7.814445 -321.686158)
				(end 7.81685 -321.61226)
			)
			(xy 7.819644 -321.583812) (xy 7.80034 -321.53098)
			(arc
				(start 7.780274 -321.510914)
				(mid 7.690522 -321.473775)
				(end 7.600696 -321.510914)
			)
			(xy 7.23773 -321.87388) (xy 6.433058 -321.87388)
			(arc
				(start 4.421886 -323.884798)
				(mid 4.347544 -324.059795)
				(end 4.415536 -324.23735)
			)
			(arc
				(start 4.415536 -324.23735)
				(mid 4.582935 -324.726577)
				(end 4.331208 -325.178166)
			)
			(arc
				(start 4.331208 -325.178166)
				(mid 4.293816 -325.22297)
				(end 4.280408 -325.279766)
			)
			(xy 4.280408 -325.37908)
		)
		(stroke
			(width 0)
			(type solid)
		)
		(fill yes)
		(layer "B.Cu")
		(net "GND")
	)
	(gr_poly
		(pts
			(arc
				(start 4.863084 -462.772252)
				(mid 5.090755 -462.630867)
				(end 5.065014 -462.364074)
			)
			(arc
				(start 5.065014 -462.364074)
				(mid 4.847134 -461.82976)
				(end 4.928108 -461.258412)
			)
			(arc
				(start 4.928108 -461.258412)
				(mid 4.936092 -461.18441)
				(end 4.901184 -461.118712)
			)
			(xy 3.95986 -460.177388) (xy 3.95986 -448.751706) (xy 8.183372 -444.528194)
			(arc
				(start 8.183372 -421.230552)
				(mid 8.026574 -420.995887)
				(end 7.749794 -421.050974)
			)
			(xy 6.274816 -422.526206) (xy 6.274816 -422.788588) (xy 6.31825 -422.853104)
			(arc
				(start 6.354572 -422.867582)
				(mid 6.965419 -423.470994)
				(end 6.960108 -424.329606)
			)
			(arc
				(start 6.960108 -424.329606)
				(mid 6.952124 -424.403608)
				(end 6.987032 -424.469306)
			)
			(xy 7.780528 -425.263056) (xy 7.780528 -435.12486)
			(arc
				(start 6.987032 -435.91861)
				(mid 6.952244 -435.984331)
				(end 6.960108 -436.05831)
			)
			(arc
				(start 6.960108 -436.05831)
				(mid 6.534291 -437.428637)
				(end 5.114036 -437.223916)
			)
			(arc
				(start 5.114036 -437.223916)
				(mid 4.833798 -437.154269)
				(end 4.669536 -437.39181)
			)
			(xy 4.669536 -446.726818) (xy 2.96926 -448.42684) (xy 2.96926 -461.437482) (xy 4.30403 -462.772252)
		)
		(stroke
			(width 0)
			(type solid)
		)
		(fill yes)
		(layer "B.Cu")
		(net "GND")
	)
	(gr_poly
		(pts
			(arc
				(start 23.226014 -199.49795)
				(mid 23.382812 -199.732615)
				(end 23.659592 -199.677528)
			)
			(xy 26.221944 -197.114922) (xy 26.221944 -196.445124) (xy 28.90774 -193.759328)
			(arc
				(start 29.495496 -193.759328)
				(mid 29.563276 -193.739728)
				(end 29.61005 -193.686938)
			)
			(arc
				(start 29.61005 -193.686938)
				(mid 30.625261 -193.164324)
				(end 31.396178 -194.00647)
			)
			(arc
				(start 31.396178 -194.00647)
				(mid 31.562513 -194.222619)
				(end 31.82874 -194.163442)
			)
			(xy 32.086296 -193.905886)
			(arc
				(start 32.086296 -190.763652)
				(mid 31.929498 -190.528987)
				(end 31.652718 -190.584074)
			)
			(xy 31.38297 -190.854076)
			(arc
				(start 31.36265 -190.854076)
				(mid 31.251486 -190.919664)
				(end 31.255208 -191.04864)
			)
			(arc
				(start 31.255208 -191.04864)
				(mid 30.545732 -192.486443)
				(end 29.586174 -191.202056)
			)
			(arc
				(start 29.586174 -191.202056)
				(mid 29.560425 -190.965524)
				(end 29.350208 -190.854076)
			)
			(xy 28.785312 -190.854076) (xy 27.760676 -191.878712) (xy 26.88463 -191.878712)
			(arc
				(start 26.858468 -191.891412)
				(mid 26.83802 -191.900536)
				(end 26.817066 -191.90843)
			)
			(xy 26.789634 -191.918082) (xy 23.22576 -195.481702)
		)
		(stroke
			(width 0)
			(type solid)
		)
		(fill yes)
		(layer "B.Cu")
		(net "GND")
	)
	(gr_poly
		(pts
			(arc
				(start 19.424904 -407.827734)
				(mid 19.581785 -408.062434)
				(end 19.858736 -408.007312)
			)
			(xy 21.905976 -405.959818) (xy 21.905976 -382.633982)
			(arc
				(start 11.880088 -372.608094)
				(mid 11.603323 -372.553042)
				(end 11.44651 -372.787672)
			)
			(arc
				(start 11.44651 -382.900936)
				(mid 11.653853 -383.15036)
				(end 11.937238 -382.99263)
			)
			(arc
				(start 11.937238 -382.99263)
				(mid 17.519312 -379.884427)
				(end 21.600668 -384.800094)
			)
			(arc
				(start 21.600668 -384.800094)
				(mid 20.156934 -388.315082)
				(end 16.659352 -389.800338)
			)
			(arc
				(start 16.659352 -389.800338)
				(mid 16.427139 -389.958539)
				(end 16.482822 -390.233916)
			)
			(xy 16.89354 -390.644634) (xy 16.89354 -394.216128) (xy 19.424904 -396.747746)
		)
		(stroke
			(width 0)
			(type solid)
		)
		(fill yes)
		(layer "B.Cu")
		(net "GND")
	)
	(gr_poly
		(pts
			(xy 40.431466 -110.931706) (xy 40.443574 -110.943164) (xy 40.472409 -110.959874) (xy 40.504592 -110.968525)
			(xy 40.537918 -110.968525) (xy 40.570101 -110.959874) (xy 40.598936 -110.943164) (xy 40.611044 -110.931706)
			(xy 40.632126 -110.910624) (xy 40.651176 -110.85449) (xy 40.647112 -110.825026) (xy 40.643842 -110.796743)
			(xy 40.644727 -110.739815) (xy 40.654062 -110.683652) (xy 40.671641 -110.629499) (xy 40.697073 -110.578561)
			(xy 40.729792 -110.531968) (xy 40.769073 -110.490755) (xy 40.814042 -110.455837) (xy 40.863702 -110.427991)
			(xy 40.916949 -110.407834) (xy 40.9726 -110.395815) (xy 41.029419 -110.392199) (xy 41.086144 -110.397069)
			(xy 41.113964 -110.403132) (xy 41.136381 -110.407965) (xy 41.182169 -110.410411) (xy 41.227653 -110.404604)
			(xy 41.271358 -110.390732) (xy 41.311865 -110.369245) (xy 41.347862 -110.340841) (xy 41.378179 -110.30644)
			(xy 41.401833 -110.267159) (xy 41.418058 -110.224272) (xy 41.426327 -110.17917) (xy 41.426892 -110.156244)
			(xy 41.426892 -101.091238) (xy 37.9095 -97.573592) (xy 37.892861 -97.557628) (xy 37.854942 -97.5314)
			(xy 37.812914 -97.512444) (xy 37.768155 -97.501379) (xy 37.722135 -97.49857) (xy 37.676363 -97.504108)
			(xy 37.63234 -97.517813) (xy 37.591513 -97.539233) (xy 37.555218 -97.567668) (xy 37.524649 -97.602182)
			(xy 37.500807 -97.641645) (xy 37.484475 -97.684761) (xy 37.476188 -97.730117) (xy 37.475668 -97.75317)
			(xy 37.475668 -101.936546) (xy 39.386492 -101.936546) (xy 39.386492 -101.87661) (xy 39.394315 -101.817188)
			(xy 39.409828 -101.759295) (xy 39.432764 -101.703922) (xy 39.462731 -101.652016) (xy 39.499218 -101.604466)
			(xy 39.541598 -101.562086) (xy 39.589148 -101.525599) (xy 39.641054 -101.495632) (xy 39.696427 -101.472696)
			(xy 39.75432 -101.457183) (xy 39.813742 -101.44936) (xy 39.873678 -101.44936) (xy 39.9331 -101.457183)
			(xy 39.990993 -101.472696) (xy 40.046366 -101.495632) (xy 40.098272 -101.525599) (xy 40.145822 -101.562086)
			(xy 40.188202 -101.604466) (xy 40.224689 -101.652016) (xy 40.254656 -101.703922) (xy 40.277592 -101.759295)
			(xy 40.293105 -101.817188) (xy 40.300928 -101.87661) (xy 40.301418 -101.906578) (xy 40.300928 -101.936546)
			(xy 40.293105 -101.995968) (xy 40.277592 -102.053861) (xy 40.254656 -102.109234) (xy 40.224689 -102.16114)
			(xy 40.188202 -102.20869) (xy 40.145822 -102.25107) (xy 40.098272 -102.287557) (xy 40.046366 -102.317524)
			(xy 39.990993 -102.34046) (xy 39.9331 -102.355973) (xy 39.873678 -102.363796) (xy 39.813742 -102.363796)
			(xy 39.75432 -102.355973) (xy 39.696427 -102.34046) (xy 39.641054 -102.317524) (xy 39.589148 -102.287557)
			(xy 39.541598 -102.25107) (xy 39.499218 -102.20869) (xy 39.462731 -102.16114) (xy 39.432764 -102.109234)
			(xy 39.409828 -102.053861) (xy 39.394315 -101.995968) (xy 39.386492 -101.936546) (xy 37.475668 -101.936546)
			(xy 37.475668 -106.118914) (xy 36.206938 -107.387898) (xy 36.195551 -107.40002) (xy 36.178888 -107.428789)
			(xy 36.170238 -107.460889) (xy 36.170188 -107.494135) (xy 36.178743 -107.526261) (xy 36.19532 -107.555079)
			(xy 36.206684 -107.567222) (xy 36.237731 -107.599214) (xy 36.2943 -107.668122) (xy 36.344093 -107.742076)
			(xy 36.386662 -107.82041) (xy 36.421627 -107.902422) (xy 36.448672 -107.987375) (xy 36.467555 -108.074506)
			(xy 36.478106 -108.163034) (xy 36.480231 -108.252162) (xy 36.473911 -108.341092) (xy 36.459202 -108.429024)
			(xy 36.436236 -108.51517) (xy 36.40522 -108.598754) (xy 36.386262 -108.639102) (xy 36.376583 -108.660352)
			(xy 36.364294 -108.705396) (xy 36.360437 -108.751925) (xy 36.365143 -108.798377) (xy 36.378254 -108.843188)
			(xy 36.399327 -108.884851) (xy 36.427656 -108.921965) (xy 36.462285 -108.953281) (xy 36.502052 -108.977745)
			(xy 36.545618 -108.994536) (xy 36.591518 -109.003088) (xy 36.614862 -109.003592) (xy 38.503606 -109.003592)
			(xy 39.533322 -110.033562) (xy 39.549893 -110.04943) (xy 39.587634 -110.075512) (xy 39.629443 -110.094396)
			(xy 39.673962 -110.105469) (xy 39.719746 -110.108373) (xy 39.765308 -110.103012) (xy 39.809168 -110.089561)
			(xy 39.849901 -110.068456) (xy 39.886185 -110.040383) (xy 39.916841 -110.006253) (xy 39.940873 -109.967176)
			(xy 39.957502 -109.92442) (xy 39.962328 -109.90199) (xy 39.968013 -109.875017) (xy 39.986112 -109.82295)
			(xy 40.011515 -109.77403) (xy 40.043693 -109.729274) (xy 40.081977 -109.689615) (xy 40.125569 -109.655877)
			(xy 40.173563 -109.628764) (xy 40.224958 -109.608839) (xy 40.278686 -109.596518) (xy 40.333628 -109.592056)
			(xy 40.38864 -109.595547) (xy 40.442577 -109.606919) (xy 40.494317 -109.625933) (xy 40.542781 -109.652195)
			(xy 40.586962 -109.685158) (xy 40.62594 -109.724135) (xy 40.658903 -109.768316) (xy 40.685166 -109.81678)
			(xy 40.704181 -109.86852) (xy 40.715552 -109.922457) (xy 40.719044 -109.977469) (xy 40.714583 -110.032411)
			(xy 40.702262 -110.086139) (xy 40.682337 -110.137535) (xy 40.655225 -110.185528) (xy 40.621487 -110.229121)
			(xy 40.581828 -110.267405) (xy 40.537073 -110.299584) (xy 40.488153 -110.324987) (xy 40.436086 -110.343086)
			(xy 40.409114 -110.348776) (xy 40.386677 -110.353594) (xy 40.343905 -110.370212) (xy 40.304812 -110.394239)
			(xy 40.270668 -110.424895) (xy 40.242582 -110.461182) (xy 40.221468 -110.501923) (xy 40.208012 -110.545792)
			(xy 40.20265 -110.591364) (xy 40.205557 -110.637159) (xy 40.216639 -110.681687) (xy 40.235535 -110.723502)
			(xy 40.261632 -110.761245) (xy 40.277542 -110.777782)
		)
		(stroke
			(width 0)
			(type solid)
		)
		(fill yes)
		(layer "B.Cu")
		(net "GND")
	)
	(gr_poly
		(pts
			(xy 26.356056 -374.13184) (xy 26.35656 -374.154889) (xy 26.364877 -374.200232) (xy 26.381231 -374.243332)
			(xy 26.405086 -374.282779) (xy 26.435661 -374.317279) (xy 26.471954 -374.345703) (xy 26.512776 -374.367119)
			(xy 26.55679 -374.380825) (xy 26.602554 -374.386374) (xy 26.648568 -374.383582) (xy 26.693325 -374.372541)
			(xy 26.735359 -374.353614) (xy 26.773293 -374.32742) (xy 26.789888 -374.311418) (xy 29.505148 -371.595904)
			(xy 29.56306 -371.595904) (xy 29.578209 -371.595472) (xy 29.607654 -371.588331) (xy 29.634582 -371.574442)
			(xy 29.657471 -371.55459) (xy 29.675029 -371.529898) (xy 29.686263 -371.501759) (xy 29.690538 -371.471764)
			(xy 29.687614 -371.441607) (xy 29.677656 -371.412992) (xy 29.66974 -371.40007) (xy 29.646788 -371.363632)
			(xy 29.606883 -371.287311) (xy 29.574125 -371.207662) (xy 29.548787 -371.12535) (xy 29.531082 -371.041067)
			(xy 29.521159 -370.955517) (xy 29.5191 -370.869419) (xy 29.524923 -370.783493) (xy 29.538579 -370.698459)
			(xy 29.559953 -370.615031) (xy 29.573982 -370.574316) (xy 29.586428 -370.539772) (xy 29.570172 -370.468144)
			(xy 28.92298 -369.820952) (xy 28.92298 -368.119406) (xy 27.911552 -367.107978) (xy 27.894771 -367.091934)
			(xy 27.856524 -367.065624) (xy 27.814135 -367.046699) (xy 27.769013 -367.035787) (xy 27.72266 -367.033253)
			(xy 27.676618 -367.03918) (xy 27.632418 -367.053371) (xy 27.591531 -367.075355) (xy 27.555317 -367.104399)
			(xy 27.524981 -367.139537) (xy 27.512772 -367.159286) (xy 27.497267 -367.184818) (xy 27.460641 -367.232007)
			(xy 27.418187 -367.274029) (xy 27.370627 -367.310171) (xy 27.318768 -367.339818) (xy 27.263493 -367.362465)
			(xy 27.205742 -367.377729) (xy 27.146495 -367.385348) (xy 27.08676 -367.385195) (xy 27.027554 -367.377272)
			(xy 26.969881 -367.361712) (xy 26.914723 -367.338781) (xy 26.863017 -367.308869) (xy 26.815643 -367.272484)
			(xy 26.773405 -367.230245) (xy 26.737021 -367.182869) (xy 26.707111 -367.131162) (xy 26.684182 -367.076003)
			(xy 26.668625 -367.01833) (xy 26.660704 -366.959122) (xy 26.660553 -366.899388) (xy 26.668175 -366.840142)
			(xy 26.68344 -366.782391) (xy 26.70609 -366.727116) (xy 26.735739 -366.675259) (xy 26.771882 -366.6277)
			(xy 26.813906 -366.585247) (xy 26.861096 -366.548623) (xy 26.886662 -366.533176) (xy 26.906436 -366.521006)
			(xy 26.941579 -366.490668) (xy 26.970625 -366.45445) (xy 26.992609 -366.413559) (xy 27.006799 -366.369354)
			(xy 27.012721 -366.323307) (xy 27.01018 -366.27695) (xy 26.999259 -366.231826) (xy 26.980323 -366.189437)
			(xy 26.954001 -366.151193) (xy 26.93797 -366.134396) (xy 25.8699 -365.066326) (xy 25.8699 -360.27614)
			(xy 22.22373 -356.629716) (xy 22.207088 -356.613778) (xy 22.169173 -356.5876) (xy 22.12716 -356.568686)
			(xy 22.082425 -356.557655) (xy 22.036435 -356.554869) (xy 21.990696 -356.560418) (xy 21.946707 -356.574122)
			(xy 21.905909 -356.595531) (xy 21.869638 -356.623944) (xy 21.839083 -356.658429) (xy 21.815245 -356.697858)
			(xy 21.798905 -356.740937) (xy 21.790598 -356.786257) (xy 21.790152 -356.809294) (xy 21.790152 -357.673402)
			(xy 23.79218 -359.675684) (xy 23.79218 -368.524536) (xy 23.792669 -368.54741) (xy 23.800863 -368.592417)
			(xy 23.816981 -368.635231) (xy 23.840501 -368.67447) (xy 23.870665 -368.708864) (xy 23.906497 -368.737305)
			(xy 23.946841 -368.758873) (xy 23.990394 -368.772872) (xy 24.035749 -368.778849) (xy 24.081442 -368.776613)
			(xy 24.103838 -368.771932) (xy 24.131177 -368.766103) (xy 24.186891 -368.761575) (xy 24.24267 -368.765225)
			(xy 24.297319 -368.776976) (xy 24.349668 -368.796575) (xy 24.398597 -368.823603) (xy 24.443058 -368.857482)
			(xy 24.482099 -368.897487) (xy 24.514885 -368.94276) (xy 24.540714 -368.992333) (xy 24.544759 -369.003322)
			(xy 26.722306 -369.003322) (xy 26.722306 -368.943386) (xy 26.730129 -368.883964) (xy 26.745642 -368.826071)
			(xy 26.768578 -368.770698) (xy 26.798545 -368.718792) (xy 26.835032 -368.671242) (xy 26.877412 -368.628862)
			(xy 26.924962 -368.592375) (xy 26.976868 -368.562408) (xy 27.032241 -368.539472) (xy 27.090134 -368.523959)
			(xy 27.149556 -368.516136) (xy 27.209492 -368.516136) (xy 27.268914 -368.523959) (xy 27.326807 -368.539472)
			(xy 27.38218 -368.562408) (xy 27.434086 -368.592375) (xy 27.481636 -368.628862) (xy 27.524016 -368.671242)
			(xy 27.560503 -368.718792) (xy 27.59047 -368.770698) (xy 27.613406 -368.826071) (xy 27.628919 -368.883964)
			(xy 27.636742 -368.943386) (xy 27.637232 -368.973354) (xy 27.636742 -369.003322) (xy 27.628919 -369.062744)
			(xy 27.613406 -369.120637) (xy 27.59047 -369.17601) (xy 27.560503 -369.227916) (xy 27.524016 -369.275466)
			(xy 27.481636 -369.317846) (xy 27.434086 -369.354333) (xy 27.38218 -369.3843) (xy 27.326807 -369.407236)
			(xy 27.268914 -369.422749) (xy 27.209492 -369.430572) (xy 27.149556 -369.430572) (xy 27.090134 -369.422749)
			(xy 27.032241 -369.407236) (xy 26.976868 -369.3843) (xy 26.924962 -369.354333) (xy 26.877412 -369.317846)
			(xy 26.835032 -369.275466) (xy 26.798545 -369.227916) (xy 26.768578 -369.17601) (xy 26.745642 -369.120637)
			(xy 26.730129 -369.062744) (xy 26.722306 -369.003322) (xy 24.544759 -369.003322) (xy 24.55037 -369.018566)
			(xy 24.560022 -369.045998) (xy 26.356056 -370.842286) (xy 26.356056 -371.700806) (xy 27.195778 -371.700806)
			(xy 27.199849 -371.645184) (xy 27.211975 -371.590747) (xy 27.231898 -371.538656) (xy 27.259194 -371.490021)
			(xy 27.29328 -371.445878) (xy 27.333429 -371.407169) (xy 27.378787 -371.374718) (xy 27.428387 -371.349217)
			(xy 27.481171 -371.33121) (xy 27.536014 -371.32108) (xy 27.591748 -371.319043) (xy 27.647185 -371.325143)
			(xy 27.701142 -371.339249) (xy 27.752471 -371.361061) (xy 27.800077 -371.390115) (xy 27.842945 -371.42579)
			(xy 27.880162 -371.467327) (xy 27.910935 -371.51384) (xy 27.934607 -371.564337) (xy 27.950675 -371.617744)
			(xy 27.958795 -371.67292) (xy 27.959304 -371.700806) (xy 27.958795 -371.728692) (xy 27.950675 -371.783868)
			(xy 27.934607 -371.837275) (xy 27.910935 -371.887772) (xy 27.880162 -371.934285) (xy 27.842945 -371.975822)
			(xy 27.800077 -372.011497) (xy 27.752471 -372.040551) (xy 27.701142 -372.062363) (xy 27.647185 -372.076469)
			(xy 27.591748 -372.082569) (xy 27.536014 -372.080532) (xy 27.481171 -372.070402) (xy 27.428387 -372.052395)
			(xy 27.378787 -372.026894) (xy 27.333429 -371.994443) (xy 27.29328 -371.955734) (xy 27.259194 -371.911591)
			(xy 27.231898 -371.862956) (xy 27.211975 -371.810865) (xy 27.199849 -371.756428) (xy 27.195778 -371.700806)
			(xy 26.356056 -371.700806)
		)
		(stroke
			(width 0)
			(type solid)
		)
		(fill yes)
		(layer "B.Cu")
		(net "GND")
	)
	(gr_poly
		(pts
			(xy 83.003644 -430.150016) (xy 83.003143 -430.049886) (xy 82.995131 -429.849786) (xy 82.979119 -429.650167)
			(xy 82.955133 -429.451348) (xy 82.923212 -429.253649) (xy 82.883407 -429.057384) (xy 82.835781 -428.86287)
			(xy 82.78041 -428.670416) (xy 82.717384 -428.480333) (xy 82.646804 -428.292923) (xy 82.568781 -428.108487)
			(xy 82.483442 -427.92732) (xy 82.390923 -427.749713) (xy 82.291372 -427.575949) (xy 82.184948 -427.406308)
			(xy 82.071822 -427.24106) (xy 81.952176 -427.080471) (xy 81.8262 -426.924798) (xy 81.694096 -426.774289)
			(xy 81.556077 -426.629187) (xy 81.412362 -426.489723) (xy 81.263183 -426.35612) (xy 81.108778 -426.228593)
			(xy 80.949394 -426.107345) (xy 80.785286 -425.992572) (xy 80.616718 -425.884457) (xy 80.44396 -425.783172)
			(xy 80.267287 -425.68888) (xy 80.086983 -425.601733) (xy 79.903337 -425.521869) (xy 79.716642 -425.449417)
			(xy 79.527199 -425.384492) (xy 79.335309 -425.327199) (xy 79.141281 -425.277629) (xy 78.945424 -425.235862)
			(xy 78.748054 -425.201965) (xy 78.549485 -425.175991) (xy 78.350036 -425.157983) (xy 78.150027 -425.147969)
			(xy 77.949776 -425.145965) (xy 77.749606 -425.151975) (xy 77.549837 -425.165989) (xy 77.350789 -425.187985)
			(xy 77.152779 -425.217926) (xy 76.956127 -425.255766) (xy 76.761145 -425.301444) (xy 76.568148 -425.354886)
			(xy 76.377443 -425.416007) (xy 76.189336 -425.484709) (xy 76.004129 -425.560882) (xy 75.822117 -425.644405)
			(xy 75.643593 -425.735142) (xy 75.468842 -425.83295) (xy 75.298145 -425.937671) (xy 75.131774 -426.049138)
			(xy 74.969996 -426.167172) (xy 74.81307 -426.291584) (xy 74.661247 -426.422175) (xy 74.514771 -426.558736)
			(xy 74.373876 -426.701048) (xy 74.238787 -426.848883) (xy 74.109722 -427.002005) (xy 73.986886 -427.160167)
			(xy 73.870476 -427.323118) (xy 73.76068 -427.490596) (xy 73.657672 -427.662333) (xy 73.561617 -427.838053)
			(xy 73.47267 -428.017476) (xy 73.390973 -428.200314) (xy 73.316657 -428.386275) (xy 73.24984 -428.575059)
			(xy 73.19063 -428.766366) (xy 73.139121 -428.959889) (xy 73.095397 -429.155317) (xy 73.059526 -429.352339)
			(xy 73.031567 -429.550638) (xy 73.011564 -429.749896) (xy 72.99955 -429.949796) (xy 72.995543 -430.150016)
			(xy 75.484741 -430.150016) (xy 75.488769 -430.007724) (xy 75.500841 -429.865888) (xy 75.520918 -429.724961)
			(xy 75.548936 -429.585397) (xy 75.584805 -429.447641) (xy 75.62841 -429.312135) (xy 75.679611 -429.179313)
			(xy 75.738245 -429.0496) (xy 75.804123 -428.923413) (xy 75.877035 -428.801154) (xy 75.956747 -428.683217)
			(xy 76.043004 -428.569978) (xy 76.135528 -428.4618) (xy 76.234025 -428.35903) (xy 76.338179 -428.261997)
			(xy 76.447655 -428.171013) (xy 76.562103 -428.086367) (xy 76.681157 -428.008332) (xy 76.804435 -427.937158)
			(xy 76.931542 -427.873071) (xy 77.062071 -427.816279) (xy 77.195605 -427.766962) (xy 77.331714 -427.725279)
			(xy 77.469964 -427.691363) (xy 77.609911 -427.665323) (xy 77.751107 -427.647242) (xy 77.8931 -427.637179)
			(xy 78.035435 -427.635164) (xy 78.177656 -427.641206) (xy 78.319307 -427.655284) (xy 78.459935 -427.677353)
			(xy 78.599089 -427.707343) (xy 78.736324 -427.745158) (xy 78.871199 -427.790676) (xy 79.003283 -427.843752)
			(xy 79.132153 -427.904215) (xy 79.257396 -427.971872) (xy 79.37861 -428.046507) (xy 79.495408 -428.12788)
			(xy 79.607415 -428.21573) (xy 79.714273 -428.309777) (xy 79.815638 -428.409718) (xy 79.911187 -428.515234)
			(xy 80.000614 -428.625987) (xy 80.083632 -428.741621) (xy 80.159974 -428.861768) (xy 80.229397 -428.98604)
			(xy 80.291678 -429.114042) (xy 80.346618 -429.245362) (xy 80.39404 -429.379579) (xy 80.433793 -429.516265)
			(xy 80.465749 -429.654981) (xy 80.489806 -429.795282) (xy 80.505887 -429.93672) (xy 80.51394 -430.078841)
			(xy 80.514444 -430.150016) (xy 80.51394 -430.221191) (xy 80.505887 -430.363312) (xy 80.489806 -430.50475)
			(xy 80.465749 -430.645051) (xy 80.433793 -430.783767) (xy 80.39404 -430.920453) (xy 80.346618 -431.05467)
			(xy 80.291678 -431.18599) (xy 80.229397 -431.313992) (xy 80.159974 -431.438264) (xy 80.083632 -431.558411)
			(xy 80.000614 -431.674045) (xy 79.911187 -431.784798) (xy 79.815638 -431.890314) (xy 79.714273 -431.990255)
			(xy 79.607415 -432.084302) (xy 79.495408 -432.172152) (xy 79.37861 -432.253525) (xy 79.257396 -432.32816)
			(xy 79.132153 -432.395817) (xy 79.003283 -432.45628) (xy 78.871199 -432.509356) (xy 78.736324 -432.554874)
			(xy 78.599089 -432.592689) (xy 78.459935 -432.622679) (xy 78.319307 -432.644748) (xy 78.177656 -432.658826)
			(xy 78.035435 -432.664868) (xy 77.8931 -432.662853) (xy 77.751107 -432.65279) (xy 77.609911 -432.634709)
			(xy 77.469964 -432.608669) (xy 77.331714 -432.574753) (xy 77.195605 -432.53307) (xy 77.062071 -432.483753)
			(xy 76.931542 -432.426961) (xy 76.804435 -432.362874) (xy 76.681157 -432.2917) (xy 76.562103 -432.213665)
			(xy 76.447655 -432.129019) (xy 76.338179 -432.038035) (xy 76.234025 -431.941002) (xy 76.135528 -431.838232)
			(xy 76.043004 -431.730054) (xy 75.956747 -431.616815) (xy 75.877035 -431.498878) (xy 75.804123 -431.376619)
			(xy 75.738245 -431.250432) (xy 75.679611 -431.120719) (xy 75.62841 -430.987897) (xy 75.584805 -430.852391)
			(xy 75.548936 -430.714635) (xy 75.520918 -430.575071) (xy 75.500841 -430.434144) (xy 75.488769 -430.292308)
			(xy 75.484741 -430.150016) (xy 72.995543 -430.150016) (xy 72.99955 -430.350236) (xy 73.011564 -430.550136)
			(xy 73.031567 -430.749394) (xy 73.059526 -430.947693) (xy 73.095397 -431.144715) (xy 73.139121 -431.340143)
			(xy 73.19063 -431.533666) (xy 73.24984 -431.724973) (xy 73.316657 -431.913757) (xy 73.390973 -432.099718)
			(xy 73.47267 -432.282556) (xy 73.561617 -432.461979) (xy 73.657672 -432.637699) (xy 73.76068 -432.809436)
			(xy 73.870476 -432.976914) (xy 73.986886 -433.139865) (xy 74.109722 -433.298027) (xy 74.238787 -433.451149)
			(xy 74.373876 -433.598984) (xy 74.514771 -433.741296) (xy 74.661247 -433.877857) (xy 74.81307 -434.008448)
			(xy 74.969996 -434.13286) (xy 75.131774 -434.250894) (xy 75.298145 -434.362361) (xy 75.468842 -434.467082)
			(xy 75.643593 -434.56489) (xy 75.822117 -434.655627) (xy 76.004129 -434.73915) (xy 76.189336 -434.815323)
			(xy 76.377443 -434.884025) (xy 76.568148 -434.945146) (xy 76.761145 -434.998588) (xy 76.956127 -435.044266)
			(xy 77.152779 -435.082106) (xy 77.350789 -435.112047) (xy 77.549837 -435.134043) (xy 77.749606 -435.148057)
			(xy 77.949776 -435.154067) (xy 78.150027 -435.152063) (xy 78.350036 -435.142049) (xy 78.549485 -435.124041)
			(xy 78.748054 -435.098067) (xy 78.945424 -435.06417) (xy 79.141281 -435.022403) (xy 79.335309 -434.972833)
			(xy 79.527199 -434.91554) (xy 79.716642 -434.850615) (xy 79.903337 -434.778163) (xy 80.086983 -434.698299)
			(xy 80.267287 -434.611152) (xy 80.44396 -434.51686) (xy 80.616718 -434.415575) (xy 80.785286 -434.30746)
			(xy 80.949394 -434.192687) (xy 81.108778 -434.071439) (xy 81.263183 -433.943912) (xy 81.412362 -433.810309)
			(xy 81.556077 -433.670845) (xy 81.694096 -433.525743) (xy 81.8262 -433.375234) (xy 81.952176 -433.219561)
			(xy 82.071822 -433.058972) (xy 82.184948 -432.893724) (xy 82.291372 -432.724083) (xy 82.390923 -432.550319)
			(xy 82.483442 -432.372712) (xy 82.568781 -432.191545) (xy 82.646804 -432.007109) (xy 82.717384 -431.819699)
			(xy 82.78041 -431.629616) (xy 82.835781 -431.437162) (xy 82.883407 -431.242648) (xy 82.923212 -431.046383)
			(xy 82.955133 -430.848684) (xy 82.979119 -430.649865) (xy 82.995131 -430.450246) (xy 83.003143 -430.250146)
		)
		(stroke
			(width 0)
			(type solid)
		)
		(fill yes)
		(layer "B.Cu")
		(net "GND")
	)
	(gr_poly
		(pts
			(xy 83.003644 -341.250016) (xy 83.003143 -341.149886) (xy 82.995131 -340.949786) (xy 82.979119 -340.750167)
			(xy 82.955133 -340.551348) (xy 82.923212 -340.353649) (xy 82.883407 -340.157384) (xy 82.835781 -339.96287)
			(xy 82.78041 -339.770416) (xy 82.717384 -339.580333) (xy 82.646804 -339.392923) (xy 82.568781 -339.208487)
			(xy 82.483442 -339.02732) (xy 82.390923 -338.849713) (xy 82.291372 -338.675949) (xy 82.184948 -338.506308)
			(xy 82.071822 -338.34106) (xy 81.952176 -338.180471) (xy 81.8262 -338.024798) (xy 81.694096 -337.874289)
			(xy 81.556077 -337.729187) (xy 81.412362 -337.589723) (xy 81.263183 -337.45612) (xy 81.108778 -337.328593)
			(xy 80.949394 -337.207345) (xy 80.785286 -337.092572) (xy 80.616718 -336.984457) (xy 80.44396 -336.883172)
			(xy 80.267287 -336.78888) (xy 80.086983 -336.701733) (xy 79.903337 -336.621869) (xy 79.716642 -336.549417)
			(xy 79.527199 -336.484492) (xy 79.335309 -336.427199) (xy 79.141281 -336.377629) (xy 78.945424 -336.335862)
			(xy 78.748054 -336.301965) (xy 78.549485 -336.275991) (xy 78.350036 -336.257983) (xy 78.150027 -336.247969)
			(xy 77.949776 -336.245965) (xy 77.749606 -336.251975) (xy 77.549837 -336.265989) (xy 77.350789 -336.287985)
			(xy 77.152779 -336.317926) (xy 76.956127 -336.355766) (xy 76.761145 -336.401444) (xy 76.568148 -336.454886)
			(xy 76.377443 -336.516007) (xy 76.189336 -336.584709) (xy 76.004129 -336.660882) (xy 75.822117 -336.744405)
			(xy 75.643593 -336.835142) (xy 75.468842 -336.93295) (xy 75.298145 -337.037671) (xy 75.131774 -337.149138)
			(xy 74.969996 -337.267172) (xy 74.81307 -337.391584) (xy 74.661247 -337.522175) (xy 74.514771 -337.658736)
			(xy 74.373876 -337.801048) (xy 74.238787 -337.948883) (xy 74.109722 -338.102005) (xy 73.986886 -338.260167)
			(xy 73.870476 -338.423118) (xy 73.76068 -338.590596) (xy 73.657672 -338.762333) (xy 73.561617 -338.938053)
			(xy 73.47267 -339.117476) (xy 73.390973 -339.300314) (xy 73.316657 -339.486275) (xy 73.24984 -339.675059)
			(xy 73.19063 -339.866366) (xy 73.139121 -340.059889) (xy 73.095397 -340.255317) (xy 73.059526 -340.452339)
			(xy 73.031567 -340.650638) (xy 73.011564 -340.849896) (xy 72.99955 -341.049796) (xy 72.995543 -341.250016)
			(xy 75.484741 -341.250016) (xy 75.488769 -341.107724) (xy 75.500841 -340.965888) (xy 75.520918 -340.824961)
			(xy 75.548936 -340.685397) (xy 75.584805 -340.547641) (xy 75.62841 -340.412135) (xy 75.679611 -340.279313)
			(xy 75.738245 -340.1496) (xy 75.804123 -340.023413) (xy 75.877035 -339.901154) (xy 75.956747 -339.783217)
			(xy 76.043004 -339.669978) (xy 76.135528 -339.5618) (xy 76.234025 -339.45903) (xy 76.338179 -339.361997)
			(xy 76.447655 -339.271013) (xy 76.562103 -339.186367) (xy 76.681157 -339.108332) (xy 76.804435 -339.037158)
			(xy 76.931542 -338.973071) (xy 77.062071 -338.916279) (xy 77.195605 -338.866962) (xy 77.331714 -338.825279)
			(xy 77.469964 -338.791363) (xy 77.609911 -338.765323) (xy 77.751107 -338.747242) (xy 77.8931 -338.737179)
			(xy 78.035435 -338.735164) (xy 78.177656 -338.741206) (xy 78.319307 -338.755284) (xy 78.459935 -338.777353)
			(xy 78.599089 -338.807343) (xy 78.736324 -338.845158) (xy 78.871199 -338.890676) (xy 79.003283 -338.943752)
			(xy 79.132153 -339.004215) (xy 79.257396 -339.071872) (xy 79.37861 -339.146507) (xy 79.495408 -339.22788)
			(xy 79.607415 -339.31573) (xy 79.714273 -339.409777) (xy 79.815638 -339.509718) (xy 79.911187 -339.615234)
			(xy 80.000614 -339.725987) (xy 80.083632 -339.841621) (xy 80.159974 -339.961768) (xy 80.229397 -340.08604)
			(xy 80.291678 -340.214042) (xy 80.346618 -340.345362) (xy 80.39404 -340.479579) (xy 80.433793 -340.616265)
			(xy 80.465749 -340.754981) (xy 80.489806 -340.895282) (xy 80.505887 -341.03672) (xy 80.51394 -341.178841)
			(xy 80.514444 -341.250016) (xy 80.51394 -341.321191) (xy 80.505887 -341.463312) (xy 80.489806 -341.60475)
			(xy 80.465749 -341.745051) (xy 80.433793 -341.883767) (xy 80.39404 -342.020453) (xy 80.346618 -342.15467)
			(xy 80.291678 -342.28599) (xy 80.229397 -342.413992) (xy 80.159974 -342.538264) (xy 80.083632 -342.658411)
			(xy 80.000614 -342.774045) (xy 79.911187 -342.884798) (xy 79.815638 -342.990314) (xy 79.714273 -343.090255)
			(xy 79.607415 -343.184302) (xy 79.495408 -343.272152) (xy 79.37861 -343.353525) (xy 79.257396 -343.42816)
			(xy 79.132153 -343.495817) (xy 79.003283 -343.55628) (xy 78.871199 -343.609356) (xy 78.736324 -343.654874)
			(xy 78.599089 -343.692689) (xy 78.459935 -343.722679) (xy 78.319307 -343.744748) (xy 78.177656 -343.758826)
			(xy 78.035435 -343.764868) (xy 77.8931 -343.762853) (xy 77.751107 -343.75279) (xy 77.609911 -343.734709)
			(xy 77.469964 -343.708669) (xy 77.331714 -343.674753) (xy 77.195605 -343.63307) (xy 77.062071 -343.583753)
			(xy 76.931542 -343.526961) (xy 76.804435 -343.462874) (xy 76.681157 -343.3917) (xy 76.562103 -343.313665)
			(xy 76.447655 -343.229019) (xy 76.338179 -343.138035) (xy 76.234025 -343.041002) (xy 76.135528 -342.938232)
			(xy 76.043004 -342.830054) (xy 75.956747 -342.716815) (xy 75.877035 -342.598878) (xy 75.804123 -342.476619)
			(xy 75.738245 -342.350432) (xy 75.679611 -342.220719) (xy 75.62841 -342.087897) (xy 75.584805 -341.952391)
			(xy 75.548936 -341.814635) (xy 75.520918 -341.675071) (xy 75.500841 -341.534144) (xy 75.488769 -341.392308)
			(xy 75.484741 -341.250016) (xy 72.995543 -341.250016) (xy 72.99955 -341.450236) (xy 73.011564 -341.650136)
			(xy 73.031567 -341.849394) (xy 73.059526 -342.047693) (xy 73.095397 -342.244715) (xy 73.139121 -342.440143)
			(xy 73.19063 -342.633666) (xy 73.24984 -342.824973) (xy 73.316657 -343.013757) (xy 73.390973 -343.199718)
			(xy 73.47267 -343.382556) (xy 73.561617 -343.561979) (xy 73.657672 -343.737699) (xy 73.76068 -343.909436)
			(xy 73.870476 -344.076914) (xy 73.986886 -344.239865) (xy 74.109722 -344.398027) (xy 74.238787 -344.551149)
			(xy 74.373876 -344.698984) (xy 74.514771 -344.841296) (xy 74.661247 -344.977857) (xy 74.81307 -345.108448)
			(xy 74.969996 -345.23286) (xy 75.131774 -345.350894) (xy 75.298145 -345.462361) (xy 75.468842 -345.567082)
			(xy 75.643593 -345.66489) (xy 75.822117 -345.755627) (xy 76.004129 -345.83915) (xy 76.189336 -345.915323)
			(xy 76.377443 -345.984025) (xy 76.568148 -346.045146) (xy 76.761145 -346.098588) (xy 76.956127 -346.144266)
			(xy 77.152779 -346.182106) (xy 77.350789 -346.212047) (xy 77.549837 -346.234043) (xy 77.749606 -346.248057)
			(xy 77.949776 -346.254067) (xy 78.150027 -346.252063) (xy 78.350036 -346.242049) (xy 78.549485 -346.224041)
			(xy 78.748054 -346.198067) (xy 78.945424 -346.16417) (xy 79.141281 -346.122403) (xy 79.335309 -346.072833)
			(xy 79.527199 -346.01554) (xy 79.716642 -345.950615) (xy 79.903337 -345.878163) (xy 80.086983 -345.798299)
			(xy 80.267287 -345.711152) (xy 80.44396 -345.61686) (xy 80.616718 -345.515575) (xy 80.785286 -345.40746)
			(xy 80.949394 -345.292687) (xy 81.108778 -345.171439) (xy 81.263183 -345.043912) (xy 81.412362 -344.910309)
			(xy 81.556077 -344.770845) (xy 81.694096 -344.625743) (xy 81.8262 -344.475234) (xy 81.952176 -344.319561)
			(xy 82.071822 -344.158972) (xy 82.184948 -343.993724) (xy 82.291372 -343.824083) (xy 82.390923 -343.650319)
			(xy 82.483442 -343.472712) (xy 82.568781 -343.291545) (xy 82.646804 -343.107109) (xy 82.717384 -342.919699)
			(xy 82.78041 -342.729616) (xy 82.835781 -342.537162) (xy 82.883407 -342.342648) (xy 82.923212 -342.146383)
			(xy 82.955133 -341.948684) (xy 82.979119 -341.749865) (xy 82.995131 -341.550246) (xy 83.003143 -341.350146)
		)
		(stroke
			(width 0)
			(type solid)
		)
		(fill yes)
		(layer "B.Cu")
		(net "GND")
	)
	(gr_poly
		(pts
			(xy 83.003644 -210.09991) (xy 83.003143 -209.99978) (xy 82.995131 -209.79968) (xy 82.979119 -209.600061)
			(xy 82.955133 -209.401242) (xy 82.923212 -209.203543) (xy 82.883407 -209.007278) (xy 82.835781 -208.812764)
			(xy 82.78041 -208.62031) (xy 82.717384 -208.430227) (xy 82.646804 -208.242817) (xy 82.568781 -208.058381)
			(xy 82.483442 -207.877214) (xy 82.390923 -207.699607) (xy 82.291372 -207.525843) (xy 82.184948 -207.356202)
			(xy 82.071822 -207.190954) (xy 81.952176 -207.030365) (xy 81.8262 -206.874692) (xy 81.694096 -206.724183)
			(xy 81.556077 -206.579081) (xy 81.412362 -206.439617) (xy 81.263183 -206.306014) (xy 81.108778 -206.178487)
			(xy 80.949394 -206.057239) (xy 80.785286 -205.942466) (xy 80.616718 -205.834351) (xy 80.44396 -205.733066)
			(xy 80.267287 -205.638774) (xy 80.086983 -205.551627) (xy 79.903337 -205.471763) (xy 79.716642 -205.399311)
			(xy 79.527199 -205.334386) (xy 79.335309 -205.277093) (xy 79.141281 -205.227523) (xy 78.945424 -205.185756)
			(xy 78.748054 -205.151859) (xy 78.549485 -205.125885) (xy 78.350036 -205.107877) (xy 78.150027 -205.097863)
			(xy 77.949776 -205.095859) (xy 77.749606 -205.101869) (xy 77.549837 -205.115883) (xy 77.350789 -205.137879)
			(xy 77.152779 -205.16782) (xy 76.956127 -205.20566) (xy 76.761145 -205.251338) (xy 76.568148 -205.30478)
			(xy 76.377443 -205.365901) (xy 76.189336 -205.434603) (xy 76.004129 -205.510776) (xy 75.822117 -205.594299)
			(xy 75.643593 -205.685036) (xy 75.468842 -205.782844) (xy 75.298145 -205.887565) (xy 75.131774 -205.999032)
			(xy 74.969996 -206.117066) (xy 74.81307 -206.241478) (xy 74.661247 -206.372069) (xy 74.514771 -206.50863)
			(xy 74.373876 -206.650942) (xy 74.238787 -206.798777) (xy 74.109722 -206.951899) (xy 73.986886 -207.110061)
			(xy 73.870476 -207.273012) (xy 73.76068 -207.44049) (xy 73.657672 -207.612227) (xy 73.561617 -207.787947)
			(xy 73.47267 -207.96737) (xy 73.390973 -208.150208) (xy 73.316657 -208.336169) (xy 73.24984 -208.524953)
			(xy 73.19063 -208.71626) (xy 73.139121 -208.909783) (xy 73.095397 -209.105211) (xy 73.059526 -209.302233)
			(xy 73.031567 -209.500532) (xy 73.011564 -209.69979) (xy 72.99955 -209.89969) (xy 72.995543 -210.09991)
			(xy 75.484741 -210.09991) (xy 75.488769 -209.957618) (xy 75.500841 -209.815782) (xy 75.520918 -209.674855)
			(xy 75.548936 -209.535291) (xy 75.584805 -209.397535) (xy 75.62841 -209.262029) (xy 75.679611 -209.129207)
			(xy 75.738245 -208.999494) (xy 75.804123 -208.873307) (xy 75.877035 -208.751048) (xy 75.956747 -208.633111)
			(xy 76.043004 -208.519872) (xy 76.135528 -208.411694) (xy 76.234025 -208.308924) (xy 76.338179 -208.211891)
			(xy 76.447655 -208.120907) (xy 76.562103 -208.036261) (xy 76.681157 -207.958226) (xy 76.804435 -207.887052)
			(xy 76.931542 -207.822965) (xy 77.062071 -207.766173) (xy 77.195605 -207.716856) (xy 77.331714 -207.675173)
			(xy 77.469964 -207.641257) (xy 77.609911 -207.615217) (xy 77.751107 -207.597136) (xy 77.8931 -207.587073)
			(xy 78.035435 -207.585058) (xy 78.177656 -207.5911) (xy 78.319307 -207.605178) (xy 78.459935 -207.627247)
			(xy 78.599089 -207.657237) (xy 78.736324 -207.695052) (xy 78.871199 -207.74057) (xy 79.003283 -207.793646)
			(xy 79.132153 -207.854109) (xy 79.257396 -207.921766) (xy 79.37861 -207.996401) (xy 79.495408 -208.077774)
			(xy 79.607415 -208.165624) (xy 79.714273 -208.259671) (xy 79.815638 -208.359612) (xy 79.911187 -208.465128)
			(xy 80.000614 -208.575881) (xy 80.083632 -208.691515) (xy 80.159974 -208.811662) (xy 80.229397 -208.935934)
			(xy 80.291678 -209.063936) (xy 80.346618 -209.195256) (xy 80.39404 -209.329473) (xy 80.433793 -209.466159)
			(xy 80.465749 -209.604875) (xy 80.489806 -209.745176) (xy 80.505887 -209.886614) (xy 80.51394 -210.028735)
			(xy 80.514444 -210.09991) (xy 80.51394 -210.171085) (xy 80.505887 -210.313206) (xy 80.489806 -210.454644)
			(xy 80.465749 -210.594945) (xy 80.433793 -210.733661) (xy 80.39404 -210.870347) (xy 80.346618 -211.004564)
			(xy 80.291678 -211.135884) (xy 80.229397 -211.263886) (xy 80.159974 -211.388158) (xy 80.083632 -211.508305)
			(xy 80.000614 -211.623939) (xy 79.911187 -211.734692) (xy 79.815638 -211.840208) (xy 79.714273 -211.940149)
			(xy 79.607415 -212.034196) (xy 79.495408 -212.122046) (xy 79.37861 -212.203419) (xy 79.257396 -212.278054)
			(xy 79.132153 -212.345711) (xy 79.003283 -212.406174) (xy 78.871199 -212.45925) (xy 78.736324 -212.504768)
			(xy 78.599089 -212.542583) (xy 78.459935 -212.572573) (xy 78.319307 -212.594642) (xy 78.177656 -212.60872)
			(xy 78.035435 -212.614762) (xy 77.8931 -212.612747) (xy 77.751107 -212.602684) (xy 77.609911 -212.584603)
			(xy 77.469964 -212.558563) (xy 77.331714 -212.524647) (xy 77.195605 -212.482964) (xy 77.062071 -212.433647)
			(xy 76.931542 -212.376855) (xy 76.804435 -212.312768) (xy 76.681157 -212.241594) (xy 76.562103 -212.163559)
			(xy 76.447655 -212.078913) (xy 76.338179 -211.987929) (xy 76.234025 -211.890896) (xy 76.135528 -211.788126)
			(xy 76.043004 -211.679948) (xy 75.956747 -211.566709) (xy 75.877035 -211.448772) (xy 75.804123 -211.326513)
			(xy 75.738245 -211.200326) (xy 75.679611 -211.070613) (xy 75.62841 -210.937791) (xy 75.584805 -210.802285)
			(xy 75.548936 -210.664529) (xy 75.520918 -210.524965) (xy 75.500841 -210.384038) (xy 75.488769 -210.242202)
			(xy 75.484741 -210.09991) (xy 72.995543 -210.09991) (xy 72.99955 -210.30013) (xy 73.011564 -210.50003)
			(xy 73.031567 -210.699288) (xy 73.059526 -210.897587) (xy 73.095397 -211.094609) (xy 73.139121 -211.290037)
			(xy 73.19063 -211.48356) (xy 73.24984 -211.674867) (xy 73.316657 -211.863651) (xy 73.390973 -212.049612)
			(xy 73.47267 -212.23245) (xy 73.561617 -212.411873) (xy 73.657672 -212.587593) (xy 73.76068 -212.75933)
			(xy 73.870476 -212.926808) (xy 73.986886 -213.089759) (xy 74.109722 -213.247921) (xy 74.238787 -213.401043)
			(xy 74.373876 -213.548878) (xy 74.514771 -213.69119) (xy 74.661247 -213.827751) (xy 74.81307 -213.958342)
			(xy 74.969996 -214.082754) (xy 75.131774 -214.200788) (xy 75.298145 -214.312255) (xy 75.468842 -214.416976)
			(xy 75.643593 -214.514784) (xy 75.822117 -214.605521) (xy 76.004129 -214.689044) (xy 76.189336 -214.765217)
			(xy 76.377443 -214.833919) (xy 76.568148 -214.89504) (xy 76.761145 -214.948482) (xy 76.956127 -214.99416)
			(xy 77.152779 -215.032) (xy 77.350789 -215.061941) (xy 77.549837 -215.083937) (xy 77.749606 -215.097951)
			(xy 77.949776 -215.103961) (xy 78.150027 -215.101957) (xy 78.350036 -215.091943) (xy 78.549485 -215.073935)
			(xy 78.748054 -215.047961) (xy 78.945424 -215.014064) (xy 79.141281 -214.972297) (xy 79.335309 -214.922727)
			(xy 79.527199 -214.865434) (xy 79.716642 -214.800509) (xy 79.903337 -214.728057) (xy 80.086983 -214.648193)
			(xy 80.267287 -214.561046) (xy 80.44396 -214.466754) (xy 80.616718 -214.365469) (xy 80.785286 -214.257354)
			(xy 80.949394 -214.142581) (xy 81.108778 -214.021333) (xy 81.263183 -213.893806) (xy 81.412362 -213.760203)
			(xy 81.556077 -213.620739) (xy 81.694096 -213.475637) (xy 81.8262 -213.325128) (xy 81.952176 -213.169455)
			(xy 82.071822 -213.008866) (xy 82.184948 -212.843618) (xy 82.291372 -212.673977) (xy 82.390923 -212.500213)
			(xy 82.483442 -212.322606) (xy 82.568781 -212.141439) (xy 82.646804 -211.957003) (xy 82.717384 -211.769593)
			(xy 82.78041 -211.57951) (xy 82.835781 -211.387056) (xy 82.883407 -211.192542) (xy 82.923212 -210.996277)
			(xy 82.955133 -210.798578) (xy 82.979119 -210.599759) (xy 82.995131 -210.40014) (xy 83.003143 -210.20004)
		)
		(stroke
			(width 0)
			(type solid)
		)
		(fill yes)
		(layer "B.Cu")
		(net "GND")
	)
	(gr_poly
		(pts
			(xy 83.003644 -121.19991) (xy 83.003143 -121.09978) (xy 82.995131 -120.89968) (xy 82.979119 -120.700061)
			(xy 82.955133 -120.501242) (xy 82.923212 -120.303543) (xy 82.883407 -120.107278) (xy 82.835781 -119.912764)
			(xy 82.78041 -119.72031) (xy 82.717384 -119.530227) (xy 82.646804 -119.342817) (xy 82.568781 -119.158381)
			(xy 82.483442 -118.977214) (xy 82.390923 -118.799607) (xy 82.291372 -118.625843) (xy 82.184948 -118.456202)
			(xy 82.071822 -118.290954) (xy 81.952176 -118.130365) (xy 81.8262 -117.974692) (xy 81.694096 -117.824183)
			(xy 81.556077 -117.679081) (xy 81.412362 -117.539617) (xy 81.263183 -117.406014) (xy 81.108778 -117.278487)
			(xy 80.949394 -117.157239) (xy 80.785286 -117.042466) (xy 80.616718 -116.934351) (xy 80.44396 -116.833066)
			(xy 80.267287 -116.738774) (xy 80.086983 -116.651627) (xy 79.903337 -116.571763) (xy 79.716642 -116.499311)
			(xy 79.527199 -116.434386) (xy 79.335309 -116.377093) (xy 79.141281 -116.327523) (xy 78.945424 -116.285756)
			(xy 78.748054 -116.251859) (xy 78.549485 -116.225885) (xy 78.350036 -116.207877) (xy 78.150027 -116.197863)
			(xy 77.949776 -116.195859) (xy 77.749606 -116.201869) (xy 77.549837 -116.215883) (xy 77.350789 -116.237879)
			(xy 77.152779 -116.26782) (xy 76.956127 -116.30566) (xy 76.761145 -116.351338) (xy 76.568148 -116.40478)
			(xy 76.377443 -116.465901) (xy 76.189336 -116.534603) (xy 76.004129 -116.610776) (xy 75.822117 -116.694299)
			(xy 75.643593 -116.785036) (xy 75.468842 -116.882844) (xy 75.298145 -116.987565) (xy 75.131774 -117.099032)
			(xy 74.969996 -117.217066) (xy 74.81307 -117.341478) (xy 74.661247 -117.472069) (xy 74.514771 -117.60863)
			(xy 74.373876 -117.750942) (xy 74.238787 -117.898777) (xy 74.109722 -118.051899) (xy 73.986886 -118.210061)
			(xy 73.870476 -118.373012) (xy 73.76068 -118.54049) (xy 73.657672 -118.712227) (xy 73.561617 -118.887947)
			(xy 73.47267 -119.06737) (xy 73.390973 -119.250208) (xy 73.316657 -119.436169) (xy 73.24984 -119.624953)
			(xy 73.19063 -119.81626) (xy 73.139121 -120.009783) (xy 73.095397 -120.205211) (xy 73.059526 -120.402233)
			(xy 73.031567 -120.600532) (xy 73.011564 -120.79979) (xy 72.99955 -120.99969) (xy 72.995543 -121.19991)
			(xy 75.484741 -121.19991) (xy 75.488769 -121.057618) (xy 75.500841 -120.915782) (xy 75.520918 -120.774855)
			(xy 75.548936 -120.635291) (xy 75.584805 -120.497535) (xy 75.62841 -120.362029) (xy 75.679611 -120.229207)
			(xy 75.738245 -120.099494) (xy 75.804123 -119.973307) (xy 75.877035 -119.851048) (xy 75.956747 -119.733111)
			(xy 76.043004 -119.619872) (xy 76.135528 -119.511694) (xy 76.234025 -119.408924) (xy 76.338179 -119.311891)
			(xy 76.447655 -119.220907) (xy 76.562103 -119.136261) (xy 76.681157 -119.058226) (xy 76.804435 -118.987052)
			(xy 76.931542 -118.922965) (xy 77.062071 -118.866173) (xy 77.195605 -118.816856) (xy 77.331714 -118.775173)
			(xy 77.469964 -118.741257) (xy 77.609911 -118.715217) (xy 77.751107 -118.697136) (xy 77.8931 -118.687073)
			(xy 78.035435 -118.685058) (xy 78.177656 -118.6911) (xy 78.319307 -118.705178) (xy 78.459935 -118.727247)
			(xy 78.599089 -118.757237) (xy 78.736324 -118.795052) (xy 78.871199 -118.84057) (xy 79.003283 -118.893646)
			(xy 79.132153 -118.954109) (xy 79.257396 -119.021766) (xy 79.37861 -119.096401) (xy 79.495408 -119.177774)
			(xy 79.607415 -119.265624) (xy 79.714273 -119.359671) (xy 79.815638 -119.459612) (xy 79.911187 -119.565128)
			(xy 80.000614 -119.675881) (xy 80.083632 -119.791515) (xy 80.159974 -119.911662) (xy 80.229397 -120.035934)
			(xy 80.291678 -120.163936) (xy 80.346618 -120.295256) (xy 80.39404 -120.429473) (xy 80.433793 -120.566159)
			(xy 80.465749 -120.704875) (xy 80.489806 -120.845176) (xy 80.505887 -120.986614) (xy 80.51394 -121.128735)
			(xy 80.514444 -121.19991) (xy 80.51394 -121.271085) (xy 80.505887 -121.413206) (xy 80.489806 -121.554644)
			(xy 80.465749 -121.694945) (xy 80.433793 -121.833661) (xy 80.39404 -121.970347) (xy 80.346618 -122.104564)
			(xy 80.291678 -122.235884) (xy 80.229397 -122.363886) (xy 80.159974 -122.488158) (xy 80.083632 -122.608305)
			(xy 80.000614 -122.723939) (xy 79.911187 -122.834692) (xy 79.815638 -122.940208) (xy 79.714273 -123.040149)
			(xy 79.607415 -123.134196) (xy 79.495408 -123.222046) (xy 79.37861 -123.303419) (xy 79.257396 -123.378054)
			(xy 79.132153 -123.445711) (xy 79.003283 -123.506174) (xy 78.871199 -123.55925) (xy 78.736324 -123.604768)
			(xy 78.599089 -123.642583) (xy 78.459935 -123.672573) (xy 78.319307 -123.694642) (xy 78.177656 -123.70872)
			(xy 78.035435 -123.714762) (xy 77.8931 -123.712747) (xy 77.751107 -123.702684) (xy 77.609911 -123.684603)
			(xy 77.469964 -123.658563) (xy 77.331714 -123.624647) (xy 77.195605 -123.582964) (xy 77.062071 -123.533647)
			(xy 76.931542 -123.476855) (xy 76.804435 -123.412768) (xy 76.681157 -123.341594) (xy 76.562103 -123.263559)
			(xy 76.447655 -123.178913) (xy 76.338179 -123.087929) (xy 76.234025 -122.990896) (xy 76.135528 -122.888126)
			(xy 76.043004 -122.779948) (xy 75.956747 -122.666709) (xy 75.877035 -122.548772) (xy 75.804123 -122.426513)
			(xy 75.738245 -122.300326) (xy 75.679611 -122.170613) (xy 75.62841 -122.037791) (xy 75.584805 -121.902285)
			(xy 75.548936 -121.764529) (xy 75.520918 -121.624965) (xy 75.500841 -121.484038) (xy 75.488769 -121.342202)
			(xy 75.484741 -121.19991) (xy 72.995543 -121.19991) (xy 72.99955 -121.40013) (xy 73.011564 -121.60003)
			(xy 73.031567 -121.799288) (xy 73.059526 -121.997587) (xy 73.095397 -122.194609) (xy 73.139121 -122.390037)
			(xy 73.19063 -122.58356) (xy 73.24984 -122.774867) (xy 73.316657 -122.963651) (xy 73.390973 -123.149612)
			(xy 73.47267 -123.33245) (xy 73.561617 -123.511873) (xy 73.657672 -123.687593) (xy 73.76068 -123.85933)
			(xy 73.870476 -124.026808) (xy 73.986886 -124.189759) (xy 74.109722 -124.347921) (xy 74.238787 -124.501043)
			(xy 74.373876 -124.648878) (xy 74.514771 -124.79119) (xy 74.661247 -124.927751) (xy 74.81307 -125.058342)
			(xy 74.969996 -125.182754) (xy 75.131774 -125.300788) (xy 75.298145 -125.412255) (xy 75.468842 -125.516976)
			(xy 75.643593 -125.614784) (xy 75.822117 -125.705521) (xy 76.004129 -125.789044) (xy 76.189336 -125.865217)
			(xy 76.377443 -125.933919) (xy 76.568148 -125.99504) (xy 76.761145 -126.048482) (xy 76.956127 -126.09416)
			(xy 77.152779 -126.132) (xy 77.350789 -126.161941) (xy 77.549837 -126.183937) (xy 77.749606 -126.197951)
			(xy 77.949776 -126.203961) (xy 78.150027 -126.201957) (xy 78.350036 -126.191943) (xy 78.549485 -126.173935)
			(xy 78.748054 -126.147961) (xy 78.945424 -126.114064) (xy 79.141281 -126.072297) (xy 79.335309 -126.022727)
			(xy 79.527199 -125.965434) (xy 79.716642 -125.900509) (xy 79.903337 -125.828057) (xy 80.086983 -125.748193)
			(xy 80.267287 -125.661046) (xy 80.44396 -125.566754) (xy 80.616718 -125.465469) (xy 80.785286 -125.357354)
			(xy 80.949394 -125.242581) (xy 81.108778 -125.121333) (xy 81.263183 -124.993806) (xy 81.412362 -124.860203)
			(xy 81.556077 -124.720739) (xy 81.694096 -124.575637) (xy 81.8262 -124.425128) (xy 81.952176 -124.269455)
			(xy 82.071822 -124.108866) (xy 82.184948 -123.943618) (xy 82.291372 -123.773977) (xy 82.390923 -123.600213)
			(xy 82.483442 -123.422606) (xy 82.568781 -123.241439) (xy 82.646804 -123.057003) (xy 82.717384 -122.869593)
			(xy 82.78041 -122.67951) (xy 82.835781 -122.487056) (xy 82.883407 -122.292542) (xy 82.923212 -122.096277)
			(xy 82.955133 -121.898578) (xy 82.979119 -121.699759) (xy 82.995131 -121.50014) (xy 83.003143 -121.30004)
		)
		(stroke
			(width 0)
			(type solid)
		)
		(fill yes)
		(layer "B.Cu")
		(net "GND")
	)
	(gr_poly
		(pts
			(xy 83.003644 -32.29991) (xy 83.003143 -32.19978) (xy 82.995131 -31.99968) (xy 82.979119 -31.800061)
			(xy 82.955133 -31.601242) (xy 82.923212 -31.403543) (xy 82.883407 -31.207278) (xy 82.835781 -31.012764)
			(xy 82.78041 -30.82031) (xy 82.717384 -30.630227) (xy 82.646804 -30.442817) (xy 82.568781 -30.258381)
			(xy 82.483442 -30.077214) (xy 82.390923 -29.899607) (xy 82.291372 -29.725843) (xy 82.184948 -29.556202)
			(xy 82.071822 -29.390954) (xy 81.952176 -29.230365) (xy 81.8262 -29.074692) (xy 81.694096 -28.924183)
			(xy 81.556077 -28.779081) (xy 81.412362 -28.639617) (xy 81.263183 -28.506014) (xy 81.108778 -28.378487)
			(xy 80.949394 -28.257239) (xy 80.785286 -28.142466) (xy 80.616718 -28.034351) (xy 80.44396 -27.933066)
			(xy 80.267287 -27.838774) (xy 80.086983 -27.751627) (xy 79.903337 -27.671763) (xy 79.716642 -27.599311)
			(xy 79.527199 -27.534386) (xy 79.335309 -27.477093) (xy 79.141281 -27.427523) (xy 78.945424 -27.385756)
			(xy 78.748054 -27.351859) (xy 78.549485 -27.325885) (xy 78.350036 -27.307877) (xy 78.150027 -27.297863)
			(xy 77.949776 -27.295859) (xy 77.749606 -27.301869) (xy 77.549837 -27.315883) (xy 77.350789 -27.337879)
			(xy 77.152779 -27.36782) (xy 76.956127 -27.40566) (xy 76.761145 -27.451338) (xy 76.568148 -27.50478)
			(xy 76.377443 -27.565901) (xy 76.189336 -27.634603) (xy 76.004129 -27.710776) (xy 75.822117 -27.794299)
			(xy 75.643593 -27.885036) (xy 75.468842 -27.982844) (xy 75.298145 -28.087565) (xy 75.131774 -28.199032)
			(xy 74.969996 -28.317066) (xy 74.81307 -28.441478) (xy 74.661247 -28.572069) (xy 74.514771 -28.70863)
			(xy 74.373876 -28.850942) (xy 74.238787 -28.998777) (xy 74.109722 -29.151899) (xy 73.986886 -29.310061)
			(xy 73.870476 -29.473012) (xy 73.76068 -29.64049) (xy 73.657672 -29.812227) (xy 73.561617 -29.987947)
			(xy 73.47267 -30.16737) (xy 73.390973 -30.350208) (xy 73.316657 -30.536169) (xy 73.24984 -30.724953)
			(xy 73.19063 -30.91626) (xy 73.139121 -31.109783) (xy 73.095397 -31.305211) (xy 73.059526 -31.502233)
			(xy 73.031567 -31.700532) (xy 73.011564 -31.89979) (xy 72.99955 -32.09969) (xy 72.995543 -32.29991)
			(xy 75.484741 -32.29991) (xy 75.488769 -32.157618) (xy 75.500841 -32.015782) (xy 75.520918 -31.874855)
			(xy 75.548936 -31.735291) (xy 75.584805 -31.597535) (xy 75.62841 -31.462029) (xy 75.679611 -31.329207)
			(xy 75.738245 -31.199494) (xy 75.804123 -31.073307) (xy 75.877035 -30.951048) (xy 75.956747 -30.833111)
			(xy 76.043004 -30.719872) (xy 76.135528 -30.611694) (xy 76.234025 -30.508924) (xy 76.338179 -30.411891)
			(xy 76.447655 -30.320907) (xy 76.562103 -30.236261) (xy 76.681157 -30.158226) (xy 76.804435 -30.087052)
			(xy 76.931542 -30.022965) (xy 77.062071 -29.966173) (xy 77.195605 -29.916856) (xy 77.331714 -29.875173)
			(xy 77.469964 -29.841257) (xy 77.609911 -29.815217) (xy 77.751107 -29.797136) (xy 77.8931 -29.787073)
			(xy 78.035435 -29.785058) (xy 78.177656 -29.7911) (xy 78.319307 -29.805178) (xy 78.459935 -29.827247)
			(xy 78.599089 -29.857237) (xy 78.736324 -29.895052) (xy 78.871199 -29.94057) (xy 79.003283 -29.993646)
			(xy 79.132153 -30.054109) (xy 79.257396 -30.121766) (xy 79.37861 -30.196401) (xy 79.495408 -30.277774)
			(xy 79.607415 -30.365624) (xy 79.714273 -30.459671) (xy 79.815638 -30.559612) (xy 79.911187 -30.665128)
			(xy 80.000614 -30.775881) (xy 80.083632 -30.891515) (xy 80.159974 -31.011662) (xy 80.229397 -31.135934)
			(xy 80.291678 -31.263936) (xy 80.346618 -31.395256) (xy 80.39404 -31.529473) (xy 80.433793 -31.666159)
			(xy 80.465749 -31.804875) (xy 80.489806 -31.945176) (xy 80.505887 -32.086614) (xy 80.51394 -32.228735)
			(xy 80.514444 -32.29991) (xy 80.51394 -32.371085) (xy 80.505887 -32.513206) (xy 80.489806 -32.654644)
			(xy 80.465749 -32.794945) (xy 80.433793 -32.933661) (xy 80.39404 -33.070347) (xy 80.346618 -33.204564)
			(xy 80.291678 -33.335884) (xy 80.229397 -33.463886) (xy 80.159974 -33.588158) (xy 80.083632 -33.708305)
			(xy 80.000614 -33.823939) (xy 79.911187 -33.934692) (xy 79.815638 -34.040208) (xy 79.714273 -34.140149)
			(xy 79.607415 -34.234196) (xy 79.495408 -34.322046) (xy 79.37861 -34.403419) (xy 79.257396 -34.478054)
			(xy 79.132153 -34.545711) (xy 79.003283 -34.606174) (xy 78.871199 -34.65925) (xy 78.736324 -34.704768)
			(xy 78.599089 -34.742583) (xy 78.459935 -34.772573) (xy 78.319307 -34.794642) (xy 78.177656 -34.80872)
			(xy 78.035435 -34.814762) (xy 77.8931 -34.812747) (xy 77.751107 -34.802684) (xy 77.609911 -34.784603)
			(xy 77.469964 -34.758563) (xy 77.331714 -34.724647) (xy 77.195605 -34.682964) (xy 77.062071 -34.633647)
			(xy 76.931542 -34.576855) (xy 76.804435 -34.512768) (xy 76.681157 -34.441594) (xy 76.562103 -34.363559)
			(xy 76.447655 -34.278913) (xy 76.338179 -34.187929) (xy 76.234025 -34.090896) (xy 76.135528 -33.988126)
			(xy 76.043004 -33.879948) (xy 75.956747 -33.766709) (xy 75.877035 -33.648772) (xy 75.804123 -33.526513)
			(xy 75.738245 -33.400326) (xy 75.679611 -33.270613) (xy 75.62841 -33.137791) (xy 75.584805 -33.002285)
			(xy 75.548936 -32.864529) (xy 75.520918 -32.724965) (xy 75.500841 -32.584038) (xy 75.488769 -32.442202)
			(xy 75.484741 -32.29991) (xy 72.995543 -32.29991) (xy 72.99955 -32.50013) (xy 73.011564 -32.70003)
			(xy 73.031567 -32.899288) (xy 73.059526 -33.097587) (xy 73.095397 -33.294609) (xy 73.139121 -33.490037)
			(xy 73.19063 -33.68356) (xy 73.24984 -33.874867) (xy 73.316657 -34.063651) (xy 73.390973 -34.249612)
			(xy 73.47267 -34.43245) (xy 73.561617 -34.611873) (xy 73.657672 -34.787593) (xy 73.76068 -34.95933)
			(xy 73.870476 -35.126808) (xy 73.986886 -35.289759) (xy 74.109722 -35.447921) (xy 74.238787 -35.601043)
			(xy 74.373876 -35.748878) (xy 74.514771 -35.89119) (xy 74.661247 -36.027751) (xy 74.81307 -36.158342)
			(xy 74.969996 -36.282754) (xy 75.131774 -36.400788) (xy 75.298145 -36.512255) (xy 75.468842 -36.616976)
			(xy 75.643593 -36.714784) (xy 75.822117 -36.805521) (xy 76.004129 -36.889044) (xy 76.189336 -36.965217)
			(xy 76.377443 -37.033919) (xy 76.568148 -37.09504) (xy 76.761145 -37.148482) (xy 76.956127 -37.19416)
			(xy 77.152779 -37.232) (xy 77.350789 -37.261941) (xy 77.549837 -37.283937) (xy 77.749606 -37.297951)
			(xy 77.949776 -37.303961) (xy 78.150027 -37.301957) (xy 78.350036 -37.291943) (xy 78.549485 -37.273935)
			(xy 78.748054 -37.247961) (xy 78.945424 -37.214064) (xy 79.141281 -37.172297) (xy 79.335309 -37.122727)
			(xy 79.527199 -37.065434) (xy 79.716642 -37.000509) (xy 79.903337 -36.928057) (xy 80.086983 -36.848193)
			(xy 80.267287 -36.761046) (xy 80.44396 -36.666754) (xy 80.616718 -36.565469) (xy 80.785286 -36.457354)
			(xy 80.949394 -36.342581) (xy 81.108778 -36.221333) (xy 81.263183 -36.093806) (xy 81.412362 -35.960203)
			(xy 81.556077 -35.820739) (xy 81.694096 -35.675637) (xy 81.8262 -35.525128) (xy 81.952176 -35.369455)
			(xy 82.071822 -35.208866) (xy 82.184948 -35.043618) (xy 82.291372 -34.873977) (xy 82.390923 -34.700213)
			(xy 82.483442 -34.522606) (xy 82.568781 -34.341439) (xy 82.646804 -34.157003) (xy 82.717384 -33.969593)
			(xy 82.78041 -33.77951) (xy 82.835781 -33.587056) (xy 82.883407 -33.392542) (xy 82.923212 -33.196277)
			(xy 82.955133 -32.998578) (xy 82.979119 -32.799759) (xy 82.995131 -32.60014) (xy 83.003143 -32.40004)
		)
		(stroke
			(width 0)
			(type solid)
		)
		(fill yes)
		(layer "B.Cu")
		(net "GND")
	)
	(gr_poly
		(pts
			(xy 83.003898 -519.049762) (xy 83.003397 -518.949632) (xy 82.995385 -518.749532) (xy 82.979373 -518.549913)
			(xy 82.955387 -518.351094) (xy 82.923466 -518.153395) (xy 82.883661 -517.95713) (xy 82.836035 -517.762616)
			(xy 82.780664 -517.570162) (xy 82.717638 -517.380079) (xy 82.647058 -517.192669) (xy 82.569035 -517.008233)
			(xy 82.483696 -516.827066) (xy 82.391177 -516.649459) (xy 82.291626 -516.475695) (xy 82.185202 -516.306054)
			(xy 82.072076 -516.140806) (xy 81.95243 -515.980217) (xy 81.826454 -515.824544) (xy 81.69435 -515.674035)
			(xy 81.556331 -515.528933) (xy 81.412616 -515.389469) (xy 81.263437 -515.255866) (xy 81.109032 -515.128339)
			(xy 80.949648 -515.007091) (xy 80.78554 -514.892318) (xy 80.616972 -514.784203) (xy 80.444214 -514.682918)
			(xy 80.267541 -514.588626) (xy 80.087237 -514.501479) (xy 79.903591 -514.421615) (xy 79.716896 -514.349163)
			(xy 79.527453 -514.284238) (xy 79.335563 -514.226945) (xy 79.141535 -514.177375) (xy 78.945678 -514.135608)
			(xy 78.748308 -514.101711) (xy 78.549739 -514.075737) (xy 78.35029 -514.057729) (xy 78.150281 -514.047715)
			(xy 77.95003 -514.045711) (xy 77.74986 -514.051721) (xy 77.550091 -514.065735) (xy 77.351043 -514.087731)
			(xy 77.153033 -514.117672) (xy 76.956381 -514.155512) (xy 76.761399 -514.20119) (xy 76.568402 -514.254632)
			(xy 76.377697 -514.315753) (xy 76.18959 -514.384455) (xy 76.004383 -514.460628) (xy 75.822371 -514.544151)
			(xy 75.643847 -514.634888) (xy 75.469096 -514.732696) (xy 75.298399 -514.837417) (xy 75.132028 -514.948884)
			(xy 74.97025 -515.066918) (xy 74.813324 -515.19133) (xy 74.661501 -515.321921) (xy 74.515025 -515.458482)
			(xy 74.37413 -515.600794) (xy 74.239041 -515.748629) (xy 74.109976 -515.901751) (xy 73.98714 -516.059913)
			(xy 73.87073 -516.222864) (xy 73.760934 -516.390342) (xy 73.657926 -516.562079) (xy 73.561871 -516.737799)
			(xy 73.472924 -516.917222) (xy 73.391227 -517.10006) (xy 73.316911 -517.286021) (xy 73.250094 -517.474805)
			(xy 73.190884 -517.666112) (xy 73.139375 -517.859635) (xy 73.095651 -518.055063) (xy 73.05978 -518.252085)
			(xy 73.031821 -518.450384) (xy 73.011818 -518.649642) (xy 72.999804 -518.849542) (xy 72.995797 -519.049762)
			(xy 75.484995 -519.049762) (xy 75.489023 -518.90747) (xy 75.501095 -518.765634) (xy 75.521172 -518.624707)
			(xy 75.54919 -518.485143) (xy 75.585059 -518.347387) (xy 75.628664 -518.211881) (xy 75.679865 -518.079059)
			(xy 75.738499 -517.949346) (xy 75.804377 -517.823159) (xy 75.877289 -517.7009) (xy 75.957001 -517.582963)
			(xy 76.043258 -517.469724) (xy 76.135782 -517.361546) (xy 76.234279 -517.258776) (xy 76.338433 -517.161743)
			(xy 76.447909 -517.070759) (xy 76.562357 -516.986113) (xy 76.681411 -516.908078) (xy 76.804689 -516.836904)
			(xy 76.931796 -516.772817) (xy 77.062325 -516.716025) (xy 77.195859 -516.666708) (xy 77.331968 -516.625025)
			(xy 77.470218 -516.591109) (xy 77.610165 -516.565069) (xy 77.751361 -516.546988) (xy 77.893354 -516.536925)
			(xy 78.035689 -516.53491) (xy 78.17791 -516.540952) (xy 78.319561 -516.55503) (xy 78.460189 -516.577099)
			(xy 78.599343 -516.607089) (xy 78.736578 -516.644904) (xy 78.871453 -516.690422) (xy 79.003537 -516.743498)
			(xy 79.132407 -516.803961) (xy 79.25765 -516.871618) (xy 79.378864 -516.946253) (xy 79.495662 -517.027626)
			(xy 79.607669 -517.115476) (xy 79.714527 -517.209523) (xy 79.815892 -517.309464) (xy 79.911441 -517.41498)
			(xy 80.000868 -517.525733) (xy 80.083886 -517.641367) (xy 80.160228 -517.761514) (xy 80.229651 -517.885786)
			(xy 80.291932 -518.013788) (xy 80.346872 -518.145108) (xy 80.394294 -518.279325) (xy 80.434047 -518.416011)
			(xy 80.466003 -518.554727) (xy 80.49006 -518.695028) (xy 80.506141 -518.836466) (xy 80.514194 -518.978587)
			(xy 80.514698 -519.049762) (xy 80.514194 -519.120937) (xy 80.506141 -519.263058) (xy 80.49006 -519.404496)
			(xy 80.466003 -519.544797) (xy 80.434047 -519.683513) (xy 80.394294 -519.820199) (xy 80.346872 -519.954416)
			(xy 80.291932 -520.085736) (xy 80.229651 -520.213738) (xy 80.160228 -520.33801) (xy 80.083886 -520.458157)
			(xy 80.000868 -520.573791) (xy 79.911441 -520.684544) (xy 79.815892 -520.79006) (xy 79.714527 -520.890001)
			(xy 79.607669 -520.984048) (xy 79.495662 -521.071898) (xy 79.378864 -521.153271) (xy 79.25765 -521.227906)
			(xy 79.132407 -521.295563) (xy 79.003537 -521.356026) (xy 78.871453 -521.409102) (xy 78.736578 -521.45462)
			(xy 78.599343 -521.492435) (xy 78.460189 -521.522425) (xy 78.319561 -521.544494) (xy 78.17791 -521.558572)
			(xy 78.035689 -521.564614) (xy 77.893354 -521.562599) (xy 77.751361 -521.552536) (xy 77.610165 -521.534455)
			(xy 77.470218 -521.508415) (xy 77.331968 -521.474499) (xy 77.195859 -521.432816) (xy 77.062325 -521.383499)
			(xy 76.931796 -521.326707) (xy 76.804689 -521.26262) (xy 76.681411 -521.191446) (xy 76.562357 -521.113411)
			(xy 76.447909 -521.028765) (xy 76.338433 -520.937781) (xy 76.234279 -520.840748) (xy 76.135782 -520.737978)
			(xy 76.043258 -520.6298) (xy 75.957001 -520.516561) (xy 75.877289 -520.398624) (xy 75.804377 -520.276365)
			(xy 75.738499 -520.150178) (xy 75.679865 -520.020465) (xy 75.628664 -519.887643) (xy 75.585059 -519.752137)
			(xy 75.54919 -519.614381) (xy 75.521172 -519.474817) (xy 75.501095 -519.33389) (xy 75.489023 -519.192054)
			(xy 75.484995 -519.049762) (xy 72.995797 -519.049762) (xy 72.999804 -519.249982) (xy 73.011818 -519.449882)
			(xy 73.031821 -519.64914) (xy 73.05978 -519.847439) (xy 73.095651 -520.044461) (xy 73.139375 -520.239889)
			(xy 73.190884 -520.433412) (xy 73.250094 -520.624719) (xy 73.316911 -520.813503) (xy 73.391227 -520.999464)
			(xy 73.472924 -521.182302) (xy 73.561871 -521.361725) (xy 73.657926 -521.537445) (xy 73.760934 -521.709182)
			(xy 73.87073 -521.87666) (xy 73.98714 -522.039611) (xy 74.109976 -522.197773) (xy 74.239041 -522.350895)
			(xy 74.37413 -522.49873) (xy 74.515025 -522.641042) (xy 74.661501 -522.777603) (xy 74.813324 -522.908194)
			(xy 74.97025 -523.032606) (xy 75.132028 -523.15064) (xy 75.298399 -523.262107) (xy 75.469096 -523.366828)
			(xy 75.643847 -523.464636) (xy 75.822371 -523.555373) (xy 76.004383 -523.638896) (xy 76.18959 -523.715069)
			(xy 76.377697 -523.783771) (xy 76.568402 -523.844892) (xy 76.761399 -523.898334) (xy 76.956381 -523.944012)
			(xy 77.153033 -523.981852) (xy 77.351043 -524.011793) (xy 77.550091 -524.033789) (xy 77.74986 -524.047803)
			(xy 77.95003 -524.053813) (xy 78.150281 -524.051809) (xy 78.35029 -524.041795) (xy 78.549739 -524.023787)
			(xy 78.748308 -523.997813) (xy 78.945678 -523.963916) (xy 79.141535 -523.922149) (xy 79.335563 -523.872579)
			(xy 79.527453 -523.815286) (xy 79.716896 -523.750361) (xy 79.903591 -523.677909) (xy 80.087237 -523.598045)
			(xy 80.267541 -523.510898) (xy 80.444214 -523.416606) (xy 80.616972 -523.315321) (xy 80.78554 -523.207206)
			(xy 80.949648 -523.092433) (xy 81.109032 -522.971185) (xy 81.263437 -522.843658) (xy 81.412616 -522.710055)
			(xy 81.556331 -522.570591) (xy 81.69435 -522.425489) (xy 81.826454 -522.27498) (xy 81.95243 -522.119307)
			(xy 82.072076 -521.958718) (xy 82.185202 -521.79347) (xy 82.291626 -521.623829) (xy 82.391177 -521.450065)
			(xy 82.483696 -521.272458) (xy 82.569035 -521.091291) (xy 82.647058 -520.906855) (xy 82.717638 -520.719445)
			(xy 82.780664 -520.529362) (xy 82.836035 -520.336908) (xy 82.883661 -520.142394) (xy 82.923466 -519.946129)
			(xy 82.955387 -519.74843) (xy 82.979373 -519.549611) (xy 82.995385 -519.349992) (xy 83.003397 -519.149892)
		)
		(stroke
			(width 0)
			(type solid)
		)
		(fill yes)
		(layer "B.Cu")
		(net "GND")
	)
	(gr_poly
		(pts
			(xy 16.599916 -468.69604) (xy 16.499786 -468.696541) (xy 16.299686 -468.704553) (xy 16.100067 -468.720565)
			(xy 15.901248 -468.744551) (xy 15.703549 -468.776472) (xy 15.507284 -468.816277) (xy 15.31277 -468.863903)
			(xy 15.120316 -468.919274) (xy 14.930233 -468.9823) (xy 14.742823 -469.05288) (xy 14.558387 -469.130903)
			(xy 14.37722 -469.216242) (xy 14.199613 -469.308761) (xy 14.025849 -469.408312) (xy 13.856208 -469.514736)
			(xy 13.69096 -469.627862) (xy 13.530371 -469.747508) (xy 13.374698 -469.873484) (xy 13.224189 -470.005588)
			(xy 13.079087 -470.143607) (xy 12.939623 -470.287322) (xy 12.80602 -470.436501) (xy 12.678493 -470.590906)
			(xy 12.557245 -470.75029) (xy 12.442472 -470.914398) (xy 12.334357 -471.082966) (xy 12.233072 -471.255724)
			(xy 12.13878 -471.432397) (xy 12.051633 -471.612701) (xy 11.971769 -471.796347) (xy 11.899317 -471.983042)
			(xy 11.834392 -472.172485) (xy 11.777099 -472.364375) (xy 11.727529 -472.558403) (xy 11.685762 -472.75426)
			(xy 11.651865 -472.95163) (xy 11.625891 -473.150199) (xy 11.607883 -473.349648) (xy 11.597869 -473.549657)
			(xy 11.596722 -473.664249) (xy 14.085064 -473.664249) (xy 14.091106 -473.522028) (xy 14.105184 -473.380377)
			(xy 14.127253 -473.239749) (xy 14.157243 -473.100595) (xy 14.195058 -472.96336) (xy 14.240576 -472.828485)
			(xy 14.293652 -472.696401) (xy 14.354115 -472.567531) (xy 14.421772 -472.442288) (xy 14.496407 -472.321074)
			(xy 14.57778 -472.204276) (xy 14.66563 -472.092269) (xy 14.759677 -471.985411) (xy 14.859618 -471.884046)
			(xy 14.965134 -471.788497) (xy 15.075887 -471.69907) (xy 15.191521 -471.616052) (xy 15.311668 -471.53971)
			(xy 15.43594 -471.470287) (xy 15.563942 -471.408006) (xy 15.695262 -471.353066) (xy 15.829479 -471.305644)
			(xy 15.966165 -471.265891) (xy 16.104881 -471.233935) (xy 16.245182 -471.209878) (xy 16.38662 -471.193797)
			(xy 16.528741 -471.185744) (xy 16.599916 -471.18524) (xy 16.671091 -471.185744) (xy 16.813212 -471.193797)
			(xy 16.95465 -471.209878) (xy 17.094951 -471.233935) (xy 17.233667 -471.265891) (xy 17.370353 -471.305644)
			(xy 17.50457 -471.353066) (xy 17.63589 -471.408006) (xy 17.763892 -471.470287) (xy 17.888164 -471.53971)
			(xy 18.008311 -471.616052) (xy 18.123945 -471.69907) (xy 18.234698 -471.788497) (xy 18.340214 -471.884046)
			(xy 18.440155 -471.985411) (xy 18.534202 -472.092269) (xy 18.622052 -472.204276) (xy 18.703425 -472.321074)
			(xy 18.77806 -472.442288) (xy 18.845717 -472.567531) (xy 18.90618 -472.696401) (xy 18.959256 -472.828485)
			(xy 19.004774 -472.96336) (xy 19.042589 -473.100595) (xy 19.072579 -473.239749) (xy 19.094648 -473.380377)
			(xy 19.108726 -473.522028) (xy 19.114768 -473.664249) (xy 19.112753 -473.806584) (xy 19.10269 -473.948577)
			(xy 19.084609 -474.089773) (xy 19.058569 -474.22972) (xy 19.024653 -474.36797) (xy 18.98297 -474.504079)
			(xy 18.933653 -474.637613) (xy 18.876861 -474.768142) (xy 18.812774 -474.895249) (xy 18.7416 -475.018527)
			(xy 18.663565 -475.137581) (xy 18.578919 -475.252029) (xy 18.487935 -475.361505) (xy 18.390902 -475.465659)
			(xy 18.288132 -475.564156) (xy 18.179954 -475.65668) (xy 18.066715 -475.742937) (xy 17.948778 -475.822649)
			(xy 17.826519 -475.895561) (xy 17.700332 -475.961439) (xy 17.570619 -476.020073) (xy 17.437797 -476.071274)
			(xy 17.302291 -476.114879) (xy 17.164535 -476.150748) (xy 17.024971 -476.178766) (xy 16.884044 -476.198843)
			(xy 16.742208 -476.210915) (xy 16.599916 -476.214944) (xy 16.457624 -476.210915) (xy 16.315788 -476.198843)
			(xy 16.174861 -476.178766) (xy 16.035297 -476.150748) (xy 15.897541 -476.114879) (xy 15.762035 -476.071274)
			(xy 15.629213 -476.020073) (xy 15.4995 -475.961439) (xy 15.373313 -475.895561) (xy 15.251054 -475.822649)
			(xy 15.133117 -475.742937) (xy 15.019878 -475.65668) (xy 14.9117 -475.564156) (xy 14.80893 -475.465659)
			(xy 14.711897 -475.361505) (xy 14.620913 -475.252029) (xy 14.536267 -475.137581) (xy 14.458232 -475.018527)
			(xy 14.387058 -474.895249) (xy 14.322971 -474.768142) (xy 14.266179 -474.637613) (xy 14.216862 -474.504079)
			(xy 14.175179 -474.36797) (xy 14.141263 -474.22972) (xy 14.115223 -474.089773) (xy 14.097142 -473.948577)
			(xy 14.087079 -473.806584) (xy 14.085064 -473.664249) (xy 11.596722 -473.664249) (xy 11.595865 -473.749908)
			(xy 11.601875 -473.950078) (xy 11.615889 -474.149847) (xy 11.637885 -474.348895) (xy 11.667826 -474.546905)
			(xy 11.705666 -474.743557) (xy 11.751344 -474.938539) (xy 11.804786 -475.131536) (xy 11.865907 -475.322241)
			(xy 11.934609 -475.510348) (xy 12.010782 -475.695555) (xy 12.094305 -475.877567) (xy 12.185042 -476.056091)
			(xy 12.28285 -476.230842) (xy 12.387571 -476.401539) (xy 12.499038 -476.56791) (xy 12.617072 -476.729688)
			(xy 12.741484 -476.886614) (xy 12.872075 -477.038437) (xy 13.008636 -477.184913) (xy 13.150948 -477.325808)
			(xy 13.298783 -477.460897) (xy 13.451905 -477.589962) (xy 13.610067 -477.712798) (xy 13.773018 -477.829208)
			(xy 13.940496 -477.939004) (xy 14.112233 -478.042012) (xy 14.287953 -478.138067) (xy 14.467376 -478.227014)
			(xy 14.650214 -478.308711) (xy 14.836175 -478.383027) (xy 15.024959 -478.449844) (xy 15.216266 -478.509054)
			(xy 15.409789 -478.560563) (xy 15.605217 -478.604287) (xy 15.802239 -478.640158) (xy 16.000538 -478.668117)
			(xy 16.199796 -478.68812) (xy 16.399696 -478.700134) (xy 16.599916 -478.704141) (xy 16.800136 -478.700134)
			(xy 17.000036 -478.68812) (xy 17.199294 -478.668117) (xy 17.397593 -478.640158) (xy 17.594615 -478.604287)
			(xy 17.790043 -478.560563) (xy 17.983566 -478.509054) (xy 18.174873 -478.449844) (xy 18.363657 -478.383027)
			(xy 18.549618 -478.308711) (xy 18.732456 -478.227014) (xy 18.911879 -478.138067) (xy 19.087599 -478.042012)
			(xy 19.259336 -477.939004) (xy 19.426814 -477.829208) (xy 19.589765 -477.712798) (xy 19.747927 -477.589962)
			(xy 19.901049 -477.460897) (xy 20.048884 -477.325808) (xy 20.191196 -477.184913) (xy 20.327757 -477.038437)
			(xy 20.458348 -476.886614) (xy 20.58276 -476.729688) (xy 20.700794 -476.56791) (xy 20.812261 -476.401539)
			(xy 20.916982 -476.230842) (xy 21.01479 -476.056091) (xy 21.105527 -475.877567) (xy 21.18905 -475.695555)
			(xy 21.265223 -475.510348) (xy 21.333925 -475.322241) (xy 21.395046 -475.131536) (xy 21.448488 -474.938539)
			(xy 21.494166 -474.743557) (xy 21.532006 -474.546905) (xy 21.561947 -474.348895) (xy 21.583943 -474.149847)
			(xy 21.597957 -473.950078) (xy 21.603967 -473.749908) (xy 21.601963 -473.549657) (xy 21.591949 -473.349648)
			(xy 21.573941 -473.150199) (xy 21.547967 -472.95163) (xy 21.51407 -472.75426) (xy 21.472303 -472.558403)
			(xy 21.422733 -472.364375) (xy 21.36544 -472.172485) (xy 21.300515 -471.983042) (xy 21.228063 -471.796347)
			(xy 21.148199 -471.612701) (xy 21.061052 -471.432397) (xy 20.96676 -471.255724) (xy 20.865475 -471.082966)
			(xy 20.75736 -470.914398) (xy 20.642587 -470.75029) (xy 20.521339 -470.590906) (xy 20.393812 -470.436501)
			(xy 20.260209 -470.287322) (xy 20.120745 -470.143607) (xy 19.975643 -470.005588) (xy 19.825134 -469.873484)
			(xy 19.669461 -469.747508) (xy 19.508872 -469.627862) (xy 19.343624 -469.514736) (xy 19.173983 -469.408312)
			(xy 19.000219 -469.308761) (xy 18.822612 -469.216242) (xy 18.641445 -469.130903) (xy 18.457009 -469.05288)
			(xy 18.269599 -468.9823) (xy 18.079516 -468.919274) (xy 17.887062 -468.863903) (xy 17.692548 -468.816277)
			(xy 17.496283 -468.776472) (xy 17.298584 -468.744551) (xy 17.099765 -468.720565) (xy 16.900146 -468.704553)
			(xy 16.700046 -468.696541)
		)
		(stroke
			(width 0)
			(type solid)
		)
		(fill yes)
		(layer "B.Cu")
		(net "GND")
	)
	(gr_poly
		(pts
			(xy 16.599916 -379.79604) (xy 16.499786 -379.796541) (xy 16.299686 -379.804553) (xy 16.100067 -379.820565)
			(xy 15.901248 -379.844551) (xy 15.703549 -379.876472) (xy 15.507284 -379.916277) (xy 15.31277 -379.963903)
			(xy 15.120316 -380.019274) (xy 14.930233 -380.0823) (xy 14.742823 -380.15288) (xy 14.558387 -380.230903)
			(xy 14.37722 -380.316242) (xy 14.199613 -380.408761) (xy 14.025849 -380.508312) (xy 13.856208 -380.614736)
			(xy 13.69096 -380.727862) (xy 13.530371 -380.847508) (xy 13.374698 -380.973484) (xy 13.224189 -381.105588)
			(xy 13.079087 -381.243607) (xy 12.939623 -381.387322) (xy 12.80602 -381.536501) (xy 12.678493 -381.690906)
			(xy 12.557245 -381.85029) (xy 12.442472 -382.014398) (xy 12.334357 -382.182966) (xy 12.233072 -382.355724)
			(xy 12.13878 -382.532397) (xy 12.051633 -382.712701) (xy 11.971769 -382.896347) (xy 11.899317 -383.083042)
			(xy 11.834392 -383.272485) (xy 11.777099 -383.464375) (xy 11.727529 -383.658403) (xy 11.685762 -383.85426)
			(xy 11.651865 -384.05163) (xy 11.625891 -384.250199) (xy 11.607883 -384.449648) (xy 11.597869 -384.649657)
			(xy 11.596722 -384.764249) (xy 14.085064 -384.764249) (xy 14.091106 -384.622028) (xy 14.105184 -384.480377)
			(xy 14.127253 -384.339749) (xy 14.157243 -384.200595) (xy 14.195058 -384.06336) (xy 14.240576 -383.928485)
			(xy 14.293652 -383.796401) (xy 14.354115 -383.667531) (xy 14.421772 -383.542288) (xy 14.496407 -383.421074)
			(xy 14.57778 -383.304276) (xy 14.66563 -383.192269) (xy 14.759677 -383.085411) (xy 14.859618 -382.984046)
			(xy 14.965134 -382.888497) (xy 15.075887 -382.79907) (xy 15.191521 -382.716052) (xy 15.311668 -382.63971)
			(xy 15.43594 -382.570287) (xy 15.563942 -382.508006) (xy 15.695262 -382.453066) (xy 15.829479 -382.405644)
			(xy 15.966165 -382.365891) (xy 16.104881 -382.333935) (xy 16.245182 -382.309878) (xy 16.38662 -382.293797)
			(xy 16.528741 -382.285744) (xy 16.599916 -382.28524) (xy 16.671091 -382.285744) (xy 16.813212 -382.293797)
			(xy 16.95465 -382.309878) (xy 17.094951 -382.333935) (xy 17.233667 -382.365891) (xy 17.370353 -382.405644)
			(xy 17.50457 -382.453066) (xy 17.63589 -382.508006) (xy 17.763892 -382.570287) (xy 17.888164 -382.63971)
			(xy 18.008311 -382.716052) (xy 18.123945 -382.79907) (xy 18.234698 -382.888497) (xy 18.340214 -382.984046)
			(xy 18.440155 -383.085411) (xy 18.534202 -383.192269) (xy 18.622052 -383.304276) (xy 18.703425 -383.421074)
			(xy 18.77806 -383.542288) (xy 18.845717 -383.667531) (xy 18.90618 -383.796401) (xy 18.959256 -383.928485)
			(xy 19.004774 -384.06336) (xy 19.042589 -384.200595) (xy 19.072579 -384.339749) (xy 19.094648 -384.480377)
			(xy 19.108726 -384.622028) (xy 19.114768 -384.764249) (xy 19.112753 -384.906584) (xy 19.10269 -385.048577)
			(xy 19.084609 -385.189773) (xy 19.058569 -385.32972) (xy 19.024653 -385.46797) (xy 18.98297 -385.604079)
			(xy 18.933653 -385.737613) (xy 18.876861 -385.868142) (xy 18.812774 -385.995249) (xy 18.7416 -386.118527)
			(xy 18.663565 -386.237581) (xy 18.578919 -386.352029) (xy 18.487935 -386.461505) (xy 18.390902 -386.565659)
			(xy 18.288132 -386.664156) (xy 18.179954 -386.75668) (xy 18.066715 -386.842937) (xy 17.948778 -386.922649)
			(xy 17.826519 -386.995561) (xy 17.700332 -387.061439) (xy 17.570619 -387.120073) (xy 17.437797 -387.171274)
			(xy 17.302291 -387.214879) (xy 17.164535 -387.250748) (xy 17.024971 -387.278766) (xy 16.884044 -387.298843)
			(xy 16.742208 -387.310915) (xy 16.599916 -387.314944) (xy 16.457624 -387.310915) (xy 16.315788 -387.298843)
			(xy 16.174861 -387.278766) (xy 16.035297 -387.250748) (xy 15.897541 -387.214879) (xy 15.762035 -387.171274)
			(xy 15.629213 -387.120073) (xy 15.4995 -387.061439) (xy 15.373313 -386.995561) (xy 15.251054 -386.922649)
			(xy 15.133117 -386.842937) (xy 15.019878 -386.75668) (xy 14.9117 -386.664156) (xy 14.80893 -386.565659)
			(xy 14.711897 -386.461505) (xy 14.620913 -386.352029) (xy 14.536267 -386.237581) (xy 14.458232 -386.118527)
			(xy 14.387058 -385.995249) (xy 14.322971 -385.868142) (xy 14.266179 -385.737613) (xy 14.216862 -385.604079)
			(xy 14.175179 -385.46797) (xy 14.141263 -385.32972) (xy 14.115223 -385.189773) (xy 14.097142 -385.048577)
			(xy 14.087079 -384.906584) (xy 14.085064 -384.764249) (xy 11.596722 -384.764249) (xy 11.595865 -384.849908)
			(xy 11.601875 -385.050078) (xy 11.615889 -385.249847) (xy 11.637885 -385.448895) (xy 11.667826 -385.646905)
			(xy 11.705666 -385.843557) (xy 11.751344 -386.038539) (xy 11.804786 -386.231536) (xy 11.865907 -386.422241)
			(xy 11.934609 -386.610348) (xy 12.010782 -386.795555) (xy 12.094305 -386.977567) (xy 12.185042 -387.156091)
			(xy 12.28285 -387.330842) (xy 12.387571 -387.501539) (xy 12.499038 -387.66791) (xy 12.617072 -387.829688)
			(xy 12.741484 -387.986614) (xy 12.872075 -388.138437) (xy 13.008636 -388.284913) (xy 13.150948 -388.425808)
			(xy 13.298783 -388.560897) (xy 13.451905 -388.689962) (xy 13.610067 -388.812798) (xy 13.773018 -388.929208)
			(xy 13.940496 -389.039004) (xy 14.112233 -389.142012) (xy 14.287953 -389.238067) (xy 14.467376 -389.327014)
			(xy 14.650214 -389.408711) (xy 14.836175 -389.483027) (xy 15.024959 -389.549844) (xy 15.216266 -389.609054)
			(xy 15.409789 -389.660563) (xy 15.605217 -389.704287) (xy 15.802239 -389.740158) (xy 16.000538 -389.768117)
			(xy 16.199796 -389.78812) (xy 16.399696 -389.800134) (xy 16.599916 -389.804141) (xy 16.800136 -389.800134)
			(xy 17.000036 -389.78812) (xy 17.199294 -389.768117) (xy 17.397593 -389.740158) (xy 17.594615 -389.704287)
			(xy 17.790043 -389.660563) (xy 17.983566 -389.609054) (xy 18.174873 -389.549844) (xy 18.363657 -389.483027)
			(xy 18.549618 -389.408711) (xy 18.732456 -389.327014) (xy 18.911879 -389.238067) (xy 19.087599 -389.142012)
			(xy 19.259336 -389.039004) (xy 19.426814 -388.929208) (xy 19.589765 -388.812798) (xy 19.747927 -388.689962)
			(xy 19.901049 -388.560897) (xy 20.048884 -388.425808) (xy 20.191196 -388.284913) (xy 20.327757 -388.138437)
			(xy 20.458348 -387.986614) (xy 20.58276 -387.829688) (xy 20.700794 -387.66791) (xy 20.812261 -387.501539)
			(xy 20.916982 -387.330842) (xy 21.01479 -387.156091) (xy 21.105527 -386.977567) (xy 21.18905 -386.795555)
			(xy 21.265223 -386.610348) (xy 21.333925 -386.422241) (xy 21.395046 -386.231536) (xy 21.448488 -386.038539)
			(xy 21.494166 -385.843557) (xy 21.532006 -385.646905) (xy 21.561947 -385.448895) (xy 21.583943 -385.249847)
			(xy 21.597957 -385.050078) (xy 21.603967 -384.849908) (xy 21.601963 -384.649657) (xy 21.591949 -384.449648)
			(xy 21.573941 -384.250199) (xy 21.547967 -384.05163) (xy 21.51407 -383.85426) (xy 21.472303 -383.658403)
			(xy 21.422733 -383.464375) (xy 21.36544 -383.272485) (xy 21.300515 -383.083042) (xy 21.228063 -382.896347)
			(xy 21.148199 -382.712701) (xy 21.061052 -382.532397) (xy 20.96676 -382.355724) (xy 20.865475 -382.182966)
			(xy 20.75736 -382.014398) (xy 20.642587 -381.85029) (xy 20.521339 -381.690906) (xy 20.393812 -381.536501)
			(xy 20.260209 -381.387322) (xy 20.120745 -381.243607) (xy 19.975643 -381.105588) (xy 19.825134 -380.973484)
			(xy 19.669461 -380.847508) (xy 19.508872 -380.727862) (xy 19.343624 -380.614736) (xy 19.173983 -380.508312)
			(xy 19.000219 -380.408761) (xy 18.822612 -380.316242) (xy 18.641445 -380.230903) (xy 18.457009 -380.15288)
			(xy 18.269599 -380.0823) (xy 18.079516 -380.019274) (xy 17.887062 -379.963903) (xy 17.692548 -379.916277)
			(xy 17.496283 -379.876472) (xy 17.298584 -379.844551) (xy 17.099765 -379.820565) (xy 16.900146 -379.804553)
			(xy 16.700046 -379.796541)
		)
		(stroke
			(width 0)
			(type solid)
		)
		(fill yes)
		(layer "B.Cu")
		(net "GND")
	)
	(gr_poly
		(pts
			(xy 16.599916 -290.89604) (xy 16.499786 -290.896541) (xy 16.299686 -290.904553) (xy 16.100067 -290.920565)
			(xy 15.901248 -290.944551) (xy 15.703549 -290.976472) (xy 15.507284 -291.016277) (xy 15.31277 -291.063903)
			(xy 15.120316 -291.119274) (xy 14.930233 -291.1823) (xy 14.742823 -291.25288) (xy 14.558387 -291.330903)
			(xy 14.37722 -291.416242) (xy 14.199613 -291.508761) (xy 14.025849 -291.608312) (xy 13.856208 -291.714736)
			(xy 13.69096 -291.827862) (xy 13.530371 -291.947508) (xy 13.374698 -292.073484) (xy 13.224189 -292.205588)
			(xy 13.079087 -292.343607) (xy 12.939623 -292.487322) (xy 12.80602 -292.636501) (xy 12.678493 -292.790906)
			(xy 12.557245 -292.95029) (xy 12.442472 -293.114398) (xy 12.334357 -293.282966) (xy 12.233072 -293.455724)
			(xy 12.13878 -293.632397) (xy 12.051633 -293.812701) (xy 11.971769 -293.996347) (xy 11.899317 -294.183042)
			(xy 11.834392 -294.372485) (xy 11.777099 -294.564375) (xy 11.727529 -294.758403) (xy 11.685762 -294.95426)
			(xy 11.651865 -295.15163) (xy 11.625891 -295.350199) (xy 11.607883 -295.549648) (xy 11.597869 -295.749657)
			(xy 11.596722 -295.864249) (xy 14.085064 -295.864249) (xy 14.091106 -295.722028) (xy 14.105184 -295.580377)
			(xy 14.127253 -295.439749) (xy 14.157243 -295.300595) (xy 14.195058 -295.16336) (xy 14.240576 -295.028485)
			(xy 14.293652 -294.896401) (xy 14.354115 -294.767531) (xy 14.421772 -294.642288) (xy 14.496407 -294.521074)
			(xy 14.57778 -294.404276) (xy 14.66563 -294.292269) (xy 14.759677 -294.185411) (xy 14.859618 -294.084046)
			(xy 14.965134 -293.988497) (xy 15.075887 -293.89907) (xy 15.191521 -293.816052) (xy 15.311668 -293.73971)
			(xy 15.43594 -293.670287) (xy 15.563942 -293.608006) (xy 15.695262 -293.553066) (xy 15.829479 -293.505644)
			(xy 15.966165 -293.465891) (xy 16.104881 -293.433935) (xy 16.245182 -293.409878) (xy 16.38662 -293.393797)
			(xy 16.528741 -293.385744) (xy 16.599916 -293.38524) (xy 16.671091 -293.385744) (xy 16.813212 -293.393797)
			(xy 16.95465 -293.409878) (xy 17.094951 -293.433935) (xy 17.233667 -293.465891) (xy 17.370353 -293.505644)
			(xy 17.50457 -293.553066) (xy 17.63589 -293.608006) (xy 17.763892 -293.670287) (xy 17.888164 -293.73971)
			(xy 18.008311 -293.816052) (xy 18.123945 -293.89907) (xy 18.234698 -293.988497) (xy 18.340214 -294.084046)
			(xy 18.440155 -294.185411) (xy 18.534202 -294.292269) (xy 18.622052 -294.404276) (xy 18.703425 -294.521074)
			(xy 18.77806 -294.642288) (xy 18.845717 -294.767531) (xy 18.90618 -294.896401) (xy 18.959256 -295.028485)
			(xy 19.004774 -295.16336) (xy 19.042589 -295.300595) (xy 19.072579 -295.439749) (xy 19.094648 -295.580377)
			(xy 19.108726 -295.722028) (xy 19.114768 -295.864249) (xy 19.112753 -296.006584) (xy 19.10269 -296.148577)
			(xy 19.084609 -296.289773) (xy 19.058569 -296.42972) (xy 19.024653 -296.56797) (xy 18.98297 -296.704079)
			(xy 18.933653 -296.837613) (xy 18.876861 -296.968142) (xy 18.812774 -297.095249) (xy 18.7416 -297.218527)
			(xy 18.663565 -297.337581) (xy 18.578919 -297.452029) (xy 18.487935 -297.561505) (xy 18.390902 -297.665659)
			(xy 18.288132 -297.764156) (xy 18.179954 -297.85668) (xy 18.066715 -297.942937) (xy 17.948778 -298.022649)
			(xy 17.826519 -298.095561) (xy 17.700332 -298.161439) (xy 17.570619 -298.220073) (xy 17.437797 -298.271274)
			(xy 17.302291 -298.314879) (xy 17.164535 -298.350748) (xy 17.024971 -298.378766) (xy 16.884044 -298.398843)
			(xy 16.742208 -298.410915) (xy 16.599916 -298.414944) (xy 16.457624 -298.410915) (xy 16.315788 -298.398843)
			(xy 16.174861 -298.378766) (xy 16.035297 -298.350748) (xy 15.897541 -298.314879) (xy 15.762035 -298.271274)
			(xy 15.629213 -298.220073) (xy 15.4995 -298.161439) (xy 15.373313 -298.095561) (xy 15.251054 -298.022649)
			(xy 15.133117 -297.942937) (xy 15.019878 -297.85668) (xy 14.9117 -297.764156) (xy 14.80893 -297.665659)
			(xy 14.711897 -297.561505) (xy 14.620913 -297.452029) (xy 14.536267 -297.337581) (xy 14.458232 -297.218527)
			(xy 14.387058 -297.095249) (xy 14.322971 -296.968142) (xy 14.266179 -296.837613) (xy 14.216862 -296.704079)
			(xy 14.175179 -296.56797) (xy 14.141263 -296.42972) (xy 14.115223 -296.289773) (xy 14.097142 -296.148577)
			(xy 14.087079 -296.006584) (xy 14.085064 -295.864249) (xy 11.596722 -295.864249) (xy 11.595865 -295.949908)
			(xy 11.601875 -296.150078) (xy 11.615889 -296.349847) (xy 11.637885 -296.548895) (xy 11.667826 -296.746905)
			(xy 11.705666 -296.943557) (xy 11.751344 -297.138539) (xy 11.804786 -297.331536) (xy 11.865907 -297.522241)
			(xy 11.934609 -297.710348) (xy 12.010782 -297.895555) (xy 12.094305 -298.077567) (xy 12.185042 -298.256091)
			(xy 12.28285 -298.430842) (xy 12.387571 -298.601539) (xy 12.499038 -298.76791) (xy 12.617072 -298.929688)
			(xy 12.741484 -299.086614) (xy 12.872075 -299.238437) (xy 13.008636 -299.384913) (xy 13.150948 -299.525808)
			(xy 13.298783 -299.660897) (xy 13.451905 -299.789962) (xy 13.610067 -299.912798) (xy 13.773018 -300.029208)
			(xy 13.940496 -300.139004) (xy 14.112233 -300.242012) (xy 14.287953 -300.338067) (xy 14.467376 -300.427014)
			(xy 14.650214 -300.508711) (xy 14.836175 -300.583027) (xy 15.024959 -300.649844) (xy 15.216266 -300.709054)
			(xy 15.409789 -300.760563) (xy 15.605217 -300.804287) (xy 15.802239 -300.840158) (xy 16.000538 -300.868117)
			(xy 16.199796 -300.88812) (xy 16.399696 -300.900134) (xy 16.599916 -300.904141) (xy 16.800136 -300.900134)
			(xy 17.000036 -300.88812) (xy 17.199294 -300.868117) (xy 17.397593 -300.840158) (xy 17.594615 -300.804287)
			(xy 17.790043 -300.760563) (xy 17.983566 -300.709054) (xy 18.174873 -300.649844) (xy 18.363657 -300.583027)
			(xy 18.549618 -300.508711) (xy 18.732456 -300.427014) (xy 18.911879 -300.338067) (xy 19.087599 -300.242012)
			(xy 19.259336 -300.139004) (xy 19.426814 -300.029208) (xy 19.589765 -299.912798) (xy 19.747927 -299.789962)
			(xy 19.901049 -299.660897) (xy 20.048884 -299.525808) (xy 20.191196 -299.384913) (xy 20.327757 -299.238437)
			(xy 20.458348 -299.086614) (xy 20.58276 -298.929688) (xy 20.700794 -298.76791) (xy 20.812261 -298.601539)
			(xy 20.916982 -298.430842) (xy 21.01479 -298.256091) (xy 21.105527 -298.077567) (xy 21.18905 -297.895555)
			(xy 21.265223 -297.710348) (xy 21.333925 -297.522241) (xy 21.395046 -297.331536) (xy 21.448488 -297.138539)
			(xy 21.494166 -296.943557) (xy 21.532006 -296.746905) (xy 21.561947 -296.548895) (xy 21.583943 -296.349847)
			(xy 21.597957 -296.150078) (xy 21.603967 -295.949908) (xy 21.601963 -295.749657) (xy 21.591949 -295.549648)
			(xy 21.573941 -295.350199) (xy 21.547967 -295.15163) (xy 21.51407 -294.95426) (xy 21.472303 -294.758403)
			(xy 21.422733 -294.564375) (xy 21.36544 -294.372485) (xy 21.300515 -294.183042) (xy 21.228063 -293.996347)
			(xy 21.148199 -293.812701) (xy 21.061052 -293.632397) (xy 20.96676 -293.455724) (xy 20.865475 -293.282966)
			(xy 20.75736 -293.114398) (xy 20.642587 -292.95029) (xy 20.521339 -292.790906) (xy 20.393812 -292.636501)
			(xy 20.260209 -292.487322) (xy 20.120745 -292.343607) (xy 19.975643 -292.205588) (xy 19.825134 -292.073484)
			(xy 19.669461 -291.947508) (xy 19.508872 -291.827862) (xy 19.343624 -291.714736) (xy 19.173983 -291.608312)
			(xy 19.000219 -291.508761) (xy 18.822612 -291.416242) (xy 18.641445 -291.330903) (xy 18.457009 -291.25288)
			(xy 18.269599 -291.1823) (xy 18.079516 -291.119274) (xy 17.887062 -291.063903) (xy 17.692548 -291.016277)
			(xy 17.496283 -290.976472) (xy 17.298584 -290.944551) (xy 17.099765 -290.920565) (xy 16.900146 -290.904553)
			(xy 16.700046 -290.896541)
		)
		(stroke
			(width 0)
			(type solid)
		)
		(fill yes)
		(layer "B.Cu")
		(net "GND")
	)
	(gr_poly
		(pts
			(xy 16.599916 -201.99604) (xy 16.499786 -201.996541) (xy 16.299686 -202.004553) (xy 16.100067 -202.020565)
			(xy 15.901248 -202.044551) (xy 15.703549 -202.076472) (xy 15.507284 -202.116277) (xy 15.31277 -202.163903)
			(xy 15.120316 -202.219274) (xy 14.930233 -202.2823) (xy 14.742823 -202.35288) (xy 14.558387 -202.430903)
			(xy 14.37722 -202.516242) (xy 14.199613 -202.608761) (xy 14.025849 -202.708312) (xy 13.856208 -202.814736)
			(xy 13.69096 -202.927862) (xy 13.530371 -203.047508) (xy 13.374698 -203.173484) (xy 13.224189 -203.305588)
			(xy 13.079087 -203.443607) (xy 12.939623 -203.587322) (xy 12.80602 -203.736501) (xy 12.678493 -203.890906)
			(xy 12.557245 -204.05029) (xy 12.442472 -204.214398) (xy 12.334357 -204.382966) (xy 12.233072 -204.555724)
			(xy 12.13878 -204.732397) (xy 12.051633 -204.912701) (xy 11.971769 -205.096347) (xy 11.899317 -205.283042)
			(xy 11.834392 -205.472485) (xy 11.777099 -205.664375) (xy 11.727529 -205.858403) (xy 11.685762 -206.05426)
			(xy 11.651865 -206.25163) (xy 11.625891 -206.450199) (xy 11.607883 -206.649648) (xy 11.597869 -206.849657)
			(xy 11.596722 -206.964249) (xy 14.085064 -206.964249) (xy 14.091106 -206.822028) (xy 14.105184 -206.680377)
			(xy 14.127253 -206.539749) (xy 14.157243 -206.400595) (xy 14.195058 -206.26336) (xy 14.240576 -206.128485)
			(xy 14.293652 -205.996401) (xy 14.354115 -205.867531) (xy 14.421772 -205.742288) (xy 14.496407 -205.621074)
			(xy 14.57778 -205.504276) (xy 14.66563 -205.392269) (xy 14.759677 -205.285411) (xy 14.859618 -205.184046)
			(xy 14.965134 -205.088497) (xy 15.075887 -204.99907) (xy 15.191521 -204.916052) (xy 15.311668 -204.83971)
			(xy 15.43594 -204.770287) (xy 15.563942 -204.708006) (xy 15.695262 -204.653066) (xy 15.829479 -204.605644)
			(xy 15.966165 -204.565891) (xy 16.104881 -204.533935) (xy 16.245182 -204.509878) (xy 16.38662 -204.493797)
			(xy 16.528741 -204.485744) (xy 16.599916 -204.48524) (xy 16.671091 -204.485744) (xy 16.813212 -204.493797)
			(xy 16.95465 -204.509878) (xy 17.094951 -204.533935) (xy 17.233667 -204.565891) (xy 17.370353 -204.605644)
			(xy 17.50457 -204.653066) (xy 17.63589 -204.708006) (xy 17.763892 -204.770287) (xy 17.888164 -204.83971)
			(xy 18.008311 -204.916052) (xy 18.123945 -204.99907) (xy 18.234698 -205.088497) (xy 18.340214 -205.184046)
			(xy 18.440155 -205.285411) (xy 18.534202 -205.392269) (xy 18.622052 -205.504276) (xy 18.703425 -205.621074)
			(xy 18.77806 -205.742288) (xy 18.845717 -205.867531) (xy 18.90618 -205.996401) (xy 18.959256 -206.128485)
			(xy 19.004774 -206.26336) (xy 19.042589 -206.400595) (xy 19.072579 -206.539749) (xy 19.094648 -206.680377)
			(xy 19.108726 -206.822028) (xy 19.114768 -206.964249) (xy 19.112753 -207.106584) (xy 19.10269 -207.248577)
			(xy 19.084609 -207.389773) (xy 19.058569 -207.52972) (xy 19.024653 -207.66797) (xy 18.98297 -207.804079)
			(xy 18.933653 -207.937613) (xy 18.876861 -208.068142) (xy 18.812774 -208.195249) (xy 18.7416 -208.318527)
			(xy 18.663565 -208.437581) (xy 18.578919 -208.552029) (xy 18.487935 -208.661505) (xy 18.390902 -208.765659)
			(xy 18.288132 -208.864156) (xy 18.179954 -208.95668) (xy 18.066715 -209.042937) (xy 17.948778 -209.122649)
			(xy 17.826519 -209.195561) (xy 17.700332 -209.261439) (xy 17.570619 -209.320073) (xy 17.437797 -209.371274)
			(xy 17.302291 -209.414879) (xy 17.164535 -209.450748) (xy 17.024971 -209.478766) (xy 16.884044 -209.498843)
			(xy 16.742208 -209.510915) (xy 16.599916 -209.514944) (xy 16.457624 -209.510915) (xy 16.315788 -209.498843)
			(xy 16.174861 -209.478766) (xy 16.035297 -209.450748) (xy 15.897541 -209.414879) (xy 15.762035 -209.371274)
			(xy 15.629213 -209.320073) (xy 15.4995 -209.261439) (xy 15.373313 -209.195561) (xy 15.251054 -209.122649)
			(xy 15.133117 -209.042937) (xy 15.019878 -208.95668) (xy 14.9117 -208.864156) (xy 14.80893 -208.765659)
			(xy 14.711897 -208.661505) (xy 14.620913 -208.552029) (xy 14.536267 -208.437581) (xy 14.458232 -208.318527)
			(xy 14.387058 -208.195249) (xy 14.322971 -208.068142) (xy 14.266179 -207.937613) (xy 14.216862 -207.804079)
			(xy 14.175179 -207.66797) (xy 14.141263 -207.52972) (xy 14.115223 -207.389773) (xy 14.097142 -207.248577)
			(xy 14.087079 -207.106584) (xy 14.085064 -206.964249) (xy 11.596722 -206.964249) (xy 11.595865 -207.049908)
			(xy 11.601875 -207.250078) (xy 11.615889 -207.449847) (xy 11.637885 -207.648895) (xy 11.667826 -207.846905)
			(xy 11.705666 -208.043557) (xy 11.751344 -208.238539) (xy 11.804786 -208.431536) (xy 11.865907 -208.622241)
			(xy 11.934609 -208.810348) (xy 12.010782 -208.995555) (xy 12.094305 -209.177567) (xy 12.185042 -209.356091)
			(xy 12.28285 -209.530842) (xy 12.387571 -209.701539) (xy 12.499038 -209.86791) (xy 12.617072 -210.029688)
			(xy 12.741484 -210.186614) (xy 12.872075 -210.338437) (xy 13.008636 -210.484913) (xy 13.150948 -210.625808)
			(xy 13.298783 -210.760897) (xy 13.451905 -210.889962) (xy 13.610067 -211.012798) (xy 13.773018 -211.129208)
			(xy 13.940496 -211.239004) (xy 14.112233 -211.342012) (xy 14.287953 -211.438067) (xy 14.467376 -211.527014)
			(xy 14.650214 -211.608711) (xy 14.836175 -211.683027) (xy 15.024959 -211.749844) (xy 15.216266 -211.809054)
			(xy 15.409789 -211.860563) (xy 15.605217 -211.904287) (xy 15.802239 -211.940158) (xy 16.000538 -211.968117)
			(xy 16.199796 -211.98812) (xy 16.399696 -212.000134) (xy 16.599916 -212.004141) (xy 16.800136 -212.000134)
			(xy 17.000036 -211.98812) (xy 17.199294 -211.968117) (xy 17.397593 -211.940158) (xy 17.594615 -211.904287)
			(xy 17.790043 -211.860563) (xy 17.983566 -211.809054) (xy 18.174873 -211.749844) (xy 18.363657 -211.683027)
			(xy 18.549618 -211.608711) (xy 18.732456 -211.527014) (xy 18.911879 -211.438067) (xy 19.087599 -211.342012)
			(xy 19.259336 -211.239004) (xy 19.426814 -211.129208) (xy 19.589765 -211.012798) (xy 19.747927 -210.889962)
			(xy 19.901049 -210.760897) (xy 20.048884 -210.625808) (xy 20.191196 -210.484913) (xy 20.327757 -210.338437)
			(xy 20.458348 -210.186614) (xy 20.58276 -210.029688) (xy 20.700794 -209.86791) (xy 20.812261 -209.701539)
			(xy 20.916982 -209.530842) (xy 21.01479 -209.356091) (xy 21.105527 -209.177567) (xy 21.18905 -208.995555)
			(xy 21.265223 -208.810348) (xy 21.333925 -208.622241) (xy 21.395046 -208.431536) (xy 21.448488 -208.238539)
			(xy 21.494166 -208.043557) (xy 21.532006 -207.846905) (xy 21.561947 -207.648895) (xy 21.583943 -207.449847)
			(xy 21.597957 -207.250078) (xy 21.603967 -207.049908) (xy 21.601963 -206.849657) (xy 21.591949 -206.649648)
			(xy 21.573941 -206.450199) (xy 21.547967 -206.25163) (xy 21.51407 -206.05426) (xy 21.472303 -205.858403)
			(xy 21.422733 -205.664375) (xy 21.36544 -205.472485) (xy 21.300515 -205.283042) (xy 21.228063 -205.096347)
			(xy 21.148199 -204.912701) (xy 21.061052 -204.732397) (xy 20.96676 -204.555724) (xy 20.865475 -204.382966)
			(xy 20.75736 -204.214398) (xy 20.642587 -204.05029) (xy 20.521339 -203.890906) (xy 20.393812 -203.736501)
			(xy 20.260209 -203.587322) (xy 20.120745 -203.443607) (xy 19.975643 -203.305588) (xy 19.825134 -203.173484)
			(xy 19.669461 -203.047508) (xy 19.508872 -202.927862) (xy 19.343624 -202.814736) (xy 19.173983 -202.708312)
			(xy 19.000219 -202.608761) (xy 18.822612 -202.516242) (xy 18.641445 -202.430903) (xy 18.457009 -202.35288)
			(xy 18.269599 -202.2823) (xy 18.079516 -202.219274) (xy 17.887062 -202.163903) (xy 17.692548 -202.116277)
			(xy 17.496283 -202.076472) (xy 17.298584 -202.044551) (xy 17.099765 -202.020565) (xy 16.900146 -202.004553)
			(xy 16.700046 -201.996541)
		)
		(stroke
			(width 0)
			(type solid)
		)
		(fill yes)
		(layer "B.Cu")
		(net "GND")
	)
	(gr_poly
		(pts
			(xy 16.599916 -113.09604) (xy 16.499786 -113.096541) (xy 16.299686 -113.104553) (xy 16.100067 -113.120565)
			(xy 15.901248 -113.144551) (xy 15.703549 -113.176472) (xy 15.507284 -113.216277) (xy 15.31277 -113.263903)
			(xy 15.120316 -113.319274) (xy 14.930233 -113.3823) (xy 14.742823 -113.45288) (xy 14.558387 -113.530903)
			(xy 14.37722 -113.616242) (xy 14.199613 -113.708761) (xy 14.025849 -113.808312) (xy 13.856208 -113.914736)
			(xy 13.69096 -114.027862) (xy 13.530371 -114.147508) (xy 13.374698 -114.273484) (xy 13.224189 -114.405588)
			(xy 13.079087 -114.543607) (xy 12.939623 -114.687322) (xy 12.80602 -114.836501) (xy 12.678493 -114.990906)
			(xy 12.557245 -115.15029) (xy 12.442472 -115.314398) (xy 12.334357 -115.482966) (xy 12.233072 -115.655724)
			(xy 12.13878 -115.832397) (xy 12.051633 -116.012701) (xy 11.971769 -116.196347) (xy 11.899317 -116.383042)
			(xy 11.834392 -116.572485) (xy 11.777099 -116.764375) (xy 11.727529 -116.958403) (xy 11.685762 -117.15426)
			(xy 11.651865 -117.35163) (xy 11.625891 -117.550199) (xy 11.607883 -117.749648) (xy 11.597869 -117.949657)
			(xy 11.596722 -118.064249) (xy 14.085064 -118.064249) (xy 14.091106 -117.922028) (xy 14.105184 -117.780377)
			(xy 14.127253 -117.639749) (xy 14.157243 -117.500595) (xy 14.195058 -117.36336) (xy 14.240576 -117.228485)
			(xy 14.293652 -117.096401) (xy 14.354115 -116.967531) (xy 14.421772 -116.842288) (xy 14.496407 -116.721074)
			(xy 14.57778 -116.604276) (xy 14.66563 -116.492269) (xy 14.759677 -116.385411) (xy 14.859618 -116.284046)
			(xy 14.965134 -116.188497) (xy 15.075887 -116.09907) (xy 15.191521 -116.016052) (xy 15.311668 -115.93971)
			(xy 15.43594 -115.870287) (xy 15.563942 -115.808006) (xy 15.695262 -115.753066) (xy 15.829479 -115.705644)
			(xy 15.966165 -115.665891) (xy 16.104881 -115.633935) (xy 16.245182 -115.609878) (xy 16.38662 -115.593797)
			(xy 16.528741 -115.585744) (xy 16.599916 -115.58524) (xy 16.671091 -115.585744) (xy 16.813212 -115.593797)
			(xy 16.95465 -115.609878) (xy 17.094951 -115.633935) (xy 17.233667 -115.665891) (xy 17.370353 -115.705644)
			(xy 17.50457 -115.753066) (xy 17.63589 -115.808006) (xy 17.763892 -115.870287) (xy 17.888164 -115.93971)
			(xy 18.008311 -116.016052) (xy 18.123945 -116.09907) (xy 18.234698 -116.188497) (xy 18.340214 -116.284046)
			(xy 18.440155 -116.385411) (xy 18.534202 -116.492269) (xy 18.622052 -116.604276) (xy 18.703425 -116.721074)
			(xy 18.77806 -116.842288) (xy 18.845717 -116.967531) (xy 18.90618 -117.096401) (xy 18.959256 -117.228485)
			(xy 19.004774 -117.36336) (xy 19.042589 -117.500595) (xy 19.072579 -117.639749) (xy 19.094648 -117.780377)
			(xy 19.108726 -117.922028) (xy 19.114768 -118.064249) (xy 19.112753 -118.206584) (xy 19.10269 -118.348577)
			(xy 19.084609 -118.489773) (xy 19.058569 -118.62972) (xy 19.024653 -118.76797) (xy 18.98297 -118.904079)
			(xy 18.933653 -119.037613) (xy 18.876861 -119.168142) (xy 18.812774 -119.295249) (xy 18.7416 -119.418527)
			(xy 18.663565 -119.537581) (xy 18.578919 -119.652029) (xy 18.487935 -119.761505) (xy 18.390902 -119.865659)
			(xy 18.288132 -119.964156) (xy 18.179954 -120.05668) (xy 18.066715 -120.142937) (xy 17.948778 -120.222649)
			(xy 17.826519 -120.295561) (xy 17.700332 -120.361439) (xy 17.570619 -120.420073) (xy 17.437797 -120.471274)
			(xy 17.302291 -120.514879) (xy 17.164535 -120.550748) (xy 17.024971 -120.578766) (xy 16.884044 -120.598843)
			(xy 16.742208 -120.610915) (xy 16.599916 -120.614944) (xy 16.457624 -120.610915) (xy 16.315788 -120.598843)
			(xy 16.174861 -120.578766) (xy 16.035297 -120.550748) (xy 15.897541 -120.514879) (xy 15.762035 -120.471274)
			(xy 15.629213 -120.420073) (xy 15.4995 -120.361439) (xy 15.373313 -120.295561) (xy 15.251054 -120.222649)
			(xy 15.133117 -120.142937) (xy 15.019878 -120.05668) (xy 14.9117 -119.964156) (xy 14.80893 -119.865659)
			(xy 14.711897 -119.761505) (xy 14.620913 -119.652029) (xy 14.536267 -119.537581) (xy 14.458232 -119.418527)
			(xy 14.387058 -119.295249) (xy 14.322971 -119.168142) (xy 14.266179 -119.037613) (xy 14.216862 -118.904079)
			(xy 14.175179 -118.76797) (xy 14.141263 -118.62972) (xy 14.115223 -118.489773) (xy 14.097142 -118.348577)
			(xy 14.087079 -118.206584) (xy 14.085064 -118.064249) (xy 11.596722 -118.064249) (xy 11.595865 -118.149908)
			(xy 11.601875 -118.350078) (xy 11.615889 -118.549847) (xy 11.637885 -118.748895) (xy 11.667826 -118.946905)
			(xy 11.705666 -119.143557) (xy 11.751344 -119.338539) (xy 11.804786 -119.531536) (xy 11.865907 -119.722241)
			(xy 11.934609 -119.910348) (xy 12.010782 -120.095555) (xy 12.094305 -120.277567) (xy 12.185042 -120.456091)
			(xy 12.28285 -120.630842) (xy 12.387571 -120.801539) (xy 12.499038 -120.96791) (xy 12.617072 -121.129688)
			(xy 12.741484 -121.286614) (xy 12.872075 -121.438437) (xy 13.008636 -121.584913) (xy 13.150948 -121.725808)
			(xy 13.298783 -121.860897) (xy 13.451905 -121.989962) (xy 13.610067 -122.112798) (xy 13.773018 -122.229208)
			(xy 13.940496 -122.339004) (xy 14.112233 -122.442012) (xy 14.287953 -122.538067) (xy 14.467376 -122.627014)
			(xy 14.650214 -122.708711) (xy 14.836175 -122.783027) (xy 15.024959 -122.849844) (xy 15.216266 -122.909054)
			(xy 15.409789 -122.960563) (xy 15.605217 -123.004287) (xy 15.802239 -123.040158) (xy 16.000538 -123.068117)
			(xy 16.199796 -123.08812) (xy 16.399696 -123.100134) (xy 16.599916 -123.104141) (xy 16.800136 -123.100134)
			(xy 17.000036 -123.08812) (xy 17.199294 -123.068117) (xy 17.397593 -123.040158) (xy 17.594615 -123.004287)
			(xy 17.790043 -122.960563) (xy 17.983566 -122.909054) (xy 18.174873 -122.849844) (xy 18.363657 -122.783027)
			(xy 18.549618 -122.708711) (xy 18.732456 -122.627014) (xy 18.911879 -122.538067) (xy 19.087599 -122.442012)
			(xy 19.259336 -122.339004) (xy 19.426814 -122.229208) (xy 19.589765 -122.112798) (xy 19.747927 -121.989962)
			(xy 19.901049 -121.860897) (xy 20.048884 -121.725808) (xy 20.191196 -121.584913) (xy 20.327757 -121.438437)
			(xy 20.458348 -121.286614) (xy 20.58276 -121.129688) (xy 20.700794 -120.96791) (xy 20.812261 -120.801539)
			(xy 20.916982 -120.630842) (xy 21.01479 -120.456091) (xy 21.105527 -120.277567) (xy 21.18905 -120.095555)
			(xy 21.265223 -119.910348) (xy 21.333925 -119.722241) (xy 21.395046 -119.531536) (xy 21.448488 -119.338539)
			(xy 21.494166 -119.143557) (xy 21.532006 -118.946905) (xy 21.561947 -118.748895) (xy 21.583943 -118.549847)
			(xy 21.597957 -118.350078) (xy 21.603967 -118.149908) (xy 21.601963 -117.949657) (xy 21.591949 -117.749648)
			(xy 21.573941 -117.550199) (xy 21.547967 -117.35163) (xy 21.51407 -117.15426) (xy 21.472303 -116.958403)
			(xy 21.422733 -116.764375) (xy 21.36544 -116.572485) (xy 21.300515 -116.383042) (xy 21.228063 -116.196347)
			(xy 21.148199 -116.012701) (xy 21.061052 -115.832397) (xy 20.96676 -115.655724) (xy 20.865475 -115.482966)
			(xy 20.75736 -115.314398) (xy 20.642587 -115.15029) (xy 20.521339 -114.990906) (xy 20.393812 -114.836501)
			(xy 20.260209 -114.687322) (xy 20.120745 -114.543607) (xy 19.975643 -114.405588) (xy 19.825134 -114.273484)
			(xy 19.669461 -114.147508) (xy 19.508872 -114.027862) (xy 19.343624 -113.914736) (xy 19.173983 -113.808312)
			(xy 19.000219 -113.708761) (xy 18.822612 -113.616242) (xy 18.641445 -113.530903) (xy 18.457009 -113.45288)
			(xy 18.269599 -113.3823) (xy 18.079516 -113.319274) (xy 17.887062 -113.263903) (xy 17.692548 -113.216277)
			(xy 17.496283 -113.176472) (xy 17.298584 -113.144551) (xy 17.099765 -113.120565) (xy 16.900146 -113.104553)
			(xy 16.700046 -113.096541)
		)
		(stroke
			(width 0)
			(type solid)
		)
		(fill yes)
		(layer "B.Cu")
		(net "GND")
	)
	(gr_poly
		(pts
			(xy 16.599916 -24.19604) (xy 16.499786 -24.196541) (xy 16.299686 -24.204553) (xy 16.100067 -24.220565)
			(xy 15.901248 -24.244551) (xy 15.703549 -24.276472) (xy 15.507284 -24.316277) (xy 15.31277 -24.363903)
			(xy 15.120316 -24.419274) (xy 14.930233 -24.4823) (xy 14.742823 -24.55288) (xy 14.558387 -24.630903)
			(xy 14.37722 -24.716242) (xy 14.199613 -24.808761) (xy 14.025849 -24.908312) (xy 13.856208 -25.014736)
			(xy 13.69096 -25.127862) (xy 13.530371 -25.247508) (xy 13.374698 -25.373484) (xy 13.224189 -25.505588)
			(xy 13.079087 -25.643607) (xy 12.939623 -25.787322) (xy 12.80602 -25.936501) (xy 12.678493 -26.090906)
			(xy 12.557245 -26.25029) (xy 12.442472 -26.414398) (xy 12.334357 -26.582966) (xy 12.233072 -26.755724)
			(xy 12.13878 -26.932397) (xy 12.051633 -27.112701) (xy 11.971769 -27.296347) (xy 11.899317 -27.483042)
			(xy 11.834392 -27.672485) (xy 11.777099 -27.864375) (xy 11.727529 -28.058403) (xy 11.685762 -28.25426)
			(xy 11.651865 -28.45163) (xy 11.625891 -28.650199) (xy 11.607883 -28.849648) (xy 11.597869 -29.049657)
			(xy 11.596722 -29.164249) (xy 14.085064 -29.164249) (xy 14.091106 -29.022028) (xy 14.105184 -28.880377)
			(xy 14.127253 -28.739749) (xy 14.157243 -28.600595) (xy 14.195058 -28.46336) (xy 14.240576 -28.328485)
			(xy 14.293652 -28.196401) (xy 14.354115 -28.067531) (xy 14.421772 -27.942288) (xy 14.496407 -27.821074)
			(xy 14.57778 -27.704276) (xy 14.66563 -27.592269) (xy 14.759677 -27.485411) (xy 14.859618 -27.384046)
			(xy 14.965134 -27.288497) (xy 15.075887 -27.19907) (xy 15.191521 -27.116052) (xy 15.311668 -27.03971)
			(xy 15.43594 -26.970287) (xy 15.563942 -26.908006) (xy 15.695262 -26.853066) (xy 15.829479 -26.805644)
			(xy 15.966165 -26.765891) (xy 16.104881 -26.733935) (xy 16.245182 -26.709878) (xy 16.38662 -26.693797)
			(xy 16.528741 -26.685744) (xy 16.599916 -26.68524) (xy 16.671091 -26.685744) (xy 16.813212 -26.693797)
			(xy 16.95465 -26.709878) (xy 17.094951 -26.733935) (xy 17.233667 -26.765891) (xy 17.370353 -26.805644)
			(xy 17.50457 -26.853066) (xy 17.63589 -26.908006) (xy 17.763892 -26.970287) (xy 17.888164 -27.03971)
			(xy 18.008311 -27.116052) (xy 18.123945 -27.19907) (xy 18.234698 -27.288497) (xy 18.340214 -27.384046)
			(xy 18.440155 -27.485411) (xy 18.534202 -27.592269) (xy 18.622052 -27.704276) (xy 18.703425 -27.821074)
			(xy 18.77806 -27.942288) (xy 18.845717 -28.067531) (xy 18.90618 -28.196401) (xy 18.959256 -28.328485)
			(xy 19.004774 -28.46336) (xy 19.042589 -28.600595) (xy 19.072579 -28.739749) (xy 19.094648 -28.880377)
			(xy 19.108726 -29.022028) (xy 19.114768 -29.164249) (xy 19.112753 -29.306584) (xy 19.10269 -29.448577)
			(xy 19.084609 -29.589773) (xy 19.058569 -29.72972) (xy 19.024653 -29.86797) (xy 18.98297 -30.004079)
			(xy 18.933653 -30.137613) (xy 18.876861 -30.268142) (xy 18.812774 -30.395249) (xy 18.7416 -30.518527)
			(xy 18.663565 -30.637581) (xy 18.578919 -30.752029) (xy 18.487935 -30.861505) (xy 18.390902 -30.965659)
			(xy 18.288132 -31.064156) (xy 18.179954 -31.15668) (xy 18.066715 -31.242937) (xy 17.948778 -31.322649)
			(xy 17.826519 -31.395561) (xy 17.700332 -31.461439) (xy 17.570619 -31.520073) (xy 17.437797 -31.571274)
			(xy 17.302291 -31.614879) (xy 17.164535 -31.650748) (xy 17.024971 -31.678766) (xy 16.884044 -31.698843)
			(xy 16.742208 -31.710915) (xy 16.599916 -31.714944) (xy 16.457624 -31.710915) (xy 16.315788 -31.698843)
			(xy 16.174861 -31.678766) (xy 16.035297 -31.650748) (xy 15.897541 -31.614879) (xy 15.762035 -31.571274)
			(xy 15.629213 -31.520073) (xy 15.4995 -31.461439) (xy 15.373313 -31.395561) (xy 15.251054 -31.322649)
			(xy 15.133117 -31.242937) (xy 15.019878 -31.15668) (xy 14.9117 -31.064156) (xy 14.80893 -30.965659)
			(xy 14.711897 -30.861505) (xy 14.620913 -30.752029) (xy 14.536267 -30.637581) (xy 14.458232 -30.518527)
			(xy 14.387058 -30.395249) (xy 14.322971 -30.268142) (xy 14.266179 -30.137613) (xy 14.216862 -30.004079)
			(xy 14.175179 -29.86797) (xy 14.141263 -29.72972) (xy 14.115223 -29.589773) (xy 14.097142 -29.448577)
			(xy 14.087079 -29.306584) (xy 14.085064 -29.164249) (xy 11.596722 -29.164249) (xy 11.595865 -29.249908)
			(xy 11.601875 -29.450078) (xy 11.615889 -29.649847) (xy 11.637885 -29.848895) (xy 11.667826 -30.046905)
			(xy 11.705666 -30.243557) (xy 11.751344 -30.438539) (xy 11.804786 -30.631536) (xy 11.865907 -30.822241)
			(xy 11.934609 -31.010348) (xy 12.010782 -31.195555) (xy 12.094305 -31.377567) (xy 12.185042 -31.556091)
			(xy 12.28285 -31.730842) (xy 12.387571 -31.901539) (xy 12.499038 -32.06791) (xy 12.617072 -32.229688)
			(xy 12.741484 -32.386614) (xy 12.872075 -32.538437) (xy 13.008636 -32.684913) (xy 13.150948 -32.825808)
			(xy 13.298783 -32.960897) (xy 13.451905 -33.089962) (xy 13.610067 -33.212798) (xy 13.773018 -33.329208)
			(xy 13.940496 -33.439004) (xy 14.112233 -33.542012) (xy 14.287953 -33.638067) (xy 14.467376 -33.727014)
			(xy 14.650214 -33.808711) (xy 14.836175 -33.883027) (xy 15.024959 -33.949844) (xy 15.216266 -34.009054)
			(xy 15.409789 -34.060563) (xy 15.605217 -34.104287) (xy 15.802239 -34.140158) (xy 16.000538 -34.168117)
			(xy 16.199796 -34.18812) (xy 16.399696 -34.200134) (xy 16.599916 -34.204141) (xy 16.800136 -34.200134)
			(xy 17.000036 -34.18812) (xy 17.199294 -34.168117) (xy 17.397593 -34.140158) (xy 17.594615 -34.104287)
			(xy 17.790043 -34.060563) (xy 17.983566 -34.009054) (xy 18.174873 -33.949844) (xy 18.363657 -33.883027)
			(xy 18.549618 -33.808711) (xy 18.732456 -33.727014) (xy 18.911879 -33.638067) (xy 19.087599 -33.542012)
			(xy 19.259336 -33.439004) (xy 19.426814 -33.329208) (xy 19.589765 -33.212798) (xy 19.747927 -33.089962)
			(xy 19.901049 -32.960897) (xy 20.048884 -32.825808) (xy 20.191196 -32.684913) (xy 20.327757 -32.538437)
			(xy 20.458348 -32.386614) (xy 20.58276 -32.229688) (xy 20.700794 -32.06791) (xy 20.812261 -31.901539)
			(xy 20.916982 -31.730842) (xy 21.01479 -31.556091) (xy 21.105527 -31.377567) (xy 21.18905 -31.195555)
			(xy 21.265223 -31.010348) (xy 21.333925 -30.822241) (xy 21.395046 -30.631536) (xy 21.448488 -30.438539)
			(xy 21.494166 -30.243557) (xy 21.532006 -30.046905) (xy 21.561947 -29.848895) (xy 21.583943 -29.649847)
			(xy 21.597957 -29.450078) (xy 21.603967 -29.249908) (xy 21.601963 -29.049657) (xy 21.591949 -28.849648)
			(xy 21.573941 -28.650199) (xy 21.547967 -28.45163) (xy 21.51407 -28.25426) (xy 21.472303 -28.058403)
			(xy 21.422733 -27.864375) (xy 21.36544 -27.672485) (xy 21.300515 -27.483042) (xy 21.228063 -27.296347)
			(xy 21.148199 -27.112701) (xy 21.061052 -26.932397) (xy 20.96676 -26.755724) (xy 20.865475 -26.582966)
			(xy 20.75736 -26.414398) (xy 20.642587 -26.25029) (xy 20.521339 -26.090906) (xy 20.393812 -25.936501)
			(xy 20.260209 -25.787322) (xy 20.120745 -25.643607) (xy 19.975643 -25.505588) (xy 19.825134 -25.373484)
			(xy 19.669461 -25.247508) (xy 19.508872 -25.127862) (xy 19.343624 -25.014736) (xy 19.173983 -24.908312)
			(xy 19.000219 -24.808761) (xy 18.822612 -24.716242) (xy 18.641445 -24.630903) (xy 18.457009 -24.55288)
			(xy 18.269599 -24.4823) (xy 18.079516 -24.419274) (xy 17.887062 -24.363903) (xy 17.692548 -24.316277)
			(xy 17.496283 -24.276472) (xy 17.298584 -24.244551) (xy 17.099765 -24.220565) (xy 16.900146 -24.204553)
			(xy 16.700046 -24.196541)
		)
		(stroke
			(width 0)
			(type solid)
		)
		(fill yes)
		(layer "B.Cu")
		(net "GND")
	)
	(gr_poly
		(pts
			(arc
				(start 101.000052 -529.49094)
				(mid 102.054334 -529.054242)
				(end 102.491032 -527.99996)
			)
			(arc
				(start 102.491032 -1.999996)
				(mid 102.054334 -0.945714)
				(end 101.000052 -0.509016)
			)
			(arc
				(start 26.500074 -0.509016)
				(mid 25.799255 -0.799305)
				(end 25.508966 -1.500124)
			)
			(arc
				(start 25.508966 -2.500122)
				(mid 24.920577 -3.920619)
				(end 23.50008 -4.509008)
			)
			(arc
				(start 1.500124 -4.509008)
				(mid 0.799305 -4.799297)
				(end 0.509016 -5.500116)
			)
			(xy 0.509016 -132.664454) (xy 1.015492 -132.664454)
			(arc
				(start 1.015492 -5.516372)
				(mid 1.15147 -5.163213)
				(end 1.49987 -5.01523)
			)
			(xy 1.500124 -5.01523) (xy 1.500124 -5.015484) (xy 23.266908 -5.015484) (xy 23.266908 -5.01523)
			(arc
				(start 23.50008 -5.01523)
				(mid 25.278456 -4.278498)
				(end 26.015188 -2.500122)
			)
			(arc
				(start 26.015188 -1.500124)
				(mid 26.157044 -1.157273)
				(end 26.49982 -1.015238)
			)
			(xy 26.500074 -1.015238) (xy 26.500074 -1.015492)
			(arc
				(start 101.000052 -1.015492)
				(mid 101.696201 -1.303847)
				(end 101.984556 -1.999996)
			)
			(xy 101.984556 -485.361234) (xy 101.98608 -485.381046) (xy 101.984556 -485.381046)
			(arc
				(start 101.984556 -527.99996)
				(mid 101.696201 -528.696109)
				(end 101.000052 -528.984464)
			)
			(xy 26.500074 -528.984464) (xy 26.500074 -528.984718)
			(arc
				(start 26.49982 -528.984718)
				(mid 26.157133 -528.842773)
				(end 26.015188 -528.500086)
			)
			(arc
				(start 26.015188 -527.500088)
				(mid 25.8238 -526.537447)
				(end 25.278588 -525.721326)
			)
			(arc
				(start 25.278588 -525.721326)
				(mid 24.462617 -525.176018)
				(end 23.50008 -524.984472)
			)
			(arc
				(start 1.516634 -524.984472)
				(mid 1.322224 -524.950922)
				(end 1.157224 -524.84274)
			)
			(arc
				(start 1.157224 -524.84274)
				(mid 1.052318 -524.685503)
				(end 1.015492 -524.500094)
			)
			(xy 1.015492 -408.615134) (xy 0.509016 -408.615134)
			(arc
				(start 0.509016 -524.500094)
				(mid 0.79923 -525.200734)
				(end 1.49987 -525.490948)
			)
			(arc
				(start 23.50008 -525.490948)
				(mid 24.920667 -526.079427)
				(end 25.508966 -527.500088)
			)
			(arc
				(start 25.508966 -528.500086)
				(mid 25.799345 -529.200741)
				(end 26.500074 -529.49094)
			)
		)
		(stroke
			(width 0)
			(type solid)
		)
		(fill yes)
		(layer "B.Cu")
		(net "GND")
	)
	(gr_poly
		(pts
			(xy 26.793444 -207.019652) (xy 26.793981 -207.036291) (xy 26.802579 -207.068439) (xy 26.819204 -207.097266)
			(xy 26.842722 -207.12081) (xy 26.871531 -207.137467) (xy 26.903669 -207.146101) (xy 26.936947 -207.146125)
			(xy 26.969097 -207.137538) (xy 26.997931 -207.120923) (xy 27.010106 -207.109568) (xy 29.07157 -205.048104)
			(xy 37.51707 -205.048104) (xy 41.805352 -200.759822) (xy 41.805352 -192.0621) (xy 40.613076 -190.869824)
			(xy 40.596771 -190.854219) (xy 40.559719 -190.828455) (xy 40.518701 -190.80964) (xy 40.475004 -190.798363)
			(xy 40.430002 -190.794981) (xy 40.385111 -190.799599) (xy 40.34174 -190.812072) (xy 40.301254 -190.832007)
			(xy 40.264924 -190.858779) (xy 40.233894 -190.891546) (xy 40.209137 -190.929278) (xy 40.199818 -190.949834)
			(xy 40.187669 -190.97705) (xy 40.157337 -191.028355) (xy 40.120602 -191.075289) (xy 40.078086 -191.117058)
			(xy 40.030509 -191.152956) (xy 39.978674 -191.182374) (xy 39.92346 -191.204815) (xy 39.865799 -191.2199)
			(xy 39.806669 -191.227374) (xy 39.747069 -191.227109) (xy 39.688007 -191.219111) (xy 39.630483 -191.203514)
			(xy 39.57547 -191.180583) (xy 39.523899 -191.150705) (xy 39.476642 -191.114387) (xy 39.434499 -191.072241)
			(xy 39.398183 -191.024983) (xy 39.368307 -190.97341) (xy 39.345379 -190.918396) (xy 39.329785 -190.860871)
			(xy 39.321789 -190.801809) (xy 39.321527 -190.742209) (xy 39.329004 -190.683079) (xy 39.344092 -190.625419)
			(xy 39.366536 -190.570206) (xy 39.395957 -190.518373) (xy 39.431856 -190.470797) (xy 39.473627 -190.428283)
			(xy 39.520563 -190.39155) (xy 39.57187 -190.361221) (xy 39.599108 -190.349124) (xy 39.619679 -190.33983)
			(xy 39.657427 -190.315083) (xy 39.690208 -190.284057) (xy 39.716992 -190.247726) (xy 39.736934 -190.207234)
			(xy 39.749409 -190.163856) (xy 39.754023 -190.118956) (xy 39.75063 -190.073948) (xy 39.739339 -190.030247)
			(xy 39.720503 -189.989228) (xy 39.694717 -189.952184) (xy 39.679118 -189.935866) (xy 36.698936 -186.955938)
			(xy 36.698936 -186.7408) (xy 36.698393 -186.72415) (xy 36.689776 -186.691984) (xy 36.673128 -186.663144)
			(xy 36.649585 -186.639594) (xy 36.620749 -186.622938) (xy 36.588586 -186.614312) (xy 36.571936 -186.6138)
			(xy 36.528756 -186.6138) (xy 36.460176 -186.666632) (xy 36.449254 -186.708542) (xy 36.4378 -186.750286)
			(xy 36.408243 -186.831652) (xy 36.371333 -186.909957) (xy 36.327381 -186.984538) (xy 36.27676 -187.054763)
			(xy 36.219898 -187.120037) (xy 36.157276 -187.179809) (xy 36.089426 -187.233571) (xy 36.016921 -187.280869)
			(xy 35.940376 -187.321303) (xy 35.860438 -187.354529) (xy 35.777784 -187.380267) (xy 35.693115 -187.398298)
			(xy 35.607147 -187.40847) (xy 35.520607 -187.410697) (xy 35.434229 -187.40496) (xy 35.348744 -187.391308)
			(xy 35.264876 -187.369855) (xy 35.223958 -187.355734) (xy 35.206858 -187.35032) (xy 35.171068 -187.348204)
			(xy 35.1361 -187.356119) (xy 35.10471 -187.37344) (xy 35.091624 -187.385706) (xy 34.621724 -187.855606)
			(xy 34.621724 -188.017404) (xy 34.622211 -188.040285) (xy 34.630406 -188.085308) (xy 34.646532 -188.128136)
			(xy 34.670066 -188.167383) (xy 34.700248 -188.201782) (xy 34.736101 -188.230221) (xy 34.776468 -188.251779)
			(xy 34.820043 -188.26576) (xy 34.865417 -188.271712) (xy 34.911123 -188.269443) (xy 34.955684 -188.259026)
			(xy 34.99766 -188.240797) (xy 35.016948 -188.228478) (xy 35.05315 -188.204854) (xy 35.129116 -188.163589)
			(xy 35.208549 -188.129472) (xy 35.290779 -188.102791) (xy 35.375111 -188.083771) (xy 35.460832 -188.072572)
			(xy 35.54722 -188.069291) (xy 35.633544 -188.073953) (xy 35.719076 -188.08652) (xy 35.803093 -188.106886)
			(xy 35.884886 -188.134879) (xy 35.963764 -188.170262) (xy 36.03906 -188.212736) (xy 36.110139 -188.261943)
			(xy 36.176402 -188.317467) (xy 36.237287 -188.37884) (xy 36.292281 -188.445543) (xy 36.34092 -188.517012)
			(xy 36.382793 -188.592645) (xy 36.417545 -188.671802) (xy 36.444885 -188.753815) (xy 36.46458 -188.837992)
			(xy 36.476465 -188.923621) (xy 36.480439 -189.00998) (xy 36.476469 -189.096339) (xy 36.464588 -189.181969)
			(xy 36.444896 -189.266146) (xy 36.41756 -189.348161) (xy 36.38281 -189.427319) (xy 36.340941 -189.502954)
			(xy 36.292305 -189.574425) (xy 36.237314 -189.64113) (xy 36.176431 -189.702506) (xy 36.110171 -189.758033)
			(xy 36.039094 -189.807243) (xy 35.963799 -189.84972) (xy 35.884923 -189.885107) (xy 35.803132 -189.913103)
			(xy 35.719116 -189.933472) (xy 35.633584 -189.946043) (xy 35.54726 -189.950709) (xy 35.460872 -189.947431)
			(xy 35.37515 -189.936236) (xy 35.290817 -189.91722) (xy 35.208586 -189.890542) (xy 35.129152 -189.856428)
			(xy 35.053184 -189.815166) (xy 35.016948 -189.791594) (xy 34.99766 -189.779274) (xy 34.955683 -189.761047)
			(xy 34.91112 -189.750631) (xy 34.865413 -189.748363) (xy 34.820038 -189.754315) (xy 34.776462 -189.768296)
			(xy 34.736094 -189.789854) (xy 34.700238 -189.818291) (xy 34.670054 -189.852689) (xy 34.646517 -189.891936)
			(xy 34.630388 -189.934763) (xy 34.622188 -189.979786) (xy 34.621724 -190.002668) (xy 34.621724 -190.557404)
			(xy 34.622211 -190.580285) (xy 34.630406 -190.625308) (xy 34.646532 -190.668136) (xy 34.670066 -190.707383)
			(xy 34.700248 -190.741782) (xy 34.736101 -190.770221) (xy 34.776468 -190.791779) (xy 34.820043 -190.80576)
			(xy 34.865417 -190.811712) (xy 34.911123 -190.809443) (xy 34.955684 -190.799026) (xy 34.99766 -190.780797)
			(xy 35.016948 -190.768478) (xy 35.05315 -190.744854) (xy 35.129116 -190.703589) (xy 35.208549 -190.669472)
			(xy 35.290779 -190.642791) (xy 35.375111 -190.623771) (xy 35.460832 -190.612572) (xy 35.54722 -190.609291)
			(xy 35.633544 -190.613953) (xy 35.719076 -190.62652) (xy 35.803093 -190.646886) (xy 35.884886 -190.674879)
			(xy 35.963764 -190.710262) (xy 36.03906 -190.752736) (xy 36.110139 -190.801943) (xy 36.176402 -190.857467)
			(xy 36.237287 -190.91884) (xy 36.292281 -190.985543) (xy 36.34092 -191.057012) (xy 36.382793 -191.132645)
			(xy 36.417545 -191.211802) (xy 36.444885 -191.293815) (xy 36.46458 -191.377992) (xy 36.476465 -191.463621)
			(xy 36.480439 -191.54998) (xy 36.476469 -191.636339) (xy 36.464588 -191.721969) (xy 36.444896 -191.806146)
			(xy 36.41756 -191.888161) (xy 36.38281 -191.967319) (xy 36.340941 -192.042954) (xy 36.292305 -192.114425)
			(xy 36.237314 -192.18113) (xy 36.176431 -192.242506) (xy 36.110171 -192.298033) (xy 36.039094 -192.347243)
			(xy 35.963799 -192.38972) (xy 35.884923 -192.425107) (xy 35.803132 -192.453103) (xy 35.719116 -192.473472)
			(xy 35.633584 -192.486043) (xy 35.54726 -192.490709) (xy 35.460872 -192.487431) (xy 35.37515 -192.476236)
			(xy 35.290817 -192.45722) (xy 35.208586 -192.430542) (xy 35.129152 -192.396428) (xy 35.053184 -192.355166)
			(xy 35.016948 -192.331594) (xy 34.99766 -192.319274) (xy 34.955683 -192.301047) (xy 34.91112 -192.290631)
			(xy 34.865413 -192.288363) (xy 34.820038 -192.294315) (xy 34.776462 -192.308296) (xy 34.736094 -192.329854)
			(xy 34.700238 -192.358291) (xy 34.670054 -192.392689) (xy 34.646517 -192.431936) (xy 34.630388 -192.474763)
			(xy 34.622188 -192.519786) (xy 34.621724 -192.542668) (xy 34.621724 -193.097404) (xy 34.622211 -193.120285)
			(xy 34.630406 -193.165308) (xy 34.646532 -193.208136) (xy 34.670066 -193.247383) (xy 34.700248 -193.281782)
			(xy 34.736101 -193.310221) (xy 34.776468 -193.331779) (xy 34.820043 -193.34576) (xy 34.865417 -193.351712)
			(xy 34.911123 -193.349443) (xy 34.955684 -193.339026) (xy 34.99766 -193.320797) (xy 35.016948 -193.308478)
			(xy 35.05315 -193.284854) (xy 35.129116 -193.243589) (xy 35.208549 -193.209472) (xy 35.290779 -193.182791)
			(xy 35.375111 -193.163771) (xy 35.460832 -193.152572) (xy 35.54722 -193.149291) (xy 35.633544 -193.153953)
			(xy 35.719076 -193.16652) (xy 35.803093 -193.186886) (xy 35.884886 -193.214879) (xy 35.963764 -193.250262)
			(xy 36.03906 -193.292736) (xy 36.110139 -193.341943) (xy 36.176402 -193.397467) (xy 36.237287 -193.45884)
			(xy 36.292281 -193.525543) (xy 36.34092 -193.597012) (xy 36.382793 -193.672645) (xy 36.417545 -193.751802)
			(xy 36.444885 -193.833815) (xy 36.46458 -193.917992) (xy 36.476465 -194.003621) (xy 36.480439 -194.08998)
			(xy 36.476469 -194.176339) (xy 36.464588 -194.261969) (xy 36.444896 -194.346146) (xy 36.41756 -194.428161)
			(xy 36.38281 -194.507319) (xy 36.340941 -194.582954) (xy 36.292305 -194.654425) (xy 36.237314 -194.72113)
			(xy 36.176431 -194.782506) (xy 36.110171 -194.838033) (xy 36.039094 -194.887243) (xy 35.963799 -194.92972)
			(xy 35.884923 -194.965107) (xy 35.803132 -194.993103) (xy 35.719116 -195.013472) (xy 35.633584 -195.026043)
			(xy 35.54726 -195.030709) (xy 35.460872 -195.027431) (xy 35.37515 -195.016236) (xy 35.290817 -194.99722)
			(xy 35.208586 -194.970542) (xy 35.129152 -194.936428) (xy 35.053184 -194.895166) (xy 35.016948 -194.871594)
			(xy 34.99766 -194.859274) (xy 34.955683 -194.841047) (xy 34.91112 -194.830631) (xy 34.865413 -194.828363)
			(xy 34.820038 -194.834315) (xy 34.776462 -194.848296) (xy 34.736094 -194.869854) (xy 34.700238 -194.898291)
			(xy 34.670054 -194.932689) (xy 34.646517 -194.971936) (xy 34.630388 -195.014763) (xy 34.622188 -195.059786)
			(xy 34.621724 -195.082668) (xy 34.621724 -195.637404) (xy 34.622211 -195.660285) (xy 34.630406 -195.705308)
			(xy 34.646532 -195.748136) (xy 34.670066 -195.787383) (xy 34.700248 -195.821782) (xy 34.736101 -195.850221)
			(xy 34.776468 -195.871779) (xy 34.820043 -195.88576) (xy 34.865417 -195.891712) (xy 34.911123 -195.889443)
			(xy 34.955684 -195.879026) (xy 34.99766 -195.860797) (xy 35.016948 -195.848478) (xy 35.05315 -195.824854)
			(xy 35.129116 -195.783589) (xy 35.208549 -195.749472) (xy 35.290779 -195.722791) (xy 35.375111 -195.703771)
			(xy 35.460832 -195.692572) (xy 35.54722 -195.689291) (xy 35.633544 -195.693953) (xy 35.719076 -195.70652)
			(xy 35.803093 -195.726886) (xy 35.884886 -195.754879) (xy 35.963764 -195.790262) (xy 36.03906 -195.832736)
			(xy 36.110139 -195.881943) (xy 36.176402 -195.937467) (xy 36.237287 -195.99884) (xy 36.292281 -196.065543)
			(xy 36.34092 -196.137012) (xy 36.382793 -196.212645) (xy 36.417545 -196.291802) (xy 36.444885 -196.373815)
			(xy 36.46458 -196.457992) (xy 36.476465 -196.543621) (xy 36.480439 -196.62998) (xy 36.476469 -196.716339)
			(xy 36.464588 -196.801969) (xy 36.444896 -196.886146) (xy 36.41756 -196.968161) (xy 36.38281 -197.047319)
			(xy 36.340941 -197.122954) (xy 36.292305 -197.194425) (xy 36.237314 -197.26113) (xy 36.176431 -197.322506)
			(xy 36.110171 -197.378033) (xy 36.039094 -197.427243) (xy 35.963799 -197.46972) (xy 35.884923 -197.505107)
			(xy 35.803132 -197.533103) (xy 35.719116 -197.553472) (xy 35.633584 -197.566043) (xy 35.54726 -197.570709)
			(xy 35.460872 -197.567431) (xy 35.37515 -197.556236) (xy 35.290817 -197.53722) (xy 35.208586 -197.510542)
			(xy 35.129152 -197.476428) (xy 35.053184 -197.435166) (xy 35.016948 -197.411594) (xy 34.99766 -197.399274)
			(xy 34.955683 -197.381047) (xy 34.91112 -197.370631) (xy 34.865413 -197.368363) (xy 34.820038 -197.374315)
			(xy 34.776462 -197.388296) (xy 34.736094 -197.409854) (xy 34.700238 -197.438291) (xy 34.670054 -197.472689)
			(xy 34.646517 -197.511936) (xy 34.630388 -197.554763) (xy 34.622188 -197.599786) (xy 34.621724 -197.622668)
			(xy 34.621724 -198.177404) (xy 34.622211 -198.200285) (xy 34.630406 -198.245308) (xy 34.646532 -198.288136)
			(xy 34.670066 -198.327383) (xy 34.700248 -198.361782) (xy 34.736101 -198.390221) (xy 34.776468 -198.411779)
			(xy 34.820043 -198.42576) (xy 34.865417 -198.431712) (xy 34.911123 -198.429443) (xy 34.955684 -198.419026)
			(xy 34.99766 -198.400797) (xy 35.016948 -198.388478) (xy 35.053066 -198.364908) (xy 35.128849 -198.323726)
			(xy 35.208086 -198.289658) (xy 35.290109 -198.262988) (xy 35.37423 -198.243943) (xy 35.459742 -198.232681)
			(xy 35.545926 -198.229298) (xy 35.632058 -198.233822) (xy 35.717413 -198.246214) (xy 35.801275 -198.266371)
			(xy 35.882938 -198.294124) (xy 35.961717 -198.329238) (xy 36.033396 -198.369428) (xy 39.992806 -198.369428)
			(xy 39.996877 -198.313806) (xy 40.009003 -198.259369) (xy 40.028926 -198.207278) (xy 40.056222 -198.158643)
			(xy 40.090308 -198.1145) (xy 40.130457 -198.075791) (xy 40.175815 -198.04334) (xy 40.225415 -198.017839)
			(xy 40.278199 -197.999832) (xy 40.333042 -197.989702) (xy 40.388776 -197.987665) (xy 40.444213 -197.993765)
			(xy 40.49817 -198.007871) (xy 40.549499 -198.029683) (xy 40.597105 -198.058737) (xy 40.639973 -198.094412)
			(xy 40.67719 -198.135949) (xy 40.707963 -198.182462) (xy 40.731635 -198.232959) (xy 40.747703 -198.286366)
			(xy 40.755823 -198.341542) (xy 40.756332 -198.369428) (xy 40.755823 -198.397314) (xy 40.747703 -198.45249)
			(xy 40.731635 -198.505897) (xy 40.707963 -198.556394) (xy 40.67719 -198.602907) (xy 40.639973 -198.644444)
			(xy 40.597105 -198.680119) (xy 40.549499 -198.709173) (xy 40.49817 -198.730985) (xy 40.444213 -198.745091)
			(xy 40.388776 -198.751191) (xy 40.333042 -198.749154) (xy 40.278199 -198.739024) (xy 40.225415 -198.721017)
			(xy 40.175815 -198.695516) (xy 40.130457 -198.663065) (xy 40.090308 -198.624356) (xy 40.056222 -198.580213)
			(xy 40.028926 -198.531578) (xy 40.009003 -198.479487) (xy 39.996877 -198.42505) (xy 39.992806 -198.369428)
			(xy 36.033396 -198.369428) (xy 36.036949 -198.37142) (xy 36.108002 -198.420313) (xy 36.174278 -198.475509)
			(xy 36.235222 -198.536541) (xy 36.29032 -198.602899) (xy 36.339109 -198.674023) (xy 36.38118 -198.749317)
			(xy 36.416179 -198.828147) (xy 36.443811 -198.909851) (xy 36.463846 -198.993743) (xy 36.476113 -199.079116)
			(xy 36.48051 -199.165254) (xy 36.477 -199.251433) (xy 36.465613 -199.336928) (xy 36.446444 -199.421021)
			(xy 36.419655 -199.503006) (xy 36.38547 -199.582192) (xy 36.344177 -199.657915) (xy 36.296123 -199.729539)
			(xy 36.241711 -199.79646) (xy 36.1814 -199.858118) (xy 36.115695 -199.913993) (xy 36.04515 -199.963616)
			(xy 35.970357 -200.00657) (xy 35.891944 -200.042494) (xy 35.810571 -200.071086) (xy 35.726921 -200.092106)
			(xy 35.641698 -200.105377) (xy 35.555618 -200.110788) (xy 35.469403 -200.108293) (xy 35.38378 -200.097912)
			(xy 35.299467 -200.079735) (xy 35.217173 -200.053912) (xy 35.13759 -200.020661) (xy 35.061386 -199.980262)
			(xy 34.989202 -199.933054) (xy 34.921645 -199.879434) (xy 34.859282 -199.819852) (xy 34.802637 -199.75481)
			(xy 34.752188 -199.684853) (xy 34.708356 -199.610571) (xy 34.671512 -199.532586) (xy 34.641964 -199.451555)
			(xy 34.619961 -199.368159) (xy 34.605688 -199.283098) (xy 34.599265 -199.197087) (xy 34.600745 -199.110849)
			(xy 34.60496 -199.067928) (xy 34.606934 -199.045628) (xy 34.603949 -199.000963) (xy 34.593184 -198.957512)
			(xy 34.574972 -198.91662) (xy 34.549878 -198.879551) (xy 34.518676 -198.847453) (xy 34.482333 -198.821318)
			(xy 34.441973 -198.801955) (xy 34.398844 -198.789964) (xy 34.354282 -198.785715) (xy 34.309665 -198.789339)
			(xy 34.266373 -198.800725) (xy 34.225745 -198.819521) (xy 34.18904 -198.845144) (xy 34.172906 -198.860664)
			(xy 32.008826 -201.024744) (xy 29.234384 -201.024744) (xy 29.114496 -201.144632) (xy 29.103044 -201.156742)
			(xy 29.086347 -201.185576) (xy 29.077703 -201.217755) (xy 29.077707 -201.251075) (xy 29.086358 -201.283252)
			(xy 29.103062 -201.312081) (xy 29.114496 -201.32421) (xy 29.124402 -201.334116) (xy 29.136594 -201.341736)
			(xy 29.162525 -201.358662) (xy 29.210267 -201.3981) (xy 29.252579 -201.443315) (xy 29.288766 -201.493566)
			(xy 29.318237 -201.548029) (xy 29.340507 -201.60581) (xy 29.355211 -201.665964) (xy 29.36211 -201.727503)
			(xy 29.361088 -201.789419) (xy 29.352164 -201.850698) (xy 29.335483 -201.910334) (xy 29.311319 -201.967349)
			(xy 29.280069 -202.02081) (xy 29.242243 -202.06984) (xy 29.220668 -202.092052) (xy 26.089356 -205.223364)
			(xy 26.089356 -205.54696) (xy 26.089853 -205.569995) (xy 26.098152 -205.615312) (xy 26.114484 -205.658389)
			(xy 26.138316 -205.697817) (xy 26.168865 -205.732301) (xy 26.205131 -205.760713) (xy 26.245925 -205.782122)
			(xy 26.28991 -205.795824) (xy 26.335644 -205.801373) (xy 26.38163 -205.798585) (xy 26.426359 -205.787552)
			(xy 26.468367 -205.768636) (xy 26.506276 -205.742456) (xy 26.522934 -205.726538) (xy 29.725112 -202.52436)
			(xy 37.161216 -202.52436) (xy 40.057832 -199.62749) (xy 40.079917 -199.606107) (xy 40.128567 -199.56853)
			(xy 40.181593 -199.53743) (xy 40.238136 -199.513309) (xy 40.297282 -199.496558) (xy 40.358076 -199.487446)
			(xy 40.388794 -199.486266) (xy 40.411982 -199.485213) (xy 40.457416 -199.475734) (xy 40.500375 -199.458167)
			(xy 40.539432 -199.433095) (xy 40.573292 -199.401352) (xy 40.600828 -199.363991) (xy 40.621126 -199.322253)
			(xy 40.633513 -199.277525) (xy 40.637577 -199.231291) (xy 40.635936 -199.208136) (xy 40.633798 -199.180497)
			(xy 40.636575 -199.125133) (xy 40.647335 -199.070753) (xy 40.665853 -199.018504) (xy 40.691739 -198.969484)
			(xy 40.724446 -198.924728) (xy 40.763287 -198.885176) (xy 40.807443 -198.851663) (xy 40.855985 -198.824893)
			(xy 40.90789 -198.80543) (xy 40.962065 -198.793685) (xy 41.01737 -198.789905) (xy 41.07264 -198.794169)
			(xy 41.126711 -198.806387) (xy 41.178444 -198.826302) (xy 41.226749 -198.853496) (xy 41.270611 -198.887394)
			(xy 41.309104 -198.927284) (xy 41.341419 -198.972325) (xy 41.366875 -199.021569) (xy 41.384935 -199.073978)
			(xy 41.39522 -199.12845) (xy 41.397512 -199.183836) (xy 41.391765 -199.238971) (xy 41.378097 -199.292694)
			(xy 41.356799 -199.343873) (xy 41.328317 -199.391431) (xy 41.293252 -199.434365) (xy 41.252342 -199.471773)
			(xy 41.206449 -199.502865) (xy 41.156539 -199.526988) (xy 41.103663 -199.543633) (xy 41.076372 -199.548496)
			(xy 41.05352 -199.552683) (xy 41.009752 -199.568247) (xy 40.969539 -199.591503) (xy 40.93422 -199.621676)
			(xy 40.90497 -199.657763) (xy 40.882762 -199.698564) (xy 40.868335 -199.74272) (xy 40.862169 -199.788762)
			(xy 40.86447 -199.835158) (xy 40.869362 -199.857868) (xy 40.875992 -199.887888) (xy 40.882483 -199.949025)
			(xy 40.881163 -200.01049) (xy 40.872054 -200.071292) (xy 40.855304 -200.130446) (xy 40.831182 -200.186996)
			(xy 40.80008 -200.240028) (xy 40.762499 -200.288685) (xy 40.741092 -200.31075) (xy 37.56152 -203.490068)
			(xy 30.125416 -203.490068) (xy 26.793444 -206.822294)
		)
		(stroke
			(width 0)
			(type solid)
		)
		(fill yes)
		(layer "B.Cu")
		(net "GND")
	)
	(gr_poly
		(pts
			(xy 31.407862 -370.731542) (xy 31.41997 -370.743) (xy 31.448805 -370.75971) (xy 31.480988 -370.768361)
			(xy 31.514314 -370.768361) (xy 31.546497 -370.75971) (xy 31.575332 -370.743) (xy 31.58744 -370.731542)
			(xy 31.677356 -370.64188) (xy 31.677356 -359.875074) (xy 30.881574 -359.079546) (xy 30.809946 -359.06329)
			(xy 30.775402 -359.075736) (xy 30.733602 -359.090098) (xy 30.647925 -359.11183) (xy 30.560587 -359.125425)
			(xy 30.472358 -359.130765) (xy 30.384017 -359.127801) (xy 30.296344 -359.11656) (xy 30.210114 -359.097141)
			(xy 30.126086 -359.069716) (xy 30.045002 -359.034526) (xy 29.967579 -358.991882) (xy 29.894499 -358.942161)
			(xy 29.826408 -358.885801) (xy 29.763906 -358.8233) (xy 29.707545 -358.75521) (xy 29.657823 -358.68213)
			(xy 29.615179 -358.604708) (xy 29.579988 -358.523625) (xy 29.552562 -358.439597) (xy 29.533142 -358.353366)
			(xy 29.5219 -358.265694) (xy 29.518935 -358.177353) (xy 29.524273 -358.089124) (xy 29.537868 -358.001785)
			(xy 29.559599 -357.916108) (xy 29.573982 -357.874316) (xy 29.586428 -357.839772) (xy 29.570172 -357.768144)
			(xy 26.699972 -354.897944) (xy 26.684118 -354.882753) (xy 26.648194 -354.857514) (xy 26.608467 -354.838825)
			(xy 26.566118 -354.827243) (xy 26.522409 -354.82311) (xy 26.478641 -354.826552) (xy 26.436115 -354.837465)
			(xy 26.396097 -354.855524) (xy 26.359779 -354.880192) (xy 26.328241 -354.910735) (xy 26.302421 -354.946245)
			(xy 26.283089 -354.985663) (xy 26.270819 -355.027817) (xy 26.267918 -355.049582) (xy 26.26411 -355.079593)
			(xy 26.249601 -355.138322) (xy 26.227481 -355.194628) (xy 26.198136 -355.24753) (xy 26.162077 -355.296104)
			(xy 26.119934 -355.339504) (xy 26.072441 -355.376975) (xy 26.020425 -355.407862) (xy 25.964793 -355.431627)
			(xy 25.906515 -355.447856) (xy 25.846608 -355.456266) (xy 25.786114 -355.456711) (xy 25.726089 -355.449182)
			(xy 25.667579 -355.433812) (xy 25.611604 -355.410867) (xy 25.55914 -355.380748) (xy 25.5111 -355.34398)
			(xy 25.468324 -355.301204) (xy 25.431555 -355.253165) (xy 25.401435 -355.200701) (xy 25.37849 -355.144726)
			(xy 25.363119 -355.086216) (xy 25.355589 -355.026191) (xy 25.356033 -354.965698) (xy 25.364443 -354.90579)
			(xy 25.380671 -354.847512) (xy 25.404436 -354.79188) (xy 25.435322 -354.739864) (xy 25.472792 -354.69237)
			(xy 25.516192 -354.650226) (xy 25.564766 -354.614167) (xy 25.617667 -354.584821) (xy 25.673973 -354.562701)
			(xy 25.732702 -354.54819) (xy 25.762712 -354.544376) (xy 25.784487 -354.541502) (xy 25.82666 -354.529243)
			(xy 25.866097 -354.509916) (xy 25.901624 -354.484097) (xy 25.932183 -354.452554) (xy 25.956864 -354.416227)
			(xy 25.974933 -354.376198) (xy 25.98585 -354.333658) (xy 25.989291 -354.289875) (xy 25.985154 -354.246152)
			(xy 25.973561 -354.203792) (xy 25.954858 -354.164055) (xy 25.929602 -354.128125) (xy 25.91435 -354.112322)
			(xy 24.1808 -352.378518) (xy 24.1808 -337.436206) (xy 25.122886 -336.49412) (xy 25.127966 -336.449924)
			(xy 25.131864 -336.419978) (xy 25.14653 -336.361397) (xy 25.168776 -336.305254) (xy 25.198213 -336.252525)
			(xy 25.23433 -336.204127) (xy 25.2765 -336.1609) (xy 25.32399 -336.123596) (xy 25.375974 -336.092863)
			(xy 25.431549 -336.069236) (xy 25.48975 -336.053124) (xy 25.549563 -336.044808) (xy 25.609952 -336.044433)
			(xy 25.669864 -336.052004) (xy 25.728261 -336.067391) (xy 25.784125 -336.090325) (xy 25.836488 -336.120409)
			(xy 25.884438 -336.15712) (xy 25.927142 -336.199819) (xy 25.963859 -336.247764) (xy 25.993949 -336.300123)
			(xy 26.016891 -336.355984) (xy 26.032285 -336.414379) (xy 26.039864 -336.47429) (xy 26.039496 -336.534679)
			(xy 26.031188 -336.594494) (xy 26.015083 -336.652696) (xy 25.991463 -336.708274) (xy 25.960737 -336.760262)
			(xy 25.923439 -336.807757) (xy 25.880217 -336.849932) (xy 25.831823 -336.886056) (xy 25.779098 -336.915499)
			(xy 25.722958 -336.937752) (xy 25.664379 -336.952426) (xy 25.634442 -336.9564) (xy 25.590246 -336.96148)
			(xy 24.841708 -337.710018) (xy 24.841708 -339.516466) (xy 24.8422 -339.533133) (xy 24.850826 -339.565332)
			(xy 24.867497 -339.594198) (xy 24.891077 -339.61776) (xy 24.919955 -339.634411) (xy 24.952161 -339.643012)
			(xy 24.985495 -339.642979) (xy 25.017683 -339.634312) (xy 25.046527 -339.617603) (xy 25.058624 -339.606128)
			(xy 25.122886 -339.54212) (xy 25.127966 -339.497924) (xy 25.131805 -339.468421) (xy 25.146142 -339.410678)
			(xy 25.167843 -339.35528) (xy 25.196541 -339.303163) (xy 25.231751 -339.255204) (xy 25.272881 -339.212214)
			(xy 25.319236 -339.174918) (xy 25.370034 -339.143944) (xy 25.424418 -339.119815) (xy 25.481471 -339.102939)
			(xy 25.540229 -339.0936) (xy 25.599703 -339.091956) (xy 25.658888 -339.098034) (xy 25.716786 -339.111731)
			(xy 25.77242 -339.132818) (xy 25.824852 -339.160937) (xy 25.873197 -339.195615) (xy 25.916639 -339.236267)
			(xy 25.93594 -339.25891) (xy 25.954228 -339.281008) (xy 26.005282 -339.305138) (xy 26.033984 -339.305138)
			(xy 26.050636 -339.304597) (xy 26.082805 -339.295982) (xy 26.111649 -339.279336) (xy 26.135203 -339.255792)
			(xy 26.151862 -339.226955) (xy 26.16049 -339.194789) (xy 26.160984 -339.178138) (xy 26.160984 -339.071712)
			(xy 25.575006 -338.48548) (xy 25.53081 -338.4804) (xy 25.500863 -338.476499) (xy 25.442279 -338.461827)
			(xy 25.386135 -338.439575) (xy 25.333406 -338.410132) (xy 25.285008 -338.374009) (xy 25.241782 -338.331833)
			(xy 25.20448 -338.284337) (xy 25.173749 -338.232347) (xy 25.150125 -338.176767) (xy 25.134017 -338.118562)
			(xy 25.125705 -338.058744) (xy 25.125334 -337.998353) (xy 25.13291 -337.938437) (xy 25.148302 -337.880038)
			(xy 25.171242 -337.824172) (xy 25.201331 -337.771809) (xy 25.238047 -337.723859) (xy 25.280751 -337.681155)
			(xy 25.328702 -337.644439) (xy 25.381065 -337.61435) (xy 25.436932 -337.591411) (xy 25.49533 -337.576019)
			(xy 25.555246 -337.568444) (xy 25.615638 -337.568815) (xy 25.675456 -337.577127) (xy 25.73366 -337.593236)
			(xy 25.78924 -337.616861) (xy 25.84123 -337.647592) (xy 25.888725 -337.684895) (xy 25.930901 -337.728121)
			(xy 25.967024 -337.776519) (xy 25.996467 -337.829249) (xy 26.018718 -337.885393) (xy 26.03339 -337.943976)
			(xy 26.037286 -337.973924) (xy 26.042366 -338.01812) (xy 26.246836 -338.22259) (xy 26.263477 -338.238547)
			(xy 26.301398 -338.264759) (xy 26.343425 -338.283704) (xy 26.388179 -338.294759) (xy 26.434193 -338.297562)
			(xy 26.479957 -338.292021) (xy 26.523973 -338.278317) (xy 26.564795 -338.2569) (xy 26.601086 -338.228473)
			(xy 26.631655 -338.193967) (xy 26.6555 -338.154514) (xy 26.67184 -338.111408) (xy 26.680137 -338.066062)
			(xy 26.680668 -338.043012) (xy 26.680668 -336.543142) (xy 25.575006 -335.43748) (xy 25.53081 -335.4324)
			(xy 25.500863 -335.428499) (xy 25.442279 -335.413827) (xy 25.386135 -335.391575) (xy 25.333406 -335.362132)
			(xy 25.285008 -335.326009) (xy 25.241782 -335.283833) (xy 25.20448 -335.236337) (xy 25.173749 -335.184347)
			(xy 25.150125 -335.128767) (xy 25.134017 -335.070562) (xy 25.125705 -335.010744) (xy 25.125334 -334.950353)
			(xy 25.13291 -334.890437) (xy 25.148302 -334.832038) (xy 25.171242 -334.776172) (xy 25.201331 -334.723809)
			(xy 25.238047 -334.675859) (xy 25.280751 -334.633155) (xy 25.328702 -334.596439) (xy 25.381065 -334.56635)
			(xy 25.436932 -334.543411) (xy 25.49533 -334.528019) (xy 25.555246 -334.520444) (xy 25.615638 -334.520815)
			(xy 25.675456 -334.529127) (xy 25.73366 -334.545236) (xy 25.78924 -334.568861) (xy 25.84123 -334.599592)
			(xy 25.888725 -334.636895) (xy 25.930901 -334.680121) (xy 25.967024 -334.728519) (xy 25.996467 -334.781249)
			(xy 26.018718 -334.837393) (xy 26.03339 -334.895976) (xy 26.037286 -334.925924) (xy 26.042366 -334.97012)
			(xy 26.672032 -335.599786) (xy 26.688673 -335.615743) (xy 26.726594 -335.641957) (xy 26.768621 -335.660903)
			(xy 26.813376 -335.671959) (xy 26.85939 -335.674762) (xy 26.905156 -335.669221) (xy 26.949172 -335.655517)
			(xy 26.989995 -335.6341) (xy 27.026286 -335.605673) (xy 27.056856 -335.571166) (xy 27.080701 -335.531712)
			(xy 27.09704 -335.488605) (xy 27.105338 -335.443258) (xy 27.105864 -335.420208) (xy 27.105864 -333.920338)
			(xy 25.575006 -332.38948) (xy 25.53081 -332.3844) (xy 25.500863 -332.380499) (xy 25.442279 -332.365827)
			(xy 25.386135 -332.343575) (xy 25.333406 -332.314132) (xy 25.285008 -332.278009) (xy 25.241782 -332.235833)
			(xy 25.20448 -332.188337) (xy 25.173749 -332.136347) (xy 25.150125 -332.080767) (xy 25.134017 -332.022562)
			(xy 25.125705 -331.962744) (xy 25.125334 -331.902353) (xy 25.13291 -331.842437) (xy 25.148302 -331.784038)
			(xy 25.171242 -331.728172) (xy 25.201331 -331.675809) (xy 25.238047 -331.627859) (xy 25.280751 -331.585155)
			(xy 25.328702 -331.548439) (xy 25.381065 -331.51835) (xy 25.436932 -331.495411) (xy 25.49533 -331.480019)
			(xy 25.555246 -331.472444) (xy 25.615638 -331.472815) (xy 25.675456 -331.481127) (xy 25.73366 -331.497236)
			(xy 25.78924 -331.520861) (xy 25.84123 -331.551592) (xy 25.888725 -331.588895) (xy 25.930901 -331.632121)
			(xy 25.967024 -331.680519) (xy 25.996467 -331.733249) (xy 26.018718 -331.789393) (xy 26.03339 -331.847976)
			(xy 26.037286 -331.877924) (xy 26.042366 -331.92212) (xy 27.173428 -333.053182) (xy 27.190069 -333.06914)
			(xy 27.22799 -333.095355) (xy 27.270018 -333.114302) (xy 27.314773 -333.125358) (xy 27.360788 -333.128162)
			(xy 27.406554 -333.122621) (xy 27.450571 -333.108918) (xy 27.491395 -333.0875) (xy 27.527687 -333.059072)
			(xy 27.558257 -333.024565) (xy 27.582102 -332.98511) (xy 27.598441 -332.942002) (xy 27.606738 -332.896655)
			(xy 27.60726 -332.873604) (xy 27.60726 -292.986714) (xy 29.692092 -290.901628) (xy 38.54704 -290.901628)
			(xy 39.704518 -289.744404) (xy 39.720482 -289.727765) (xy 39.746709 -289.689845) (xy 39.765666 -289.647815)
			(xy 39.776731 -289.603056) (xy 39.77954 -289.557035) (xy 39.774002 -289.511262) (xy 39.760297 -289.467239)
			(xy 39.738877 -289.426411) (xy 39.710443 -289.390115) (xy 39.675929 -289.359545) (xy 39.636466 -289.335701)
			(xy 39.593349 -289.319367) (xy 39.547994 -289.311079) (xy 39.52494 -289.310572) (xy 27.607768 -289.310572)
			(xy 22.56282 -284.265624) (xy 22.56282 -279.760934) (xy 18.934176 -276.132544) (xy 18.934176 -257.777234)
			(xy 18.934649 -257.746901) (xy 18.942242 -257.686712) (xy 18.957312 -257.627947) (xy 18.979622 -257.571532)
			(xy 19.008822 -257.518355) (xy 19.04445 -257.469253) (xy 19.085947 -257.424999) (xy 19.132659 -257.38629)
			(xy 19.183851 -257.353736) (xy 19.238716 -257.327848) (xy 19.296392 -257.309034) (xy 19.355969 -257.297591)
			(xy 19.41651 -257.293699) (xy 19.477062 -257.297419) (xy 19.536672 -257.308692) (xy 19.594401 -257.327341)
			(xy 19.64934 -257.353072) (xy 19.700624 -257.38548) (xy 19.72437 -257.404362) (xy 19.738236 -257.415083)
			(xy 19.770312 -257.429179) (xy 19.805015 -257.434) (xy 19.839718 -257.429179) (xy 19.871794 -257.415083)
			(xy 19.88566 -257.404362) (xy 19.908653 -257.385987) (xy 19.958296 -257.354364) (xy 20.011417 -257.329014)
			(xy 20.067227 -257.310313) (xy 20.124897 -257.298539) (xy 20.183571 -257.293867) (xy 20.242378 -257.296367)
			(xy 20.271486 -257.30073) (xy 20.293314 -257.30386) (xy 20.337405 -257.303432) (xy 20.38076 -257.295398)
			(xy 20.422076 -257.279999) (xy 20.460113 -257.257698) (xy 20.493728 -257.229164) (xy 20.521912 -257.195254)
			(xy 20.543818 -257.156988) (xy 20.558788 -257.115514) (xy 20.566372 -257.072079) (xy 20.566888 -257.050032)
			(xy 20.566888 -240.260124) (xy 17.122902 -236.816138) (xy 17.106261 -236.800176) (xy 17.068339 -236.773953)
			(xy 17.026308 -236.755) (xy 16.981549 -236.743938) (xy 16.935528 -236.741131) (xy 16.889756 -236.746669)
			(xy 16.845733 -236.760373) (xy 16.804904 -236.781792) (xy 16.768608 -236.810223) (xy 16.738035 -236.844735)
			(xy 16.714187 -236.884195) (xy 16.697848 -236.927309) (xy 16.689553 -236.972663) (xy 16.68907 -236.995716)
			(xy 16.689324 -252.17374) (xy 18.190464 -253.675134) (xy 18.190464 -275.901658) (xy 22.03196 -279.743154)
			(xy 22.03196 -284.317948) (xy 26.561288 -288.847022) (xy 26.561288 -319.824608) (xy 22.641052 -323.744844)
			(xy 22.641052 -333.483708) (xy 25.125408 -333.483708) (xy 25.125408 -333.423772) (xy 25.133231 -333.36435)
			(xy 25.148744 -333.306457) (xy 25.17168 -333.251084) (xy 25.201647 -333.199178) (xy 25.238134 -333.151628)
			(xy 25.280514 -333.109248) (xy 25.328064 -333.072761) (xy 25.37997 -333.042794) (xy 25.435343 -333.019858)
			(xy 25.493236 -333.004345) (xy 25.552658 -332.996522) (xy 25.612594 -332.996522) (xy 25.672016 -333.004345)
			(xy 25.729909 -333.019858) (xy 25.785282 -333.042794) (xy 25.837188 -333.072761) (xy 25.884738 -333.109248)
			(xy 25.927118 -333.151628) (xy 25.963605 -333.199178) (xy 25.993572 -333.251084) (xy 26.016508 -333.306457)
			(xy 26.032021 -333.36435) (xy 26.039844 -333.423772) (xy 26.040334 -333.45374) (xy 26.039844 -333.483708)
			(xy 26.032021 -333.54313) (xy 26.016508 -333.601023) (xy 25.993572 -333.656396) (xy 25.963605 -333.708302)
			(xy 25.927118 -333.755852) (xy 25.884738 -333.798232) (xy 25.837188 -333.834719) (xy 25.785282 -333.864686)
			(xy 25.729909 -333.887622) (xy 25.672016 -333.903135) (xy 25.612594 -333.910958) (xy 25.552658 -333.910958)
			(xy 25.493236 -333.903135) (xy 25.435343 -333.887622) (xy 25.37997 -333.864686) (xy 25.328064 -333.834719)
			(xy 25.280514 -333.798232) (xy 25.238134 -333.755852) (xy 25.201647 -333.708302) (xy 25.17168 -333.656396)
			(xy 25.148744 -333.601023) (xy 25.133231 -333.54313) (xy 25.125408 -333.483708) (xy 22.641052 -333.483708)
			(xy 22.641052 -354.456996) (xy 24.056322 -354.456996) (xy 24.056322 -354.39706) (xy 24.064145 -354.337638)
			(xy 24.079658 -354.279745) (xy 24.102594 -354.224372) (xy 24.132561 -354.172466) (xy 24.169048 -354.124916)
			(xy 24.211428 -354.082536) (xy 24.258978 -354.046049) (xy 24.310884 -354.016082) (xy 24.366257 -353.993146)
			(xy 24.42415 -353.977633) (xy 24.483572 -353.96981) (xy 24.543508 -353.96981) (xy 24.60293 -353.977633)
			(xy 24.660823 -353.993146) (xy 24.716196 -354.016082) (xy 24.768102 -354.046049) (xy 24.815652 -354.082536)
			(xy 24.858032 -354.124916) (xy 24.894519 -354.172466) (xy 24.924486 -354.224372) (xy 24.947422 -354.279745)
			(xy 24.962935 -354.337638) (xy 24.970758 -354.39706) (xy 24.971248 -354.427028) (xy 24.970758 -354.456996)
			(xy 24.962935 -354.516418) (xy 24.947422 -354.574311) (xy 24.924486 -354.629684) (xy 24.894519 -354.68159)
			(xy 24.858032 -354.72914) (xy 24.815652 -354.77152) (xy 24.768102 -354.808007) (xy 24.716196 -354.837974)
			(xy 24.660823 -354.86091) (xy 24.60293 -354.876423) (xy 24.543508 -354.884246) (xy 24.483572 -354.884246)
			(xy 24.42415 -354.876423) (xy 24.366257 -354.86091) (xy 24.310884 -354.837974) (xy 24.258978 -354.808007)
			(xy 24.211428 -354.77152) (xy 24.169048 -354.72914) (xy 24.132561 -354.68159) (xy 24.102594 -354.629684)
			(xy 24.079658 -354.574311) (xy 24.064145 -354.516418) (xy 24.056322 -354.456996) (xy 22.641052 -354.456996)
			(xy 22.641052 -356.112064) (xy 26.531316 -360.002328) (xy 26.531316 -360.247438) (xy 26.531864 -360.264082)
			(xy 26.540488 -360.296235) (xy 26.55714 -360.32506) (xy 26.580683 -360.348593) (xy 26.609516 -360.365232)
			(xy 26.641671 -360.373843) (xy 26.658316 -360.374438) (xy 26.674593 -360.37394) (xy 26.706085 -360.365691)
			(xy 26.73446 -360.349736) (xy 26.75787 -360.327114) (xy 26.766774 -360.313478) (xy 26.782754 -360.288083)
			(xy 26.820341 -360.241315) (xy 26.863718 -360.19986) (xy 26.91214 -360.164429) (xy 26.964776 -360.135629)
			(xy 27.020725 -360.113955) (xy 27.079027 -360.099778) (xy 27.138681 -360.093341) (xy 27.198665 -360.094755)
			(xy 27.25795 -360.103995) (xy 27.315518 -360.120903) (xy 27.370384 -360.14519) (xy 27.421606 -360.176437)
			(xy 27.468304 -360.214111) (xy 27.50968 -360.257563) (xy 27.545022 -360.30605) (xy 27.573725 -360.35874)
			(xy 27.595296 -360.414729) (xy 27.609366 -360.473056) (xy 27.615694 -360.532722) (xy 27.614169 -360.592703)
			(xy 27.60482 -360.651971) (xy 27.587806 -360.709509) (xy 27.563419 -360.764329) (xy 27.557808 -360.773488)
			(xy 29.519874 -360.773488) (xy 29.519874 -360.686588) (xy 29.527892 -360.600059) (xy 29.54386 -360.514639)
			(xy 29.567641 -360.431057) (xy 29.599033 -360.350025) (xy 29.637767 -360.272236) (xy 29.683514 -360.198352)
			(xy 29.735883 -360.129005) (xy 29.794427 -360.064785) (xy 29.858647 -360.006241) (xy 29.927994 -359.953872)
			(xy 30.001878 -359.908125) (xy 30.079667 -359.869391) (xy 30.160699 -359.837999) (xy 30.244281 -359.814218)
			(xy 30.329701 -359.79825) (xy 30.41623 -359.790232) (xy 30.50313 -359.790232) (xy 30.589659 -359.79825)
			(xy 30.675079 -359.814218) (xy 30.758661 -359.837999) (xy 30.839693 -359.869391) (xy 30.917482 -359.908125)
			(xy 30.991366 -359.953872) (xy 31.060713 -360.006241) (xy 31.124933 -360.064785) (xy 31.183477 -360.129005)
			(xy 31.235846 -360.198352) (xy 31.281593 -360.272236) (xy 31.320327 -360.350025) (xy 31.351719 -360.431057)
			(xy 31.3755 -360.514639) (xy 31.391468 -360.600059) (xy 31.399486 -360.686588) (xy 31.399988 -360.730038)
			(xy 31.399486 -360.773488) (xy 31.391468 -360.860017) (xy 31.3755 -360.945437) (xy 31.351719 -361.029019)
			(xy 31.320327 -361.110051) (xy 31.281593 -361.18784) (xy 31.235846 -361.261724) (xy 31.183477 -361.331071)
			(xy 31.124933 -361.395291) (xy 31.060713 -361.453835) (xy 30.991366 -361.506204) (xy 30.917482 -361.551951)
			(xy 30.839693 -361.590685) (xy 30.758661 -361.622077) (xy 30.675079 -361.645858) (xy 30.589659 -361.661826)
			(xy 30.50313 -361.669844) (xy 30.41623 -361.669844) (xy 30.329701 -361.661826) (xy 30.244281 -361.645858)
			(xy 30.160699 -361.622077) (xy 30.079667 -361.590685) (xy 30.001878 -361.551951) (xy 29.927994 -361.506204)
			(xy 29.858647 -361.453835) (xy 29.794427 -361.395291) (xy 29.735883 -361.331071) (xy 29.683514 -361.261724)
			(xy 29.637767 -361.18784) (xy 29.599033 -361.110051) (xy 29.567641 -361.029019) (xy 29.54386 -360.945437)
			(xy 29.527892 -360.860017) (xy 29.519874 -360.773488) (xy 27.557808 -360.773488) (xy 27.532077 -360.815493)
			(xy 27.494318 -360.862123) (xy 27.45079 -360.903418) (xy 27.402238 -360.938671) (xy 27.349496 -360.967278)
			(xy 27.293467 -360.988746) (xy 27.235114 -361.002709) (xy 27.175437 -361.008927) (xy 27.115459 -361.007292)
			(xy 27.056208 -360.997834) (xy 26.998702 -360.980714) (xy 26.943926 -360.956227) (xy 26.918158 -360.940858)
			(xy 26.898764 -360.929516) (xy 26.85694 -360.913113) (xy 26.812885 -360.904321) (xy 26.767969 -360.903412)
			(xy 26.723594 -360.910416) (xy 26.681142 -360.925113) (xy 26.641936 -360.947047) (xy 26.607198 -360.975534)
			(xy 26.57801 -361.009685) (xy 26.555282 -361.048436) (xy 26.539723 -361.09058) (xy 26.531817 -361.134804)
			(xy 26.531316 -361.157266) (xy 26.531316 -363.313488) (xy 29.519874 -363.313488) (xy 29.519874 -363.226588)
			(xy 29.527892 -363.140059) (xy 29.54386 -363.054639) (xy 29.567641 -362.971057) (xy 29.599033 -362.890025)
			(xy 29.637767 -362.812236) (xy 29.683514 -362.738352) (xy 29.735883 -362.669005) (xy 29.794427 -362.604785)
			(xy 29.858647 -362.546241) (xy 29.927994 -362.493872) (xy 30.001878 -362.448125) (xy 30.079667 -362.409391)
			(xy 30.160699 -362.377999) (xy 30.244281 -362.354218) (xy 30.329701 -362.33825) (xy 30.41623 -362.330232)
			(xy 30.50313 -362.330232) (xy 30.589659 -362.33825) (xy 30.675079 -362.354218) (xy 30.758661 -362.377999)
			(xy 30.839693 -362.409391) (xy 30.917482 -362.448125) (xy 30.991366 -362.493872) (xy 31.060713 -362.546241)
			(xy 31.124933 -362.604785) (xy 31.183477 -362.669005) (xy 31.235846 -362.738352) (xy 31.281593 -362.812236)
			(xy 31.320327 -362.890025) (xy 31.351719 -362.971057) (xy 31.3755 -363.054639) (xy 31.391468 -363.140059)
			(xy 31.399486 -363.226588) (xy 31.399988 -363.270038) (xy 31.399486 -363.313488) (xy 31.391468 -363.400017)
			(xy 31.3755 -363.485437) (xy 31.351719 -363.569019) (xy 31.320327 -363.650051) (xy 31.281593 -363.72784)
			(xy 31.235846 -363.801724) (xy 31.183477 -363.871071) (xy 31.124933 -363.935291) (xy 31.060713 -363.993835)
			(xy 30.991366 -364.046204) (xy 30.917482 -364.091951) (xy 30.839693 -364.130685) (xy 30.758661 -364.162077)
			(xy 30.675079 -364.185858) (xy 30.589659 -364.201826) (xy 30.50313 -364.209844) (xy 30.41623 -364.209844)
			(xy 30.329701 -364.201826) (xy 30.244281 -364.185858) (xy 30.160699 -364.162077) (xy 30.079667 -364.130685)
			(xy 30.001878 -364.091951) (xy 29.927994 -364.046204) (xy 29.858647 -363.993835) (xy 29.794427 -363.935291)
			(xy 29.735883 -363.871071) (xy 29.683514 -363.801724) (xy 29.637767 -363.72784) (xy 29.599033 -363.650051)
			(xy 29.567641 -363.569019) (xy 29.54386 -363.485437) (xy 29.527892 -363.400017) (xy 29.519874 -363.313488)
			(xy 26.531316 -363.313488) (xy 26.531316 -363.64672) (xy 26.531807 -363.669371) (xy 26.539831 -363.713956)
			(xy 26.555639 -363.75641) (xy 26.578728 -363.795386) (xy 26.608368 -363.829646) (xy 26.643615 -363.858103)
			(xy 26.683353 -363.879855) (xy 26.72632 -363.89421) (xy 26.771153 -363.900714) (xy 26.816427 -363.89916)
			(xy 26.860708 -363.889597) (xy 26.902589 -363.872329) (xy 26.921968 -363.860588) (xy 26.947797 -363.844677)
			(xy 27.002791 -363.819066) (xy 27.060687 -363.800945) (xy 27.120469 -363.790631) (xy 27.181089 -363.788306)
			(xy 27.241486 -363.79401) (xy 27.300599 -363.807644) (xy 27.357393 -363.828968) (xy 27.410872 -363.857609)
			(xy 27.460098 -363.893064) (xy 27.504209 -363.934711) (xy 27.54243 -363.981822) (xy 27.574092 -364.033569)
			(xy 27.598641 -364.089045) (xy 27.615644 -364.147279) (xy 27.624805 -364.207248) (xy 27.625963 -364.267903)
			(xy 27.619097 -364.328178) (xy 27.604328 -364.387018) (xy 27.581915 -364.443391) (xy 27.55225 -364.496309)
			(xy 27.515854 -364.544843) (xy 27.473365 -364.588144) (xy 27.425528 -364.625451) (xy 27.373181 -364.656112)
			(xy 27.317242 -364.679588) (xy 27.258692 -364.695467) (xy 27.198558 -364.703472) (xy 27.137892 -364.703462)
			(xy 27.07776 -364.695438) (xy 27.019215 -364.679539) (xy 26.963284 -364.656045) (xy 26.910948 -364.625367)
			(xy 26.863122 -364.588044) (xy 26.820648 -364.544729) (xy 26.784268 -364.496183) (xy 26.76906 -364.469934)
			(xy 26.752042 -364.439962) (xy 26.69286 -364.405164) (xy 26.658316 -364.405164) (xy 26.641665 -364.405705)
			(xy 26.609495 -364.41432) (xy 26.580651 -364.430966) (xy 26.557098 -364.45451) (xy 26.54044 -364.483347)
			(xy 26.531812 -364.515513) (xy 26.531316 -364.532164) (xy 26.531316 -364.792514) (xy 27.59229 -365.853488)
			(xy 29.519874 -365.853488) (xy 29.519874 -365.766588) (xy 29.527892 -365.680059) (xy 29.54386 -365.594639)
			(xy 29.567641 -365.511057) (xy 29.599033 -365.430025) (xy 29.637767 -365.352236) (xy 29.683514 -365.278352)
			(xy 29.735883 -365.209005) (xy 29.794427 -365.144785) (xy 29.858647 -365.086241) (xy 29.927994 -365.033872)
			(xy 30.001878 -364.988125) (xy 30.079667 -364.949391) (xy 30.160699 -364.917999) (xy 30.244281 -364.894218)
			(xy 30.329701 -364.87825) (xy 30.41623 -364.870232) (xy 30.50313 -364.870232) (xy 30.589659 -364.87825)
			(xy 30.675079 -364.894218) (xy 30.758661 -364.917999) (xy 30.839693 -364.949391) (xy 30.917482 -364.988125)
			(xy 30.991366 -365.033872) (xy 31.060713 -365.086241) (xy 31.124933 -365.144785) (xy 31.183477 -365.209005)
			(xy 31.235846 -365.278352) (xy 31.281593 -365.352236) (xy 31.320327 -365.430025) (xy 31.351719 -365.511057)
			(xy 31.3755 -365.594639) (xy 31.391468 -365.680059) (xy 31.399486 -365.766588) (xy 31.399988 -365.810038)
			(xy 31.399486 -365.853488) (xy 31.391468 -365.940017) (xy 31.3755 -366.025437) (xy 31.351719 -366.109019)
			(xy 31.320327 -366.190051) (xy 31.281593 -366.26784) (xy 31.235846 -366.341724) (xy 31.183477 -366.411071)
			(xy 31.124933 -366.475291) (xy 31.060713 -366.533835) (xy 30.991366 -366.586204) (xy 30.917482 -366.631951)
			(xy 30.839693 -366.670685) (xy 30.758661 -366.702077) (xy 30.675079 -366.725858) (xy 30.589659 -366.741826)
			(xy 30.50313 -366.749844) (xy 30.41623 -366.749844) (xy 30.329701 -366.741826) (xy 30.244281 -366.725858)
			(xy 30.160699 -366.702077) (xy 30.079667 -366.670685) (xy 30.001878 -366.631951) (xy 29.927994 -366.586204)
			(xy 29.858647 -366.533835) (xy 29.794427 -366.475291) (xy 29.735883 -366.411071) (xy 29.683514 -366.341724)
			(xy 29.637767 -366.26784) (xy 29.599033 -366.190051) (xy 29.567641 -366.109019) (xy 29.54386 -366.025437)
			(xy 29.527892 -365.940017) (xy 29.519874 -365.853488) (xy 27.59229 -365.853488) (xy 29.42971 -367.690908)
			(xy 29.445776 -367.706351) (xy 29.482273 -367.731916) (xy 29.522671 -367.750721) (xy 29.565731 -367.762186)
			(xy 29.61013 -367.765962) (xy 29.654508 -367.761931) (xy 29.697501 -367.750219) (xy 29.73779 -367.731183)
			(xy 29.774139 -367.705408) (xy 29.790136 -367.689892) (xy 29.82067 -367.659607) (xy 29.886393 -367.60413)
			(xy 29.956908 -367.554888) (xy 30.031625 -367.512292) (xy 30.109921 -367.476698) (xy 30.19114 -367.448403)
			(xy 30.274603 -367.427643) (xy 30.359614 -367.414593) (xy 30.445461 -367.409362) (xy 30.531428 -367.411993)
			(xy 30.616795 -367.422463) (xy 30.700848 -367.440687) (xy 30.782887 -367.466511) (xy 30.862223 -367.499719)
			(xy 30.938196 -367.540034) (xy 31.010169 -367.587119) (xy 31.077541 -367.640581) (xy 31.139749 -367.699972)
			(xy 31.196273 -367.764796) (xy 31.24664 -367.834512) (xy 31.29043 -367.908536) (xy 31.327276 -367.98625)
			(xy 31.356871 -368.067005) (xy 31.378967 -368.150125) (xy 31.39338 -368.234915) (xy 31.399988 -368.320667)
			(xy 31.398738 -368.406665) (xy 31.389638 -368.492189) (xy 31.372766 -368.576524) (xy 31.348262 -368.658966)
			(xy 31.316331 -368.738826) (xy 31.277241 -368.815435) (xy 31.231317 -368.888155) (xy 31.178943 -368.956376)
			(xy 31.120558 -369.019529) (xy 31.056649 -369.077086) (xy 30.987751 -369.128566) (xy 30.914439 -369.173538)
			(xy 30.837326 -369.211627) (xy 30.757057 -369.242514) (xy 30.674303 -369.265941) (xy 30.589755 -369.281713)
			(xy 30.504119 -369.289697) (xy 30.418113 -369.289826) (xy 30.332454 -369.2821) (xy 30.247859 -369.266584)
			(xy 30.165034 -369.243406) (xy 30.084672 -369.212761) (xy 30.007445 -369.174905) (xy 29.970476 -369.152932)
			(xy 29.951072 -369.141678) (xy 29.909262 -369.125444) (xy 29.86525 -369.1168) (xy 29.820405 -369.116017)
			(xy 29.776119 -369.123118) (xy 29.733767 -369.137882) (xy 29.694664 -369.159852) (xy 29.660024 -369.188344)
			(xy 29.630924 -369.222475) (xy 29.608267 -369.261183) (xy 29.592757 -369.303268) (xy 29.584875 -369.347422)
			(xy 29.584396 -369.369848) (xy 29.584396 -369.54714) (xy 30.011624 -369.974368) (xy 30.024712 -369.986643)
			(xy 30.056094 -370.004006) (xy 30.091071 -370.01194) (xy 30.126873 -370.009817) (xy 30.143958 -370.00434)
			(xy 30.185429 -369.99009) (xy 30.270415 -369.968459) (xy 30.357046 -369.954836) (xy 30.444569 -369.94934)
			(xy 30.532224 -369.952018) (xy 30.619249 -369.962848) (xy 30.704887 -369.981734) (xy 30.788393 -370.008513)
			(xy 30.869044 -370.042953) (xy 30.946136 -370.084753) (xy 31.019001 -370.133551) (xy 31.087005 -370.188922)
			(xy 31.149558 -370.250386) (xy 31.206114 -370.317407) (xy 31.256184 -370.389404) (xy 31.299331 -370.465751)
			(xy 31.335181 -370.545785) (xy 31.363422 -370.628809) (xy 31.37408 -370.671344) (xy 31.382462 -370.706142)
		)
		(stroke
			(width 0)
			(type solid)
		)
		(fill yes)
		(layer "B.Cu")
		(net "GND")
	)
	(gr_poly
		(pts
			(xy 21.061426 -378.842778) (xy 21.078084 -378.857849) (xy 21.115653 -378.882468) (xy 21.156964 -378.900104)
			(xy 21.20073 -378.910207) (xy 21.245591 -378.912463) (xy 21.29015 -378.906802) (xy 21.333022 -378.893399)
			(xy 21.372871 -378.872672) (xy 21.408459 -378.845267) (xy 21.438678 -378.812034) (xy 21.462588 -378.774009)
			(xy 21.479444 -378.732375) (xy 21.488723 -378.688426) (xy 21.489924 -378.665994) (xy 21.489924 -360.486706)
			(xy 21.258784 -360.255566) (xy 19.670268 -358.667304) (xy 19.670268 -322.326) (xy 24.011128 -317.985394)
			(xy 24.022474 -317.973244) (xy 24.039055 -317.944448) (xy 24.047641 -317.912347) (xy 24.048212 -317.895732)
			(xy 24.048212 -290.856416) (xy 24.047674 -290.839798) (xy 24.039085 -290.80769) (xy 24.022488 -290.778895)
			(xy 24.011128 -290.766754) (xy 18.773648 -285.529528) (xy 18.773648 -281.149806) (xy 14.964156 -277.34006)
			(xy 14.964156 -258.832604) (xy 14.964631 -258.801964) (xy 14.972384 -258.741176) (xy 14.987767 -258.681857)
			(xy 15.010531 -258.624962) (xy 15.040312 -258.571404) (xy 15.07663 -258.522045) (xy 15.118901 -258.477678)
			(xy 15.166447 -258.439016) (xy 15.218502 -258.406681) (xy 15.27423 -258.381192) (xy 15.332736 -258.362959)
			(xy 15.393078 -258.352276) (xy 15.454287 -258.349314) (xy 15.515379 -258.35412) (xy 15.575372 -258.366618)
			(xy 15.60449 -258.376166) (xy 15.636 -258.387605) (xy 15.695778 -258.417941) (xy 15.723616 -258.436618)
			(xy 15.738602 -258.447032) (xy 15.813786 -258.472178) (xy 15.88262 -258.451604) (xy 15.896844 -258.442968)
			(xy 15.914311 -258.43256) (xy 15.950682 -258.414376) (xy 15.969488 -258.406646) (xy 15.998848 -258.39546)
			(xy 16.059725 -258.379917) (xy 16.122103 -258.372402) (xy 16.18493 -258.373043) (xy 16.247142 -258.381827)
			(xy 16.30769 -258.398608) (xy 16.365548 -258.423102) (xy 16.419741 -258.454893) (xy 16.469352 -258.493446)
			(xy 16.513543 -258.538109) (xy 16.551566 -258.588127) (xy 16.58278 -258.642654) (xy 16.606657 -258.70077)
			(xy 16.622793 -258.761493) (xy 16.630916 -258.823795) (xy 16.631412 -258.85521) (xy 16.631412 -276.648926)
			(xy 16.777716 -276.79523) (xy 16.789835 -276.806669) (xy 16.818674 -276.823351) (xy 16.850847 -276.831999)
			(xy 16.884163 -276.832024) (xy 16.91635 -276.823424) (xy 16.945213 -276.806786) (xy 16.968786 -276.783243)
			(xy 16.985461 -276.754401) (xy 16.994102 -276.722226) (xy 16.994632 -276.705568) (xy 16.994632 -254.324612)
			(xy 16.419068 -253.749048) (xy 15.559532 -252.889258) (xy 15.559532 -225.04146) (xy 15.559014 -225.026933)
			(xy 15.550839 -224.999053) (xy 15.53516 -224.974592) (xy 15.513239 -224.955523) (xy 15.486844 -224.943381)
			(xy 15.4581 -224.939145) (xy 15.429324 -224.943157) (xy 15.402834 -224.955092) (xy 15.380765 -224.973989)
			(xy 15.372334 -224.985834) (xy 15.340742 -225.033416) (xy 15.271825 -225.12451) (xy 15.196684 -225.210541)
			(xy 15.11569 -225.291086) (xy 15.029241 -225.365747) (xy 14.937765 -225.434155) (xy 14.841713 -225.495974)
			(xy 14.741559 -225.550899) (xy 14.637797 -225.598657) (xy 14.530938 -225.639015) (xy 14.421509 -225.671772)
			(xy 14.310052 -225.696767) (xy 14.197114 -225.713877) (xy 14.083255 -225.723017) (xy 13.969034 -225.724142)
			(xy 13.855017 -225.717248) (xy 13.741764 -225.702367) (xy 13.629836 -225.679573) (xy 13.519783 -225.648978)
			(xy 13.41215 -225.610735) (xy 13.307466 -225.56503) (xy 13.206249 -225.51209) (xy 13.108998 -225.452176)
			(xy 13.016191 -225.385583) (xy 12.928289 -225.31264) (xy 12.845723 -225.233707) (xy 12.768901 -225.149173)
			(xy 12.698203 -225.059455) (xy 12.633976 -224.964996) (xy 12.576539 -224.866262) (xy 12.526173 -224.763739)
			(xy 12.483128 -224.657934) (xy 12.447617 -224.549369) (xy 12.419813 -224.438578) (xy 12.399854 -224.326109)
			(xy 12.38784 -224.212517) (xy 12.383828 -224.098362) (xy 12.38784 -223.984206) (xy 12.399854 -223.870614)
			(xy 12.419812 -223.758145) (xy 12.447616 -223.647355) (xy 12.483127 -223.538789) (xy 12.526172 -223.432984)
			(xy 12.576537 -223.330461) (xy 12.633975 -223.231727) (xy 12.698201 -223.137267) (xy 12.768899 -223.047549)
			(xy 12.845721 -222.963015) (xy 12.928286 -222.884082) (xy 13.016189 -222.811139) (xy 13.108995 -222.744546)
			(xy 13.206246 -222.684632) (xy 13.307463 -222.631692) (xy 13.412147 -222.585987) (xy 13.51978 -222.547743)
			(xy 13.629833 -222.517148) (xy 13.741761 -222.494354) (xy 13.855013 -222.479473) (xy 13.969031 -222.472578)
			(xy 14.083251 -222.473703) (xy 14.197111 -222.482843) (xy 14.310048 -222.499953) (xy 14.421506 -222.524948)
			(xy 14.530934 -222.557704) (xy 14.637793 -222.598061) (xy 14.741556 -222.64582) (xy 14.841711 -222.700744)
			(xy 14.937763 -222.762563) (xy 15.029239 -222.830971) (xy 15.115687 -222.905632) (xy 15.196682 -222.986176)
			(xy 15.271823 -223.072208) (xy 15.34074 -223.163301) (xy 15.372334 -223.210882) (xy 15.380698 -223.222787)
			(xy 15.402778 -223.241713) (xy 15.429288 -223.253669) (xy 15.45809 -223.257689) (xy 15.48686 -223.25345)
			(xy 15.513278 -223.241293) (xy 15.535213 -223.222199) (xy 15.550895 -223.197708) (xy 15.559059 -223.169797)
			(xy 15.559532 -223.155256) (xy 15.559532 -222.00743) (xy 17.53997 -220.026992) (xy 17.54505 -219.982796)
			(xy 17.54911 -219.951872) (xy 17.564532 -219.891439) (xy 17.588018 -219.833661) (xy 17.619131 -219.779606)
			(xy 17.657297 -219.730277) (xy 17.701808 -219.686588) (xy 17.751839 -219.649347) (xy 17.806463 -219.619245)
			(xy 17.864669 -219.59684) (xy 17.925379 -219.582546) (xy 17.987467 -219.576628) (xy 18.049783 -219.579197)
			(xy 18.111174 -219.590203) (xy 18.170502 -219.609444) (xy 18.226667 -219.636563) (xy 18.252948 -219.653358)
			(xy 18.265894 -219.661401) (xy 18.29456 -219.671723) (xy 18.324857 -219.674947) (xy 18.355053 -219.670889)
			(xy 18.383424 -219.659781) (xy 18.408348 -219.642256) (xy 18.4284 -219.619318) (xy 18.442436 -219.592275)
			(xy 18.449653 -219.562674) (xy 18.450052 -219.54744) (xy 18.450052 -219.428568) (xy 18.26641 -219.244926)
			(xy 17.99209 -218.970352) (xy 17.947894 -218.965272) (xy 17.917945 -218.961372) (xy 17.85936 -218.946701)
			(xy 17.803213 -218.92445) (xy 17.750481 -218.895007) (xy 17.70208 -218.858884) (xy 17.658852 -218.816707)
			(xy 17.621547 -218.769211) (xy 17.590814 -218.71722) (xy 17.567188 -218.661638) (xy 17.551078 -218.603431)
			(xy 17.542765 -218.543611) (xy 17.542393 -218.483217) (xy 17.549969 -218.4233) (xy 17.565361 -218.364899)
			(xy 17.588301 -218.30903) (xy 17.618391 -218.256665) (xy 17.655108 -218.208713) (xy 17.697814 -218.166007)
			(xy 17.745766 -218.12929) (xy 17.798132 -218.0992) (xy 17.854001 -218.07626) (xy 17.912401 -218.060869)
			(xy 17.972319 -218.053293) (xy 18.032713 -218.053665) (xy 18.092533 -218.061978) (xy 18.15074 -218.078088)
			(xy 18.206322 -218.101715) (xy 18.258312 -218.132448) (xy 18.305809 -218.169753) (xy 18.347985 -218.212981)
			(xy 18.384108 -218.261382) (xy 18.413551 -218.314114) (xy 18.435801 -218.370261) (xy 18.450472 -218.428847)
			(xy 18.45437 -218.458796) (xy 18.45945 -218.502992) (xy 18.850102 -218.89339) (xy 19.111468 -219.154756)
			(xy 19.111468 -235.59389) (xy 21.23948 -237.721902) (xy 21.256371 -237.737133) (xy 21.294485 -237.761941)
			(xy 21.336406 -237.779569) (xy 21.380796 -237.789454) (xy 21.426236 -237.791282) (xy 21.471275 -237.784992)
			(xy 21.514476 -237.770787) (xy 21.55446 -237.749119) (xy 21.589948 -237.720682) (xy 21.619808 -237.686382)
			(xy 21.643087 -237.647314) (xy 21.65904 -237.604728) (xy 21.66716 -237.559982) (xy 21.667724 -237.537244)
			(xy 21.667724 -237.026704) (xy 22.265894 -236.428534) (xy 23.159466 -235.535216) (xy 23.164546 -235.49102)
			(xy 23.168387 -235.461495) (xy 23.18274 -235.40371) (xy 23.204473 -235.348278) (xy 23.233219 -235.296137)
			(xy 23.26849 -235.248168) (xy 23.288752 -235.226352) (xy 23.288752 -234.10926) (xy 21.522944 -232.343452)
			(xy 21.522944 -221.776036) (xy 22.209252 -221.089728) (xy 22.209252 -216.353644) (xy 22.208998 -211.617306)
			(xy 22.208501 -211.594555) (xy 22.200414 -211.549777) (xy 22.184481 -211.507157) (xy 22.161209 -211.468056)
			(xy 22.131345 -211.433726) (xy 22.095843 -211.405265) (xy 22.055839 -211.383584) (xy 22.012612 -211.369375)
			(xy 21.967546 -211.363094) (xy 21.922082 -211.364941) (xy 21.877674 -211.374857) (xy 21.835742 -211.392525)
			(xy 21.797629 -211.417381) (xy 21.780754 -211.432648) (xy 20.094702 -213.1187) (xy 12.203176 -213.1187)
			(xy 9.245854 -210.161124) (xy 9.233708 -210.149768) (xy 9.204914 -210.133166) (xy 9.17281 -210.124562)
			(xy 9.156192 -210.12404) (xy 9.079992 -210.12404) (xy 9.063833 -210.125228) (xy 9.032873 -210.134748)
			(xy 9.005314 -210.151766) (xy 8.982935 -210.175182) (xy 8.967183 -210.203484) (xy 8.959076 -210.234844)
			(xy 8.95858 -210.25104) (xy 8.95858 -210.289394) (xy 8.979408 -210.321144) (xy 8.998356 -210.350744)
			(xy 9.030331 -210.413336) (xy 9.055208 -210.479071) (xy 9.072684 -210.547149) (xy 9.082546 -210.616739)
			(xy 9.084056 -210.651852) (xy 9.08457 -210.679107) (xy 9.081517 -210.733537) (xy 9.07796 -210.760564)
			(xy 9.073642 -210.790282) (xy 9.092692 -210.846924) (xy 14.901672 -216.655904) (xy 17.683226 -216.655904)
			(xy 17.705639 -216.635156) (xy 17.754989 -216.599171) (xy 17.808686 -216.570069) (xy 17.865776 -216.548366)
			(xy 17.925246 -216.534448) (xy 17.986038 -216.528563) (xy 18.047073 -216.530814) (xy 18.107266 -216.541163)
			(xy 18.165548 -216.559424) (xy 18.220884 -216.585274) (xy 18.272291 -216.618254) (xy 18.318855 -216.657777)
			(xy 18.35975 -216.703142) (xy 18.394248 -216.753542) (xy 18.421738 -216.808082) (xy 18.44173 -216.865794)
			(xy 18.453869 -216.925651) (xy 18.457941 -216.986592) (xy 18.453872 -217.047532) (xy 18.441734 -217.10739)
			(xy 18.421744 -217.165103) (xy 18.394257 -217.219644) (xy 18.35976 -217.270045) (xy 18.318867 -217.315411)
			(xy 18.272304 -217.354936) (xy 18.220899 -217.387918) (xy 18.165564 -217.41377) (xy 18.107282 -217.432033)
			(xy 18.047089 -217.442384) (xy 17.986054 -217.444638) (xy 17.925262 -217.438754) (xy 17.865792 -217.424839)
			(xy 17.808701 -217.403138) (xy 17.755003 -217.374038) (xy 17.705652 -217.338055) (xy 17.683226 -217.31732)
			(xy 14.62786 -217.31732) (xy 8.625078 -211.314538) (xy 8.568436 -211.295488) (xy 8.538718 -211.299806)
			(xy 8.501606 -211.304566) (xy 8.426804 -211.306382) (xy 8.352308 -211.299395) (xy 8.279148 -211.283702)
			(xy 8.24357 -211.27212) (xy 8.212988 -211.261241) (xy 8.154019 -211.234103) (xy 8.098119 -211.201102)
			(xy 8.045871 -211.162579) (xy 8.021574 -211.141056) (xy 8.004401 -211.12672) (xy 7.966052 -211.103694)
			(xy 7.924264 -211.087737) (xy 7.880328 -211.07934) (xy 7.8356 -211.078765) (xy 7.791463 -211.086027)
			(xy 7.749278 -211.100903) (xy 7.710348 -211.122934) (xy 7.675876 -211.151439) (xy 7.646926 -211.185538)
			(xy 7.624391 -211.224179) (xy 7.608969 -211.266167) (xy 7.601134 -211.310207) (xy 7.600696 -211.332572)
			(xy 7.600696 -212.00872) (xy 7.601169 -212.031083) (xy 7.609001 -212.075118) (xy 7.624421 -212.117101)
			(xy 7.646952 -212.155737) (xy 7.675899 -212.189833) (xy 7.710366 -212.218335) (xy 7.749291 -212.240364)
			(xy 7.791471 -212.255239) (xy 7.835604 -212.2625) (xy 7.880326 -212.261924) (xy 7.924257 -212.253529)
			(xy 7.966039 -212.237573) (xy 8.004384 -212.214549) (xy 8.021574 -212.200236) (xy 8.048567 -212.176405)
			(xy 8.107008 -212.134338) (xy 8.16983 -212.099146) (xy 8.236226 -212.071279) (xy 8.305347 -212.051095)
			(xy 8.376306 -212.038853) (xy 8.448194 -212.034709) (xy 8.520089 -212.038716) (xy 8.591071 -212.050823)
			(xy 8.66023 -212.070875) (xy 8.72668 -212.098615) (xy 8.789568 -212.133688) (xy 8.84809 -212.175643)
			(xy 8.901495 -212.223944) (xy 8.949098 -212.277971) (xy 8.990291 -212.337033) (xy 9.024544 -212.400371)
			(xy 9.051419 -212.467175) (xy 9.070572 -212.536589) (xy 9.081756 -212.607722) (xy 9.08483 -212.679663)
			(xy 9.079753 -212.751492) (xy 9.073642 -212.786976) (xy 9.066491 -212.822563) (xy 9.045163 -212.891948)
			(xy 9.016068 -212.958452) (xy 8.979585 -213.021207) (xy 8.93619 -213.079397) (xy 8.886447 -213.132263)
			(xy 8.831005 -213.179118) (xy 8.770585 -213.219351) (xy 8.705975 -213.252438) (xy 8.638016 -213.277947)
			(xy 8.567592 -213.295548) (xy 8.495622 -213.30501) (xy 8.423043 -213.306211) (xy 8.350799 -213.299134)
			(xy 8.279832 -213.283872) (xy 8.211067 -213.260624) (xy 8.145397 -213.229692) (xy 8.08368 -213.19148)
			(xy 8.026719 -213.146484) (xy 7.975255 -213.095292) (xy 7.929959 -213.038569) (xy 7.89142 -212.977054)
			(xy 7.860142 -212.91155) (xy 7.847838 -212.8774) (xy 7.83463 -212.838792) (xy 7.76859 -212.791802)
			(xy 7.727696 -212.791802) (xy 7.711048 -212.792346) (xy 7.678887 -212.800964) (xy 7.650052 -212.817613)
			(xy 7.626509 -212.841157) (xy 7.609862 -212.869993) (xy 7.601245 -212.902154) (xy 7.600696 -212.918802)
			(xy 7.600696 -212.986366) (xy 7.40537 -213.181438) (xy 7.092696 -213.494366) (xy 7.073646 -213.551008)
			(xy 7.077964 -213.580726) (xy 7.082482 -213.61573) (xy 7.084665 -213.68628) (xy 7.079017 -213.756637)
			(xy 7.065608 -213.825934) (xy 7.044603 -213.89332) (xy 7.016262 -213.957963) (xy 6.980932 -214.019068)
			(xy 6.939049 -214.075882) (xy 6.89113 -214.127706) (xy 6.837763 -214.173901) (xy 6.779607 -214.213898)
			(xy 6.717376 -214.247205) (xy 6.651839 -214.273413) (xy 6.583801 -214.292197) (xy 6.514101 -214.303327)
			(xy 6.443597 -214.306666) (xy 6.373157 -214.302172) (xy 6.303649 -214.289901) (xy 6.235928 -214.270004)
			(xy 6.170829 -214.242726) (xy 6.109153 -214.208403) (xy 6.05166 -214.167457) (xy 5.999058 -214.120394)
			(xy 5.951994 -214.067792) (xy 5.911048 -214.010299) (xy 5.876725 -213.948623) (xy 5.849447 -213.883524)
			(xy 5.82955 -213.815803) (xy 5.817279 -213.746295) (xy 5.812784 -213.675855) (xy 5.816123 -213.605351)
			(xy 5.827253 -213.535651) (xy 5.846037 -213.467613) (xy 5.872244 -213.402076) (xy 5.905551 -213.339845)
			(xy 5.945548 -213.281689) (xy 5.991743 -213.228322) (xy 6.043566 -213.180402) (xy 6.10038 -213.138519)
			(xy 6.161485 -213.103189) (xy 6.226128 -213.074848) (xy 6.293513 -213.053843) (xy 6.362811 -213.040434)
			(xy 6.433168 -213.034785) (xy 6.503717 -213.036967) (xy 6.538722 -213.041484) (xy 6.553359 -213.043164)
			(xy 6.582698 -213.040549) (xy 6.61065 -213.031261) (xy 6.635719 -213.015798) (xy 6.646418 -213.00567)
			(xy 6.821932 -212.830156) (xy 6.93928 -212.712554) (xy 6.93928 -212.52815) (xy 6.938753 -212.504779)
			(xy 6.930211 -212.458824) (xy 6.913406 -212.415207) (xy 6.888905 -212.3754) (xy 6.857536 -212.340748)
			(xy 6.820357 -212.312419) (xy 6.778622 -212.29137) (xy 6.733741 -212.278311) (xy 6.687229 -212.273683)
			(xy 6.640655 -212.277642) (xy 6.61797 -212.283294) (xy 6.583668 -212.292259) (xy 6.513647 -212.303406)
			(xy 6.442821 -212.306691) (xy 6.37207 -212.302073) (xy 6.302271 -212.289609) (xy 6.234294 -212.269455)
			(xy 6.168982 -212.24186) (xy 6.107147 -212.207167) (xy 6.049558 -212.165808) (xy 5.996929 -212.118297)
			(xy 5.949915 -212.065223) (xy 5.9091 -212.007247) (xy 5.874991 -211.945088) (xy 5.848012 -211.879519)
			(xy 5.828499 -211.811355) (xy 5.816692 -211.741443) (xy 5.812741 -211.670651) (xy 5.816692 -211.599859)
			(xy 5.828498 -211.529947) (xy 5.848012 -211.461783) (xy 5.87499 -211.396214) (xy 5.909099 -211.334055)
			(xy 5.949914 -211.276078) (xy 5.996928 -211.223005) (xy 6.049556 -211.175493) (xy 6.107146 -211.134134)
			(xy 6.16898 -211.099441) (xy 6.234292 -211.071846) (xy 6.302269 -211.051691) (xy 6.372067 -211.039227)
			(xy 6.442819 -211.034609) (xy 6.513645 -211.037894) (xy 6.583666 -211.049041) (xy 6.61797 -211.057998)
			(xy 6.640645 -211.063681) (xy 6.687219 -211.067622) (xy 6.733728 -211.062979) (xy 6.778604 -211.049911)
			(xy 6.820334 -211.028857) (xy 6.85751 -211.000527) (xy 6.888879 -210.965877) (xy 6.913383 -210.926075)
			(xy 6.930195 -210.882463) (xy 6.93875 -210.836512) (xy 6.93928 -210.813142) (xy 6.93928 -210.380072)
			(xy 7.307072 -210.01228) (xy 7.856474 -209.463132) (xy 8.076438 -209.463132) (xy 8.093085 -209.462584)
			(xy 8.125242 -209.453961) (xy 8.154073 -209.437311) (xy 8.177614 -209.413768) (xy 8.194263 -209.384936)
			(xy 8.202885 -209.352779) (xy 8.203438 -209.336132) (xy 8.203438 -209.301334) (xy 8.16864 -209.241898)
			(xy 8.138414 -209.225134) (xy 8.107792 -209.207433) (xy 8.050294 -209.166235) (xy 7.997726 -209.11891)
			(xy 7.950736 -209.066041) (xy 7.909905 -209.008282) (xy 7.875739 -208.946347) (xy 7.84866 -208.881003)
			(xy 7.829002 -208.813056) (xy 7.817009 -208.743347) (xy 7.812828 -208.672737) (xy 7.816512 -208.6021)
			(xy 7.828015 -208.532308) (xy 7.847194 -208.464225) (xy 7.873813 -208.398692) (xy 7.890256 -208.367376)
			(xy 7.900003 -208.346445) (xy 7.912589 -208.302027) (xy 7.916949 -208.256066) (xy 7.912938 -208.210073)
			(xy 7.90069 -208.165561) (xy 7.880606 -208.123991) (xy 7.853346 -208.086731) (xy 7.819808 -208.055004)
			(xy 7.781092 -208.029855) (xy 7.738472 -208.012109) (xy 7.693348 -208.002349) (xy 7.670292 -208.001108)
			(xy 7.058914 -208.001108) (xy 7.044175 -208.001529) (xy 7.015487 -208.008299) (xy 6.989121 -208.02148)
			(xy 6.966489 -208.040366) (xy 6.957314 -208.051908) (xy 6.935758 -208.079859) (xy 6.887417 -208.131295)
			(xy 6.833675 -208.177059) (xy 6.775192 -208.216585) (xy 6.71269 -208.249388) (xy 6.646938 -208.275064)
			(xy 6.578745 -208.293295) (xy 6.508953 -208.303859) (xy 6.43842 -208.306624) (xy 6.368014 -208.301556)
			(xy 6.298604 -208.288719) (xy 6.231044 -208.268269) (xy 6.166166 -208.240459) (xy 6.104768 -208.205632)
			(xy 6.047608 -208.164216) (xy 5.995389 -208.116721) (xy 5.948754 -208.063733) (xy 5.908278 -208.005904)
			(xy 5.874458 -207.943946) (xy 5.847712 -207.878622) (xy 5.82837 -207.810736) (xy 5.816668 -207.741125)
			(xy 5.812751 -207.670647) (xy 5.816669 -207.600168) (xy 5.828371 -207.530558) (xy 5.847715 -207.462672)
			(xy 5.874461 -207.397349) (xy 5.908281 -207.335391) (xy 5.948758 -207.277562) (xy 5.995393 -207.224574)
			(xy 6.047613 -207.17708) (xy 6.104774 -207.135665) (xy 6.166171 -207.100838) (xy 6.23105 -207.073029)
			(xy 6.298611 -207.05258) (xy 6.368021 -207.039743) (xy 6.438426 -207.034676) (xy 6.508959 -207.037442)
			(xy 6.578752 -207.048006) (xy 6.646944 -207.066238) (xy 6.712696 -207.091914) (xy 6.775198 -207.124718)
			(xy 6.83368 -207.164245) (xy 6.887422 -207.210009) (xy 6.935763 -207.261446) (xy 6.957314 -207.2894)
			(xy 6.966496 -207.300935) (xy 6.989126 -207.319819) (xy 7.01549 -207.332998) (xy 7.044177 -207.339767)
			(xy 7.058914 -207.3402) (xy 7.670292 -207.3402) (xy 7.693358 -207.338986) (xy 7.738505 -207.329252)
			(xy 7.781151 -207.311521) (xy 7.819891 -207.286377) (xy 7.85345 -207.254647) (xy 7.880724 -207.217375)
			(xy 7.900815 -207.17579) (xy 7.913062 -207.131258) (xy 7.917061 -207.085247) (xy 7.912682 -207.03927)
			(xy 7.900067 -206.994842) (xy 7.890256 -206.973932) (xy 7.873903 -206.942828) (xy 7.847387 -206.877746)
			(xy 7.828213 -206.810137) (xy 7.816614 -206.740825) (xy 7.812733 -206.670656) (xy 7.816615 -206.600488)
			(xy 7.828215 -206.531176) (xy 7.84739 -206.463567) (xy 7.873906 -206.398486) (xy 7.890256 -206.36738)
			(xy 7.900004 -206.346449) (xy 7.91259 -206.30203) (xy 7.91695 -206.256069) (xy 7.91294 -206.210076)
			(xy 7.900692 -206.165562) (xy 7.880608 -206.123992) (xy 7.853349 -206.086731) (xy 7.81981 -206.055004)
			(xy 7.781094 -206.029854) (xy 7.738473 -206.012107) (xy 7.693348 -206.002348) (xy 7.670292 -206.001112)
			(xy 7.058914 -206.001112) (xy 7.044176 -206.001534) (xy 7.015487 -206.008304) (xy 6.989122 -206.021485)
			(xy 6.96649 -206.040371) (xy 6.957314 -206.051912) (xy 6.935759 -206.079863) (xy 6.887418 -206.131299)
			(xy 6.833676 -206.177063) (xy 6.775194 -206.21659) (xy 6.712693 -206.249393) (xy 6.646941 -206.275069)
			(xy 6.578749 -206.293301) (xy 6.508957 -206.303865) (xy 6.438425 -206.30663) (xy 6.36802 -206.301563)
			(xy 6.29861 -206.288726) (xy 6.23105 -206.268277) (xy 6.166172 -206.240468) (xy 6.104774 -206.205642)
			(xy 6.047614 -206.164226) (xy 5.995395 -206.116732) (xy 5.94876 -206.063745) (xy 5.908283 -206.005916)
			(xy 5.874464 -205.943958) (xy 5.847717 -205.878635) (xy 5.828374 -205.81075) (xy 5.816672 -205.74114)
			(xy 5.812755 -205.670662) (xy 5.816672 -205.600183) (xy 5.828373 -205.530573) (xy 5.847716 -205.462688)
			(xy 5.874462 -205.397365) (xy 5.908282 -205.335407) (xy 5.948758 -205.277578) (xy 5.995393 -205.22459)
			(xy 6.047612 -205.177096) (xy 6.104772 -205.13568) (xy 6.166169 -205.100853) (xy 6.231047 -205.073044)
			(xy 6.298607 -205.052595) (xy 6.368017 -205.039757) (xy 6.438421 -205.03469) (xy 6.508954 -205.037455)
			(xy 6.578746 -205.048019) (xy 6.646938 -205.06625) (xy 6.71269 -205.091926) (xy 6.775192 -205.124729)
			(xy 6.833674 -205.164255) (xy 6.887416 -205.210019) (xy 6.935757 -205.261455) (xy 6.957314 -205.289404)
			(xy 6.966495 -205.300939) (xy 6.989126 -205.319823) (xy 7.01549 -205.333001) (xy 7.044177 -205.33977)
			(xy 7.058914 -205.340204) (xy 7.670292 -205.340204) (xy 7.693358 -205.33899) (xy 7.738506 -205.329256)
			(xy 7.781152 -205.311525) (xy 7.819892 -205.286381) (xy 7.853452 -205.25465) (xy 7.880727 -205.217379)
			(xy 7.900818 -205.175793) (xy 7.913066 -205.131261) (xy 7.917065 -205.08525) (xy 7.912686 -205.039273)
			(xy 7.900072 -204.994843) (xy 7.890256 -204.973936) (xy 7.873903 -204.942832) (xy 7.847387 -204.87775)
			(xy 7.828212 -204.810141) (xy 7.816613 -204.740829) (xy 7.812731 -204.67066) (xy 7.816613 -204.600491)
			(xy 7.828212 -204.531179) (xy 7.847387 -204.46357) (xy 7.873903 -204.398488) (xy 7.890256 -204.367384)
			(xy 7.900004 -204.346453) (xy 7.912592 -204.302034) (xy 7.916952 -204.256072) (xy 7.912942 -204.210078)
			(xy 7.900694 -204.165564) (xy 7.880611 -204.123992) (xy 7.853351 -204.086731) (xy 7.819812 -204.055003)
			(xy 7.781095 -204.029853) (xy 7.738474 -204.012106) (xy 7.693349 -204.002346) (xy 7.670292 -204.001116)
			(xy 7.058914 -204.001116) (xy 7.044176 -204.001538) (xy 7.015487 -204.008308) (xy 6.989122 -204.021489)
			(xy 6.966491 -204.040376) (xy 6.957314 -204.051916) (xy 6.935759 -204.079867) (xy 6.887418 -204.131303)
			(xy 6.833675 -204.177067) (xy 6.775193 -204.216593) (xy 6.712691 -204.249396) (xy 6.646939 -204.275072)
			(xy 6.578747 -204.293304) (xy 6.508954 -204.303867) (xy 6.438421 -204.306632) (xy 6.368016 -204.301565)
			(xy 6.298606 -204.288728) (xy 6.231046 -204.268278) (xy 6.166168 -204.240469) (xy 6.10477 -204.205642)
			(xy 6.04761 -204.164226) (xy 5.995391 -204.116732) (xy 5.948756 -204.063744) (xy 5.908279 -204.005915)
			(xy 5.87446 -203.943957) (xy 5.847714 -203.878633) (xy 5.828371 -203.810747) (xy 5.816669 -203.741137)
			(xy 5.812753 -203.670658) (xy 5.81667 -203.60018) (xy 5.828372 -203.530569) (xy 5.847715 -203.462684)
			(xy 5.874461 -203.397361) (xy 5.908281 -203.335403) (xy 5.948758 -203.277574) (xy 5.995393 -203.224586)
			(xy 6.047613 -203.177092) (xy 6.104773 -203.135676) (xy 6.166171 -203.10085) (xy 6.231049 -203.073041)
			(xy 6.298609 -203.052592) (xy 6.368019 -203.039754) (xy 6.438425 -203.034687) (xy 6.508958 -203.037453)
			(xy 6.57875 -203.048017) (xy 6.646942 -203.066249) (xy 6.712694 -203.091925) (xy 6.775196 -203.124728)
			(xy 6.833678 -203.164255) (xy 6.88742 -203.210019) (xy 6.935761 -203.261456) (xy 6.957314 -203.289408)
			(xy 6.966496 -203.300943) (xy 6.989127 -203.319826) (xy 7.015491 -203.333004) (xy 7.044177 -203.339773)
			(xy 7.058914 -203.340208) (xy 7.670546 -203.340208) (xy 7.693789 -203.338941) (xy 7.73926 -203.329009)
			(xy 7.782164 -203.310967) (xy 7.821068 -203.285418) (xy 7.854673 -203.253216) (xy 7.881857 -203.215436)
			(xy 7.901712 -203.17334) (xy 7.913574 -203.128334) (xy 7.917047 -203.081921) (xy 7.912016 -203.03565)
			(xy 7.898648 -202.991068) (xy 7.888478 -202.97013) (xy 7.872022 -202.938312) (xy 7.84556 -202.871741)
			(xy 7.826747 -202.802619) (xy 7.815821 -202.73182) (xy 7.81292 -202.660242) (xy 7.818082 -202.588792)
			(xy 7.83124 -202.518374) (xy 7.841234 -202.483974) (xy 7.851822 -202.451034) (xy 7.879188 -202.387481)
			(xy 7.913295 -202.327276) (xy 7.953741 -202.271133) (xy 8.000045 -202.219716) (xy 8.051661 -202.173632)
			(xy 8.107977 -202.133428) (xy 8.168327 -202.099579) (xy 8.231997 -202.072486) (xy 8.298233 -202.05247)
			(xy 8.366251 -202.039767) (xy 8.435247 -202.034528) (xy 8.504404 -202.036814) (xy 8.538718 -202.041252)
			(xy 8.568436 -202.04557) (xy 8.625078 -202.02652) (xy 17.12468 -193.526918) (xy 17.12468 -141.975078)
			(xy 18.94332 -140.156438) (xy 18.94332 -133.99008) (xy 16.230346 -131.277106) (xy 15.962376 -131.277106)
			(xy 15.773654 -131.465828) (xy 15.773654 -133.191504) (xy 14.01953 -134.945628) (xy 14.01953 -135.9535)
			(xy 14.020033 -135.977138) (xy 14.028735 -136.023606) (xy 14.045877 -136.067664) (xy 14.070867 -136.107794)
			(xy 14.102845 -136.142613) (xy 14.140707 -136.170922) (xy 14.183151 -136.191743) (xy 14.228711 -136.20436)
			(xy 14.275819 -136.208338) (xy 14.32285 -136.20354) (xy 14.345666 -136.19734) (xy 14.405917 -136.177626)
			(xy 14.528413 -136.144925) (xy 14.652728 -136.120022) (xy 14.778368 -136.103014) (xy 14.90483 -136.093971)
			(xy 15.031611 -136.092928) (xy 15.158205 -136.099889) (xy 15.284107 -136.114827) (xy 15.408815 -136.137682)
			(xy 15.531832 -136.168362) (xy 15.652667 -136.206747) (xy 15.770839 -136.252681) (xy 15.885875 -136.305983)
			(xy 15.997318 -136.36644) (xy 16.104722 -136.43381) (xy 16.20766 -136.507825) (xy 16.305721 -136.58819)
			(xy 16.398514 -136.674585) (xy 16.485669 -136.766664) (xy 16.566838 -136.86406) (xy 16.641698 -136.966386)
			(xy 16.70995 -137.073232) (xy 16.771321 -137.184174) (xy 16.825568 -137.298768) (xy 16.872473 -137.416557)
			(xy 16.911851 -137.537072) (xy 16.943543 -137.659833) (xy 16.967423 -137.784349) (xy 16.983396 -137.910124)
			(xy 16.991399 -138.036656) (xy 16.991399 -138.163441) (xy 16.983396 -138.289974) (xy 16.967423 -138.415749)
			(xy 16.943543 -138.540265) (xy 16.911851 -138.663025) (xy 16.872474 -138.78354) (xy 16.825569 -138.90133)
			(xy 16.771322 -139.015924) (xy 16.709951 -139.126866) (xy 16.641699 -139.233712) (xy 16.56684 -139.336038)
			(xy 16.485671 -139.433435) (xy 16.398516 -139.525514) (xy 16.305723 -139.611908) (xy 16.207662 -139.692273)
			(xy 16.104724 -139.766288) (xy 15.99732 -139.833659) (xy 15.885877 -139.894116) (xy 15.770841 -139.947418)
			(xy 15.65267 -139.993352) (xy 15.531834 -140.031737) (xy 15.408818 -140.062418) (xy 15.284109 -140.085273)
			(xy 15.158207 -140.100211) (xy 15.031613 -140.107172) (xy 14.904832 -140.106129) (xy 14.77837 -140.097086)
			(xy 14.652731 -140.080079) (xy 14.528415 -140.055175) (xy 14.40592 -140.022475) (xy 14.345666 -140.002768)
			(xy 14.322849 -139.996552) (xy 14.27581 -139.991733) (xy 14.228691 -139.995698) (xy 14.183117 -140.008307)
			(xy 14.140662 -140.029128) (xy 14.10279 -140.057441) (xy 14.070808 -140.09227) (xy 14.045818 -140.132412)
			(xy 14.028683 -140.176484) (xy 14.019995 -140.222965) (xy 14.01953 -140.246608) (xy 14.01953 -142.210028)
			(xy 14.781278 -142.210028) (xy 14.785323 -142.130265) (xy 14.797416 -142.051321) (xy 14.817435 -141.974006)
			(xy 14.845172 -141.899112) (xy 14.880344 -141.827409) (xy 14.92259 -141.759632) (xy 14.971476 -141.696476)
			(xy 15.0265 -141.638591) (xy 15.087099 -141.586569) (xy 15.152649 -141.540945) (xy 15.222479 -141.502186)
			(xy 15.295872 -141.470691) (xy 15.372074 -141.446782) (xy 15.450304 -141.430705) (xy 15.529759 -141.422625)
			(xy 15.569692 -141.42212) (xy 15.609625 -141.422625) (xy 15.68908 -141.430705) (xy 15.76731 -141.446782)
			(xy 15.843512 -141.470691) (xy 15.916905 -141.502186) (xy 15.986735 -141.540945) (xy 16.052285 -141.586569)
			(xy 16.112884 -141.638591) (xy 16.167908 -141.696476) (xy 16.216794 -141.759632) (xy 16.25904 -141.827409)
			(xy 16.294212 -141.899112) (xy 16.321949 -141.974006) (xy 16.341968 -142.051321) (xy 16.354061 -142.130265)
			(xy 16.358107 -142.210028) (xy 16.354061 -142.289791) (xy 16.341968 -142.368735) (xy 16.321949 -142.44605)
			(xy 16.294212 -142.520944) (xy 16.25904 -142.592647) (xy 16.216794 -142.660424) (xy 16.167908 -142.72358)
			(xy 16.112884 -142.781465) (xy 16.052285 -142.833487) (xy 15.986735 -142.879111) (xy 15.916905 -142.91787)
			(xy 15.843512 -142.949365) (xy 15.76731 -142.973274) (xy 15.68908 -142.989351) (xy 15.609625 -142.997431)
			(xy 15.529759 -142.997431) (xy 15.450304 -142.989351) (xy 15.372074 -142.973274) (xy 15.295872 -142.949365)
			(xy 15.222479 -142.91787) (xy 15.152649 -142.879111) (xy 15.087099 -142.833487) (xy 15.0265 -142.781465)
			(xy 14.971476 -142.72358) (xy 14.92259 -142.660424) (xy 14.880344 -142.592647) (xy 14.845172 -142.520944)
			(xy 14.817435 -142.44605) (xy 14.797416 -142.368735) (xy 14.785323 -142.289791) (xy 14.781278 -142.210028)
			(xy 14.01953 -142.210028) (xy 14.01953 -170.861482) (xy 14.019967 -170.883356) (xy 14.027421 -170.926464)
			(xy 14.042146 -170.967659) (xy 14.063706 -171.005725) (xy 14.091466 -171.039537) (xy 14.124606 -171.068096)
			(xy 14.162146 -171.090559) (xy 14.202978 -171.106263) (xy 14.245896 -171.114744) (xy 14.289632 -171.11575)
			(xy 14.332894 -171.109253) (xy 14.353794 -171.102782) (xy 14.372916 -171.096055) (xy 14.41209 -171.085625)
			(xy 14.432026 -171.081954) (xy 14.443579 -171.080039) (xy 14.466831 -171.077242) (xy 14.478508 -171.076366)
			(xy 14.502293 -171.074188) (xy 14.548489 -171.062082) (xy 14.591614 -171.041567) (xy 14.630152 -171.013363)
			(xy 14.662749 -170.978462) (xy 14.688259 -170.93809) (xy 14.705785 -170.893666) (xy 14.714712 -170.846752)
			(xy 14.715236 -170.822874) (xy 14.715236 -170.692064) (xy 14.68755 -170.657266) (xy 14.669165 -170.633352)
			(xy 14.63817 -170.581605) (xy 14.61424 -170.526234) (xy 14.597791 -170.4682) (xy 14.589107 -170.408508)
			(xy 14.588339 -170.348192) (xy 14.595501 -170.288299) (xy 14.610467 -170.229864) (xy 14.63298 -170.173903)
			(xy 14.662648 -170.121383) (xy 14.698957 -170.073215) (xy 14.74128 -170.030234) (xy 14.788881 -169.993184)
			(xy 14.840936 -169.962708) (xy 14.896543 -169.939333) (xy 14.954739 -169.923466) (xy 15.014515 -169.91538)
			(xy 15.044674 -169.914824) (xy 15.0744 -169.915218) (xy 15.13337 -169.922757) (xy 15.190868 -169.937865)
			(xy 15.245926 -169.96029) (xy 15.297618 -169.989653) (xy 15.345074 -170.025461) (xy 15.387495 -170.067112)
			(xy 15.424167 -170.113903) (xy 15.454473 -170.165048) (xy 15.477904 -170.219685) (xy 15.494064 -170.276897)
			(xy 15.502682 -170.335718) (xy 15.503613 -170.395161) (xy 15.496841 -170.454224) (xy 15.48248 -170.511913)
			(xy 15.460772 -170.567258) (xy 15.432082 -170.619326) (xy 15.396893 -170.667243) (xy 15.376652 -170.689016)
			(xy 15.376652 -187.273184) (xy 11.407902 -191.241934) (xy 11.407902 -191.884554) (xy 9.315196 -193.97726)
			(xy 7.357364 -193.97726) (xy 6.92023 -194.414394) (xy 3.385058 -194.414394) (xy 2.51079 -193.540126)
			(xy 1.398778 -193.540126) (xy 0.894842 -193.03619) (xy 0.705104 -193.03619) (xy 0.705104 -193.378582)
			(xy 0.54356 -193.540126) (xy 0.509016 -193.540126) (xy 0.509016 -195.706339) (xy 3.31393 -195.706339)
			(xy 3.31393 -195.635017) (xy 3.321916 -195.564143) (xy 3.337786 -195.494608) (xy 3.361343 -195.427288)
			(xy 3.392288 -195.363029) (xy 3.430234 -195.302638) (xy 3.474703 -195.246876) (xy 3.525136 -195.196443)
			(xy 3.580898 -195.151974) (xy 3.641289 -195.114028) (xy 3.705548 -195.083083) (xy 3.772868 -195.059526)
			(xy 3.842403 -195.043656) (xy 3.913277 -195.03567) (xy 3.948938 -195.03517) (xy 3.984599 -195.03567)
			(xy 4.055473 -195.043656) (xy 4.125008 -195.059526) (xy 4.192328 -195.083083) (xy 4.256587 -195.114028)
			(xy 4.316978 -195.151974) (xy 4.37274 -195.196443) (xy 4.423173 -195.246876) (xy 4.467642 -195.302638)
			(xy 4.505588 -195.363029) (xy 4.536533 -195.427288) (xy 4.56009 -195.494608) (xy 4.57596 -195.564143)
			(xy 4.583946 -195.635017) (xy 4.583946 -195.706339) (xy 5.813798 -195.706339) (xy 5.813798 -195.635017)
			(xy 5.821784 -195.564143) (xy 5.837654 -195.494608) (xy 5.861211 -195.427288) (xy 5.892156 -195.363029)
			(xy 5.930102 -195.302638) (xy 5.974571 -195.246876) (xy 6.025004 -195.196443) (xy 6.080766 -195.151974)
			(xy 6.141157 -195.114028) (xy 6.205416 -195.083083) (xy 6.272736 -195.059526) (xy 6.342271 -195.043656)
			(xy 6.413145 -195.03567) (xy 6.448806 -195.03517) (xy 6.484467 -195.03567) (xy 6.555341 -195.043656)
			(xy 6.624876 -195.059526) (xy 6.692196 -195.083083) (xy 6.756455 -195.114028) (xy 6.816846 -195.151974)
			(xy 6.872608 -195.196443) (xy 6.923041 -195.246876) (xy 6.96751 -195.302638) (xy 7.005456 -195.363029)
			(xy 7.036401 -195.427288) (xy 7.059958 -195.494608) (xy 7.075828 -195.564143) (xy 7.083814 -195.635017)
			(xy 7.083814 -195.706339) (xy 7.075828 -195.777213) (xy 7.059958 -195.846748) (xy 7.036401 -195.914068)
			(xy 7.005456 -195.978327) (xy 6.96751 -196.038718) (xy 6.923041 -196.09448) (xy 6.872608 -196.144913)
			(xy 6.816846 -196.189382) (xy 6.756455 -196.227328) (xy 6.692196 -196.258273) (xy 6.624876 -196.28183)
			(xy 6.555341 -196.2977) (xy 6.484467 -196.305686) (xy 6.413145 -196.305686) (xy 6.342271 -196.2977)
			(xy 6.272736 -196.28183) (xy 6.205416 -196.258273) (xy 6.141157 -196.227328) (xy 6.080766 -196.189382)
			(xy 6.025004 -196.144913) (xy 5.974571 -196.09448) (xy 5.930102 -196.038718) (xy 5.892156 -195.978327)
			(xy 5.861211 -195.914068) (xy 5.837654 -195.846748) (xy 5.821784 -195.777213) (xy 5.813798 -195.706339)
			(xy 4.583946 -195.706339) (xy 4.57596 -195.777213) (xy 4.56009 -195.846748) (xy 4.536533 -195.914068)
			(xy 4.505588 -195.978327) (xy 4.467642 -196.038718) (xy 4.423173 -196.09448) (xy 4.37274 -196.144913)
			(xy 4.316978 -196.189382) (xy 4.256587 -196.227328) (xy 4.192328 -196.258273) (xy 4.125008 -196.28183)
			(xy 4.055473 -196.2977) (xy 3.984599 -196.305686) (xy 3.913277 -196.305686) (xy 3.842403 -196.2977)
			(xy 3.772868 -196.28183) (xy 3.705548 -196.258273) (xy 3.641289 -196.227328) (xy 3.580898 -196.189382)
			(xy 3.525136 -196.144913) (xy 3.474703 -196.09448) (xy 3.430234 -196.038718) (xy 3.392288 -195.978327)
			(xy 3.361343 -195.914068) (xy 3.337786 -195.846748) (xy 3.321916 -195.777213) (xy 3.31393 -195.706339)
			(xy 0.509016 -195.706339) (xy 0.509016 -196.706083) (xy 1.313934 -196.706083) (xy 1.313934 -196.634761)
			(xy 1.32192 -196.563887) (xy 1.33779 -196.494352) (xy 1.361347 -196.427032) (xy 1.392292 -196.362773)
			(xy 1.430238 -196.302382) (xy 1.474707 -196.24662) (xy 1.52514 -196.196187) (xy 1.580902 -196.151718)
			(xy 1.641293 -196.113772) (xy 1.705552 -196.082827) (xy 1.772872 -196.05927) (xy 1.842407 -196.0434)
			(xy 1.913281 -196.035414) (xy 1.948942 -196.034914) (xy 1.984603 -196.035414) (xy 2.055477 -196.0434)
			(xy 2.125012 -196.05927) (xy 2.192332 -196.082827) (xy 2.256591 -196.113772) (xy 2.316982 -196.151718)
			(xy 2.372744 -196.196187) (xy 2.423177 -196.24662) (xy 2.467646 -196.302382) (xy 2.505592 -196.362773)
			(xy 2.536537 -196.427032) (xy 2.560094 -196.494352) (xy 2.575964 -196.563887) (xy 2.58395 -196.634761)
			(xy 2.58395 -196.706083) (xy 7.813794 -196.706083) (xy 7.813794 -196.634761) (xy 7.82178 -196.563887)
			(xy 7.83765 -196.494352) (xy 7.861207 -196.427032) (xy 7.892152 -196.362773) (xy 7.930098 -196.302382)
			(xy 7.974567 -196.24662) (xy 8.025 -196.196187) (xy 8.080762 -196.151718) (xy 8.141153 -196.113772)
			(xy 8.205412 -196.082827) (xy 8.272732 -196.05927) (xy 8.342267 -196.0434) (xy 8.413141 -196.035414)
			(xy 8.448802 -196.034914) (xy 8.484463 -196.035414) (xy 8.555337 -196.0434) (xy 8.624872 -196.05927)
			(xy 8.692192 -196.082827) (xy 8.756451 -196.113772) (xy 8.816842 -196.151718) (xy 8.872604 -196.196187)
			(xy 8.923037 -196.24662) (xy 8.967506 -196.302382) (xy 9.005452 -196.362773) (xy 9.036397 -196.427032)
			(xy 9.059954 -196.494352) (xy 9.075824 -196.563887) (xy 9.08381 -196.634761) (xy 9.08381 -196.706083)
			(xy 9.075824 -196.776957) (xy 9.059954 -196.846492) (xy 9.036397 -196.913812) (xy 9.005452 -196.978071)
			(xy 8.967506 -197.038462) (xy 8.923037 -197.094224) (xy 8.872604 -197.144657) (xy 8.816842 -197.189126)
			(xy 8.756451 -197.227072) (xy 8.692192 -197.258017) (xy 8.624872 -197.281574) (xy 8.555337 -197.297444)
			(xy 8.484463 -197.30543) (xy 8.413141 -197.30543) (xy 8.342267 -197.297444) (xy 8.272732 -197.281574)
			(xy 8.205412 -197.258017) (xy 8.141153 -197.227072) (xy 8.080762 -197.189126) (xy 8.025 -197.144657)
			(xy 7.974567 -197.094224) (xy 7.930098 -197.038462) (xy 7.892152 -196.978071) (xy 7.861207 -196.913812)
			(xy 7.83765 -196.846492) (xy 7.82178 -196.776957) (xy 7.813794 -196.706083) (xy 2.58395 -196.706083)
			(xy 2.575964 -196.776957) (xy 2.560094 -196.846492) (xy 2.536537 -196.913812) (xy 2.505592 -196.978071)
			(xy 2.467646 -197.038462) (xy 2.423177 -197.094224) (xy 2.372744 -197.144657) (xy 2.316982 -197.189126)
			(xy 2.256591 -197.227072) (xy 2.192332 -197.258017) (xy 2.125012 -197.281574) (xy 2.055477 -197.297444)
			(xy 1.984603 -197.30543) (xy 1.913281 -197.30543) (xy 1.842407 -197.297444) (xy 1.772872 -197.281574)
			(xy 1.705552 -197.258017) (xy 1.641293 -197.227072) (xy 1.580902 -197.189126) (xy 1.52514 -197.144657)
			(xy 1.474707 -197.094224) (xy 1.430238 -197.038462) (xy 1.392292 -196.978071) (xy 1.361347 -196.913812)
			(xy 1.33779 -196.846492) (xy 1.32192 -196.776957) (xy 1.313934 -196.706083) (xy 0.509016 -196.706083)
			(xy 0.509016 -197.706335) (xy 3.31393 -197.706335) (xy 3.31393 -197.635013) (xy 3.321916 -197.564139)
			(xy 3.337786 -197.494604) (xy 3.361343 -197.427284) (xy 3.392288 -197.363025) (xy 3.430234 -197.302634)
			(xy 3.474703 -197.246872) (xy 3.525136 -197.196439) (xy 3.580898 -197.15197) (xy 3.641289 -197.114024)
			(xy 3.705548 -197.083079) (xy 3.772868 -197.059522) (xy 3.842403 -197.043652) (xy 3.913277 -197.035666)
			(xy 3.948938 -197.035166) (xy 3.984599 -197.035666) (xy 4.055473 -197.043652) (xy 4.125008 -197.059522)
			(xy 4.192328 -197.083079) (xy 4.256587 -197.114024) (xy 4.316978 -197.15197) (xy 4.37274 -197.196439)
			(xy 4.423173 -197.246872) (xy 4.467642 -197.302634) (xy 4.505588 -197.363025) (xy 4.536533 -197.427284)
			(xy 4.56009 -197.494604) (xy 4.57596 -197.564139) (xy 4.583946 -197.635013) (xy 4.583946 -197.706335)
			(xy 5.813798 -197.706335) (xy 5.813798 -197.635013) (xy 5.821784 -197.564139) (xy 5.837654 -197.494604)
			(xy 5.861211 -197.427284) (xy 5.892156 -197.363025) (xy 5.930102 -197.302634) (xy 5.974571 -197.246872)
			(xy 6.025004 -197.196439) (xy 6.080766 -197.15197) (xy 6.141157 -197.114024) (xy 6.205416 -197.083079)
			(xy 6.272736 -197.059522) (xy 6.342271 -197.043652) (xy 6.413145 -197.035666) (xy 6.448806 -197.035166)
			(xy 6.484467 -197.035666) (xy 6.555341 -197.043652) (xy 6.624876 -197.059522) (xy 6.692196 -197.083079)
			(xy 6.756455 -197.114024) (xy 6.816846 -197.15197) (xy 6.872608 -197.196439) (xy 6.923041 -197.246872)
			(xy 6.96751 -197.302634) (xy 7.005456 -197.363025) (xy 7.036401 -197.427284) (xy 7.059958 -197.494604)
			(xy 7.075828 -197.564139) (xy 7.083814 -197.635013) (xy 7.083814 -197.706335) (xy 7.075828 -197.777209)
			(xy 7.059958 -197.846744) (xy 7.036401 -197.914064) (xy 7.005456 -197.978323) (xy 6.96751 -198.038714)
			(xy 6.923041 -198.094476) (xy 6.872608 -198.144909) (xy 6.816846 -198.189378) (xy 6.756455 -198.227324)
			(xy 6.692196 -198.258269) (xy 6.624876 -198.281826) (xy 6.555341 -198.297696) (xy 6.484467 -198.305682)
			(xy 6.413145 -198.305682) (xy 6.342271 -198.297696) (xy 6.272736 -198.281826) (xy 6.205416 -198.258269)
			(xy 6.141157 -198.227324) (xy 6.080766 -198.189378) (xy 6.025004 -198.144909) (xy 5.974571 -198.094476)
			(xy 5.930102 -198.038714) (xy 5.892156 -197.978323) (xy 5.861211 -197.914064) (xy 5.837654 -197.846744)
			(xy 5.821784 -197.777209) (xy 5.813798 -197.706335) (xy 4.583946 -197.706335) (xy 4.57596 -197.777209)
			(xy 4.56009 -197.846744) (xy 4.536533 -197.914064) (xy 4.505588 -197.978323) (xy 4.467642 -198.038714)
			(xy 4.423173 -198.094476) (xy 4.37274 -198.144909) (xy 4.316978 -198.189378) (xy 4.256587 -198.227324)
			(xy 4.192328 -198.258269) (xy 4.125008 -198.281826) (xy 4.055473 -198.297696) (xy 3.984599 -198.305682)
			(xy 3.913277 -198.305682) (xy 3.842403 -198.297696) (xy 3.772868 -198.281826) (xy 3.705548 -198.258269)
			(xy 3.641289 -198.227324) (xy 3.580898 -198.189378) (xy 3.525136 -198.144909) (xy 3.474703 -198.094476)
			(xy 3.430234 -198.038714) (xy 3.392288 -197.978323) (xy 3.361343 -197.914064) (xy 3.337786 -197.846744)
			(xy 3.321916 -197.777209) (xy 3.31393 -197.706335) (xy 0.509016 -197.706335) (xy 0.509016 -198.706079)
			(xy 1.313934 -198.706079) (xy 1.313934 -198.634757) (xy 1.32192 -198.563883) (xy 1.33779 -198.494348)
			(xy 1.361347 -198.427028) (xy 1.392292 -198.362769) (xy 1.430238 -198.302378) (xy 1.474707 -198.246616)
			(xy 1.52514 -198.196183) (xy 1.580902 -198.151714) (xy 1.641293 -198.113768) (xy 1.705552 -198.082823)
			(xy 1.772872 -198.059266) (xy 1.842407 -198.043396) (xy 1.913281 -198.03541) (xy 1.948942 -198.03491)
			(xy 1.984603 -198.03541) (xy 2.055477 -198.043396) (xy 2.125012 -198.059266) (xy 2.192332 -198.082823)
			(xy 2.256591 -198.113768) (xy 2.316982 -198.151714) (xy 2.372744 -198.196183) (xy 2.423177 -198.246616)
			(xy 2.467646 -198.302378) (xy 2.505592 -198.362769) (xy 2.536537 -198.427028) (xy 2.560094 -198.494348)
			(xy 2.575964 -198.563883) (xy 2.58395 -198.634757) (xy 2.58395 -198.706079) (xy 7.813794 -198.706079)
			(xy 7.813794 -198.634757) (xy 7.82178 -198.563883) (xy 7.83765 -198.494348) (xy 7.861207 -198.427028)
			(xy 7.892152 -198.362769) (xy 7.930098 -198.302378) (xy 7.974567 -198.246616) (xy 8.025 -198.196183)
			(xy 8.080762 -198.151714) (xy 8.141153 -198.113768) (xy 8.205412 -198.082823) (xy 8.272732 -198.059266)
			(xy 8.342267 -198.043396) (xy 8.413141 -198.03541) (xy 8.448802 -198.03491) (xy 8.484463 -198.03541)
			(xy 8.555337 -198.043396) (xy 8.624872 -198.059266) (xy 8.692192 -198.082823) (xy 8.756451 -198.113768)
			(xy 8.816842 -198.151714) (xy 8.872604 -198.196183) (xy 8.923037 -198.246616) (xy 8.967506 -198.302378)
			(xy 9.005452 -198.362769) (xy 9.036397 -198.427028) (xy 9.059954 -198.494348) (xy 9.075824 -198.563883)
			(xy 9.08381 -198.634757) (xy 9.08381 -198.706079) (xy 9.075824 -198.776953) (xy 9.059954 -198.846488)
			(xy 9.036397 -198.913808) (xy 9.005452 -198.978067) (xy 8.967506 -199.038458) (xy 8.923037 -199.09422)
			(xy 8.872604 -199.144653) (xy 8.816842 -199.189122) (xy 8.756451 -199.227068) (xy 8.692192 -199.258013)
			(xy 8.624872 -199.28157) (xy 8.555337 -199.29744) (xy 8.484463 -199.305426) (xy 8.413141 -199.305426)
			(xy 8.342267 -199.29744) (xy 8.272732 -199.28157) (xy 8.205412 -199.258013) (xy 8.141153 -199.227068)
			(xy 8.080762 -199.189122) (xy 8.025 -199.144653) (xy 7.974567 -199.09422) (xy 7.930098 -199.038458)
			(xy 7.892152 -198.978067) (xy 7.861207 -198.913808) (xy 7.83765 -198.846488) (xy 7.82178 -198.776953)
			(xy 7.813794 -198.706079) (xy 2.58395 -198.706079) (xy 2.575964 -198.776953) (xy 2.560094 -198.846488)
			(xy 2.536537 -198.913808) (xy 2.505592 -198.978067) (xy 2.467646 -199.038458) (xy 2.423177 -199.09422)
			(xy 2.372744 -199.144653) (xy 2.316982 -199.189122) (xy 2.256591 -199.227068) (xy 2.192332 -199.258013)
			(xy 2.125012 -199.28157) (xy 2.055477 -199.29744) (xy 1.984603 -199.305426) (xy 1.913281 -199.305426)
			(xy 1.842407 -199.29744) (xy 1.772872 -199.28157) (xy 1.705552 -199.258013) (xy 1.641293 -199.227068)
			(xy 1.580902 -199.189122) (xy 1.52514 -199.144653) (xy 1.474707 -199.09422) (xy 1.430238 -199.038458)
			(xy 1.392292 -198.978067) (xy 1.361347 -198.913808) (xy 1.33779 -198.846488) (xy 1.32192 -198.776953)
			(xy 1.313934 -198.706079) (xy 0.509016 -198.706079) (xy 0.509016 -199.706331) (xy 3.31393 -199.706331)
			(xy 3.31393 -199.635009) (xy 3.321916 -199.564135) (xy 3.337786 -199.4946) (xy 3.361343 -199.42728)
			(xy 3.392288 -199.363021) (xy 3.430234 -199.30263) (xy 3.474703 -199.246868) (xy 3.525136 -199.196435)
			(xy 3.580898 -199.151966) (xy 3.641289 -199.11402) (xy 3.705548 -199.083075) (xy 3.772868 -199.059518)
			(xy 3.842403 -199.043648) (xy 3.913277 -199.035662) (xy 3.948938 -199.035162) (xy 3.984599 -199.035662)
			(xy 4.055473 -199.043648) (xy 4.125008 -199.059518) (xy 4.192328 -199.083075) (xy 4.256587 -199.11402)
			(xy 4.316978 -199.151966) (xy 4.37274 -199.196435) (xy 4.423173 -199.246868) (xy 4.467642 -199.30263)
			(xy 4.505588 -199.363021) (xy 4.536533 -199.42728) (xy 4.56009 -199.4946) (xy 4.57596 -199.564135)
			(xy 4.583946 -199.635009) (xy 4.583946 -199.706331) (xy 5.813798 -199.706331) (xy 5.813798 -199.635009)
			(xy 5.821784 -199.564135) (xy 5.837654 -199.4946) (xy 5.861211 -199.42728) (xy 5.892156 -199.363021)
			(xy 5.930102 -199.30263) (xy 5.974571 -199.246868) (xy 6.025004 -199.196435) (xy 6.080766 -199.151966)
			(xy 6.141157 -199.11402) (xy 6.205416 -199.083075) (xy 6.272736 -199.059518) (xy 6.342271 -199.043648)
			(xy 6.413145 -199.035662) (xy 6.448806 -199.035162) (xy 6.484467 -199.035662) (xy 6.555341 -199.043648)
			(xy 6.624876 -199.059518) (xy 6.692196 -199.083075) (xy 6.756455 -199.11402) (xy 6.816846 -199.151966)
			(xy 6.872608 -199.196435) (xy 6.923041 -199.246868) (xy 6.96751 -199.30263) (xy 7.005456 -199.363021)
			(xy 7.036401 -199.42728) (xy 7.059958 -199.4946) (xy 7.075828 -199.564135) (xy 7.083814 -199.635009)
			(xy 7.083814 -199.706331) (xy 7.075828 -199.777205) (xy 7.059958 -199.84674) (xy 7.036401 -199.91406)
			(xy 7.005456 -199.978319) (xy 6.96751 -200.03871) (xy 6.923041 -200.094472) (xy 6.872608 -200.144905)
			(xy 6.816846 -200.189374) (xy 6.756455 -200.22732) (xy 6.692196 -200.258265) (xy 6.624876 -200.281822)
			(xy 6.555341 -200.297692) (xy 6.484467 -200.305678) (xy 6.413145 -200.305678) (xy 6.342271 -200.297692)
			(xy 6.272736 -200.281822) (xy 6.205416 -200.258265) (xy 6.141157 -200.22732) (xy 6.080766 -200.189374)
			(xy 6.025004 -200.144905) (xy 5.974571 -200.094472) (xy 5.930102 -200.03871) (xy 5.892156 -199.978319)
			(xy 5.861211 -199.91406) (xy 5.837654 -199.84674) (xy 5.821784 -199.777205) (xy 5.813798 -199.706331)
			(xy 4.583946 -199.706331) (xy 4.57596 -199.777205) (xy 4.56009 -199.84674) (xy 4.536533 -199.91406)
			(xy 4.505588 -199.978319) (xy 4.467642 -200.03871) (xy 4.423173 -200.094472) (xy 4.37274 -200.144905)
			(xy 4.316978 -200.189374) (xy 4.256587 -200.22732) (xy 4.192328 -200.258265) (xy 4.125008 -200.281822)
			(xy 4.055473 -200.297692) (xy 3.984599 -200.305678) (xy 3.913277 -200.305678) (xy 3.842403 -200.297692)
			(xy 3.772868 -200.281822) (xy 3.705548 -200.258265) (xy 3.641289 -200.22732) (xy 3.580898 -200.189374)
			(xy 3.525136 -200.144905) (xy 3.474703 -200.094472) (xy 3.430234 -200.03871) (xy 3.392288 -199.978319)
			(xy 3.361343 -199.91406) (xy 3.337786 -199.84674) (xy 3.321916 -199.777205) (xy 3.31393 -199.706331)
			(xy 0.509016 -199.706331) (xy 0.509016 -200.706075) (xy 1.313934 -200.706075) (xy 1.313934 -200.634753)
			(xy 1.32192 -200.563879) (xy 1.33779 -200.494344) (xy 1.361347 -200.427024) (xy 1.392292 -200.362765)
			(xy 1.430238 -200.302374) (xy 1.474707 -200.246612) (xy 1.52514 -200.196179) (xy 1.580902 -200.15171)
			(xy 1.641293 -200.113764) (xy 1.705552 -200.082819) (xy 1.772872 -200.059262) (xy 1.842407 -200.043392)
			(xy 1.913281 -200.035406) (xy 1.948942 -200.034906) (xy 1.984603 -200.035406) (xy 2.055477 -200.043392)
			(xy 2.125012 -200.059262) (xy 2.192332 -200.082819) (xy 2.256591 -200.113764) (xy 2.316982 -200.15171)
			(xy 2.372744 -200.196179) (xy 2.423177 -200.246612) (xy 2.467646 -200.302374) (xy 2.505592 -200.362765)
			(xy 2.536537 -200.427024) (xy 2.560094 -200.494344) (xy 2.575964 -200.563879) (xy 2.58395 -200.634753)
			(xy 2.58395 -200.706075) (xy 7.813794 -200.706075) (xy 7.813794 -200.634753) (xy 7.82178 -200.563879)
			(xy 7.83765 -200.494344) (xy 7.861207 -200.427024) (xy 7.892152 -200.362765) (xy 7.930098 -200.302374)
			(xy 7.974567 -200.246612) (xy 8.025 -200.196179) (xy 8.080762 -200.15171) (xy 8.141153 -200.113764)
			(xy 8.205412 -200.082819) (xy 8.272732 -200.059262) (xy 8.342267 -200.043392) (xy 8.413141 -200.035406)
			(xy 8.448802 -200.034906) (xy 8.484463 -200.035406) (xy 8.555337 -200.043392) (xy 8.624872 -200.059262)
			(xy 8.692192 -200.082819) (xy 8.756451 -200.113764) (xy 8.816842 -200.15171) (xy 8.872604 -200.196179)
			(xy 8.923037 -200.246612) (xy 8.967506 -200.302374) (xy 9.005452 -200.362765) (xy 9.036397 -200.427024)
			(xy 9.059954 -200.494344) (xy 9.075824 -200.563879) (xy 9.08381 -200.634753) (xy 9.08381 -200.706075)
			(xy 9.075824 -200.776949) (xy 9.059954 -200.846484) (xy 9.036397 -200.913804) (xy 9.005452 -200.978063)
			(xy 8.967506 -201.038454) (xy 8.923037 -201.094216) (xy 8.872604 -201.144649) (xy 8.816842 -201.189118)
			(xy 8.756451 -201.227064) (xy 8.692192 -201.258009) (xy 8.624872 -201.281566) (xy 8.555337 -201.297436)
			(xy 8.484463 -201.305422) (xy 8.413141 -201.305422) (xy 8.342267 -201.297436) (xy 8.272732 -201.281566)
			(xy 8.205412 -201.258009) (xy 8.141153 -201.227064) (xy 8.080762 -201.189118) (xy 8.025 -201.144649)
			(xy 7.974567 -201.094216) (xy 7.930098 -201.038454) (xy 7.892152 -200.978063) (xy 7.861207 -200.913804)
			(xy 7.83765 -200.846484) (xy 7.82178 -200.776949) (xy 7.813794 -200.706075) (xy 2.58395 -200.706075)
			(xy 2.575964 -200.776949) (xy 2.560094 -200.846484) (xy 2.536537 -200.913804) (xy 2.505592 -200.978063)
			(xy 2.467646 -201.038454) (xy 2.423177 -201.094216) (xy 2.372744 -201.144649) (xy 2.316982 -201.189118)
			(xy 2.256591 -201.227064) (xy 2.192332 -201.258009) (xy 2.125012 -201.281566) (xy 2.055477 -201.297436)
			(xy 1.984603 -201.305422) (xy 1.913281 -201.305422) (xy 1.842407 -201.297436) (xy 1.772872 -201.281566)
			(xy 1.705552 -201.258009) (xy 1.641293 -201.227064) (xy 1.580902 -201.189118) (xy 1.52514 -201.144649)
			(xy 1.474707 -201.094216) (xy 1.430238 -201.038454) (xy 1.392292 -200.978063) (xy 1.361347 -200.913804)
			(xy 1.33779 -200.846484) (xy 1.32192 -200.776949) (xy 1.313934 -200.706075) (xy 0.509016 -200.706075)
			(xy 0.509016 -202.706071) (xy 1.313934 -202.706071) (xy 1.313934 -202.634749) (xy 1.32192 -202.563875)
			(xy 1.33779 -202.49434) (xy 1.361347 -202.42702) (xy 1.392292 -202.362761) (xy 1.430238 -202.30237)
			(xy 1.474707 -202.246608) (xy 1.52514 -202.196175) (xy 1.580902 -202.151706) (xy 1.641293 -202.11376)
			(xy 1.705552 -202.082815) (xy 1.772872 -202.059258) (xy 1.842407 -202.043388) (xy 1.913281 -202.035402)
			(xy 1.948942 -202.034902) (xy 1.984603 -202.035402) (xy 2.055477 -202.043388) (xy 2.125012 -202.059258)
			(xy 2.192332 -202.082815) (xy 2.256591 -202.11376) (xy 2.316982 -202.151706) (xy 2.372744 -202.196175)
			(xy 2.423177 -202.246608) (xy 2.467646 -202.30237) (xy 2.505592 -202.362761) (xy 2.536537 -202.42702)
			(xy 2.560094 -202.49434) (xy 2.575964 -202.563875) (xy 2.58395 -202.634749) (xy 2.58395 -202.706071)
			(xy 2.575964 -202.776945) (xy 2.560094 -202.84648) (xy 2.536537 -202.9138) (xy 2.505592 -202.978059)
			(xy 2.467646 -203.03845) (xy 2.423177 -203.094212) (xy 2.372744 -203.144645) (xy 2.316982 -203.189114)
			(xy 2.256591 -203.22706) (xy 2.192332 -203.258005) (xy 2.125012 -203.281562) (xy 2.055477 -203.297432)
			(xy 1.984603 -203.305418) (xy 1.913281 -203.305418) (xy 1.842407 -203.297432) (xy 1.772872 -203.281562)
			(xy 1.705552 -203.258005) (xy 1.641293 -203.22706) (xy 1.580902 -203.189114) (xy 1.52514 -203.144645)
			(xy 1.474707 -203.094212) (xy 1.430238 -203.03845) (xy 1.392292 -202.978059) (xy 1.361347 -202.9138)
			(xy 1.33779 -202.84648) (xy 1.32192 -202.776945) (xy 1.313934 -202.706071) (xy 0.509016 -202.706071)
			(xy 0.509016 -203.706323) (xy 3.31393 -203.706323) (xy 3.31393 -203.635001) (xy 3.321916 -203.564127)
			(xy 3.337786 -203.494592) (xy 3.361343 -203.427272) (xy 3.392288 -203.363013) (xy 3.430234 -203.302622)
			(xy 3.474703 -203.24686) (xy 3.525136 -203.196427) (xy 3.580898 -203.151958) (xy 3.641289 -203.114012)
			(xy 3.705548 -203.083067) (xy 3.772868 -203.05951) (xy 3.842403 -203.04364) (xy 3.913277 -203.035654)
			(xy 3.948938 -203.035154) (xy 3.984599 -203.035654) (xy 4.055473 -203.04364) (xy 4.125008 -203.05951)
			(xy 4.192328 -203.083067) (xy 4.256587 -203.114012) (xy 4.316978 -203.151958) (xy 4.37274 -203.196427)
			(xy 4.423173 -203.24686) (xy 4.467642 -203.302622) (xy 4.505588 -203.363013) (xy 4.536533 -203.427272)
			(xy 4.56009 -203.494592) (xy 4.57596 -203.564127) (xy 4.583946 -203.635001) (xy 4.583946 -203.706323)
			(xy 4.57596 -203.777197) (xy 4.56009 -203.846732) (xy 4.536533 -203.914052) (xy 4.505588 -203.978311)
			(xy 4.467642 -204.038702) (xy 4.423173 -204.094464) (xy 4.37274 -204.144897) (xy 4.316978 -204.189366)
			(xy 4.256587 -204.227312) (xy 4.192328 -204.258257) (xy 4.125008 -204.281814) (xy 4.055473 -204.297684)
			(xy 3.984599 -204.30567) (xy 3.913277 -204.30567) (xy 3.842403 -204.297684) (xy 3.772868 -204.281814)
			(xy 3.705548 -204.258257) (xy 3.641289 -204.227312) (xy 3.580898 -204.189366) (xy 3.525136 -204.144897)
			(xy 3.474703 -204.094464) (xy 3.430234 -204.038702) (xy 3.392288 -203.978311) (xy 3.361343 -203.914052)
			(xy 3.337786 -203.846732) (xy 3.321916 -203.777197) (xy 3.31393 -203.706323) (xy 0.509016 -203.706323)
			(xy 0.509016 -204.706321) (xy 1.313934 -204.706321) (xy 1.313934 -204.634999) (xy 1.32192 -204.564125)
			(xy 1.33779 -204.49459) (xy 1.361347 -204.42727) (xy 1.392292 -204.363011) (xy 1.430238 -204.30262)
			(xy 1.474707 -204.246858) (xy 1.52514 -204.196425) (xy 1.580902 -204.151956) (xy 1.641293 -204.11401)
			(xy 1.705552 -204.083065) (xy 1.772872 -204.059508) (xy 1.842407 -204.043638) (xy 1.913281 -204.035652)
			(xy 1.948942 -204.035152) (xy 1.984603 -204.035652) (xy 2.055477 -204.043638) (xy 2.125012 -204.059508)
			(xy 2.192332 -204.083065) (xy 2.256591 -204.11401) (xy 2.316982 -204.151956) (xy 2.372744 -204.196425)
			(xy 2.423177 -204.246858) (xy 2.467646 -204.30262) (xy 2.505592 -204.363011) (xy 2.536537 -204.42727)
			(xy 2.560094 -204.49459) (xy 2.575964 -204.564125) (xy 2.58395 -204.634999) (xy 2.58395 -204.706321)
			(xy 2.575964 -204.777195) (xy 2.560094 -204.84673) (xy 2.536537 -204.91405) (xy 2.505592 -204.978309)
			(xy 2.467646 -205.0387) (xy 2.423177 -205.094462) (xy 2.372744 -205.144895) (xy 2.316982 -205.189364)
			(xy 2.256591 -205.22731) (xy 2.192332 -205.258255) (xy 2.125012 -205.281812) (xy 2.055477 -205.297682)
			(xy 1.984603 -205.305668) (xy 1.913281 -205.305668) (xy 1.842407 -205.297682) (xy 1.772872 -205.281812)
			(xy 1.705552 -205.258255) (xy 1.641293 -205.22731) (xy 1.580902 -205.189364) (xy 1.52514 -205.144895)
			(xy 1.474707 -205.094462) (xy 1.430238 -205.0387) (xy 1.392292 -204.978309) (xy 1.361347 -204.91405)
			(xy 1.33779 -204.84673) (xy 1.32192 -204.777195) (xy 1.313934 -204.706321) (xy 0.509016 -204.706321)
			(xy 0.509016 -205.706319) (xy 3.31393 -205.706319) (xy 3.31393 -205.634997) (xy 3.321916 -205.564123)
			(xy 3.337786 -205.494588) (xy 3.361343 -205.427268) (xy 3.392288 -205.363009) (xy 3.430234 -205.302618)
			(xy 3.474703 -205.246856) (xy 3.525136 -205.196423) (xy 3.580898 -205.151954) (xy 3.641289 -205.114008)
			(xy 3.705548 -205.083063) (xy 3.772868 -205.059506) (xy 3.842403 -205.043636) (xy 3.913277 -205.03565)
			(xy 3.948938 -205.03515) (xy 3.984599 -205.03565) (xy 4.055473 -205.043636) (xy 4.125008 -205.059506)
			(xy 4.192328 -205.083063) (xy 4.256587 -205.114008) (xy 4.316978 -205.151954) (xy 4.37274 -205.196423)
			(xy 4.423173 -205.246856) (xy 4.467642 -205.302618) (xy 4.505588 -205.363009) (xy 4.536533 -205.427268)
			(xy 4.56009 -205.494588) (xy 4.57596 -205.564123) (xy 4.583946 -205.634997) (xy 4.583946 -205.706319)
			(xy 4.57596 -205.777193) (xy 4.56009 -205.846728) (xy 4.536533 -205.914048) (xy 4.505588 -205.978307)
			(xy 4.467642 -206.038698) (xy 4.423173 -206.09446) (xy 4.37274 -206.144893) (xy 4.316978 -206.189362)
			(xy 4.256587 -206.227308) (xy 4.192328 -206.258253) (xy 4.125008 -206.28181) (xy 4.055473 -206.29768)
			(xy 3.984599 -206.305666) (xy 3.913277 -206.305666) (xy 3.842403 -206.29768) (xy 3.772868 -206.28181)
			(xy 3.705548 -206.258253) (xy 3.641289 -206.227308) (xy 3.580898 -206.189362) (xy 3.525136 -206.144893)
			(xy 3.474703 -206.09446) (xy 3.430234 -206.038698) (xy 3.392288 -205.978307) (xy 3.361343 -205.914048)
			(xy 3.337786 -205.846728) (xy 3.321916 -205.777193) (xy 3.31393 -205.706319) (xy 0.509016 -205.706319)
			(xy 0.509016 -206.706317) (xy 1.313934 -206.706317) (xy 1.313934 -206.634995) (xy 1.32192 -206.564121)
			(xy 1.33779 -206.494586) (xy 1.361347 -206.427266) (xy 1.392292 -206.363007) (xy 1.430238 -206.302616)
			(xy 1.474707 -206.246854) (xy 1.52514 -206.196421) (xy 1.580902 -206.151952) (xy 1.641293 -206.114006)
			(xy 1.705552 -206.083061) (xy 1.772872 -206.059504) (xy 1.842407 -206.043634) (xy 1.913281 -206.035648)
			(xy 1.948942 -206.035148) (xy 1.984603 -206.035648) (xy 2.055477 -206.043634) (xy 2.125012 -206.059504)
			(xy 2.192332 -206.083061) (xy 2.256591 -206.114006) (xy 2.316982 -206.151952) (xy 2.372744 -206.196421)
			(xy 2.423177 -206.246854) (xy 2.467646 -206.302616) (xy 2.505592 -206.363007) (xy 2.536537 -206.427266)
			(xy 2.560094 -206.494586) (xy 2.575964 -206.564121) (xy 2.58395 -206.634995) (xy 2.58395 -206.706317)
			(xy 2.575964 -206.777191) (xy 2.560094 -206.846726) (xy 2.536537 -206.914046) (xy 2.505592 -206.978305)
			(xy 2.467646 -207.038696) (xy 2.423177 -207.094458) (xy 2.372744 -207.144891) (xy 2.316982 -207.18936)
			(xy 2.256591 -207.227306) (xy 2.192332 -207.258251) (xy 2.125012 -207.281808) (xy 2.055477 -207.297678)
			(xy 1.984603 -207.305664) (xy 1.913281 -207.305664) (xy 1.842407 -207.297678) (xy 1.772872 -207.281808)
			(xy 1.705552 -207.258251) (xy 1.641293 -207.227306) (xy 1.580902 -207.18936) (xy 1.52514 -207.144891)
			(xy 1.474707 -207.094458) (xy 1.430238 -207.038696) (xy 1.392292 -206.978305) (xy 1.361347 -206.914046)
			(xy 1.33779 -206.846726) (xy 1.32192 -206.777191) (xy 1.313934 -206.706317) (xy 0.509016 -206.706317)
			(xy 0.509016 -207.706315) (xy 3.31393 -207.706315) (xy 3.31393 -207.634993) (xy 3.321916 -207.564119)
			(xy 3.337786 -207.494584) (xy 3.361343 -207.427264) (xy 3.392288 -207.363005) (xy 3.430234 -207.302614)
			(xy 3.474703 -207.246852) (xy 3.525136 -207.196419) (xy 3.580898 -207.15195) (xy 3.641289 -207.114004)
			(xy 3.705548 -207.083059) (xy 3.772868 -207.059502) (xy 3.842403 -207.043632) (xy 3.913277 -207.035646)
			(xy 3.948938 -207.035146) (xy 3.984599 -207.035646) (xy 4.055473 -207.043632) (xy 4.125008 -207.059502)
			(xy 4.192328 -207.083059) (xy 4.256587 -207.114004) (xy 4.316978 -207.15195) (xy 4.37274 -207.196419)
			(xy 4.423173 -207.246852) (xy 4.467642 -207.302614) (xy 4.505588 -207.363005) (xy 4.536533 -207.427264)
			(xy 4.56009 -207.494584) (xy 4.57596 -207.564119) (xy 4.583946 -207.634993) (xy 4.583946 -207.706315)
			(xy 4.57596 -207.777189) (xy 4.56009 -207.846724) (xy 4.536533 -207.914044) (xy 4.505588 -207.978303)
			(xy 4.467642 -208.038694) (xy 4.423173 -208.094456) (xy 4.37274 -208.144889) (xy 4.316978 -208.189358)
			(xy 4.256587 -208.227304) (xy 4.192328 -208.258249) (xy 4.125008 -208.281806) (xy 4.055473 -208.297676)
			(xy 3.984599 -208.305662) (xy 3.913277 -208.305662) (xy 3.842403 -208.297676) (xy 3.772868 -208.281806)
			(xy 3.705548 -208.258249) (xy 3.641289 -208.227304) (xy 3.580898 -208.189358) (xy 3.525136 -208.144889)
			(xy 3.474703 -208.094456) (xy 3.430234 -208.038694) (xy 3.392288 -207.978303) (xy 3.361343 -207.914044)
			(xy 3.337786 -207.846724) (xy 3.321916 -207.777189) (xy 3.31393 -207.706315) (xy 0.509016 -207.706315)
			(xy 0.509016 -208.706313) (xy 1.313934 -208.706313) (xy 1.313934 -208.634991) (xy 1.32192 -208.564117)
			(xy 1.33779 -208.494582) (xy 1.361347 -208.427262) (xy 1.392292 -208.363003) (xy 1.430238 -208.302612)
			(xy 1.474707 -208.24685) (xy 1.52514 -208.196417) (xy 1.580902 -208.151948) (xy 1.641293 -208.114002)
			(xy 1.705552 -208.083057) (xy 1.772872 -208.0595) (xy 1.842407 -208.04363) (xy 1.913281 -208.035644)
			(xy 1.948942 -208.035144) (xy 1.984603 -208.035644) (xy 2.055477 -208.04363) (xy 2.125012 -208.0595)
			(xy 2.192332 -208.083057) (xy 2.256591 -208.114002) (xy 2.316982 -208.151948) (xy 2.372744 -208.196417)
			(xy 2.423177 -208.24685) (xy 2.467646 -208.302612) (xy 2.505592 -208.363003) (xy 2.536537 -208.427262)
			(xy 2.560094 -208.494582) (xy 2.575964 -208.564117) (xy 2.58395 -208.634991) (xy 2.58395 -208.706313)
			(xy 2.575964 -208.777187) (xy 2.560094 -208.846722) (xy 2.536537 -208.914042) (xy 2.505592 -208.978301)
			(xy 2.467646 -209.038692) (xy 2.423177 -209.094454) (xy 2.372744 -209.144887) (xy 2.316982 -209.189356)
			(xy 2.256591 -209.227302) (xy 2.192332 -209.258247) (xy 2.125012 -209.281804) (xy 2.055477 -209.297674)
			(xy 1.984603 -209.30566) (xy 1.913281 -209.30566) (xy 1.842407 -209.297674) (xy 1.772872 -209.281804)
			(xy 1.705552 -209.258247) (xy 1.641293 -209.227302) (xy 1.580902 -209.189356) (xy 1.52514 -209.144887)
			(xy 1.474707 -209.094454) (xy 1.430238 -209.038692) (xy 1.392292 -208.978301) (xy 1.361347 -208.914042)
			(xy 1.33779 -208.846722) (xy 1.32192 -208.777187) (xy 1.313934 -208.706313) (xy 0.509016 -208.706313)
			(xy 0.509016 -210.706309) (xy 1.313934 -210.706309) (xy 1.313934 -210.634987) (xy 1.32192 -210.564113)
			(xy 1.33779 -210.494578) (xy 1.361347 -210.427258) (xy 1.392292 -210.362999) (xy 1.430238 -210.302608)
			(xy 1.474707 -210.246846) (xy 1.52514 -210.196413) (xy 1.580902 -210.151944) (xy 1.641293 -210.113998)
			(xy 1.705552 -210.083053) (xy 1.772872 -210.059496) (xy 1.842407 -210.043626) (xy 1.913281 -210.03564)
			(xy 1.948942 -210.03514) (xy 1.984603 -210.03564) (xy 2.055477 -210.043626) (xy 2.125012 -210.059496)
			(xy 2.192332 -210.083053) (xy 2.256591 -210.113998) (xy 2.316982 -210.151944) (xy 2.372744 -210.196413)
			(xy 2.423177 -210.246846) (xy 2.467646 -210.302608) (xy 2.505592 -210.362999) (xy 2.536537 -210.427258)
			(xy 2.560094 -210.494578) (xy 2.575964 -210.564113) (xy 2.58395 -210.634987) (xy 2.58395 -210.706309)
			(xy 2.575964 -210.777183) (xy 2.560094 -210.846718) (xy 2.536537 -210.914038) (xy 2.505592 -210.978297)
			(xy 2.467646 -211.038688) (xy 2.423177 -211.09445) (xy 2.372744 -211.144883) (xy 2.316982 -211.189352)
			(xy 2.256591 -211.227298) (xy 2.192332 -211.258243) (xy 2.125012 -211.2818) (xy 2.055477 -211.29767)
			(xy 1.984603 -211.305656) (xy 1.913281 -211.305656) (xy 1.842407 -211.29767) (xy 1.772872 -211.2818)
			(xy 1.705552 -211.258243) (xy 1.641293 -211.227298) (xy 1.580902 -211.189352) (xy 1.52514 -211.144883)
			(xy 1.474707 -211.09445) (xy 1.430238 -211.038688) (xy 1.392292 -210.978297) (xy 1.361347 -210.914038)
			(xy 1.33779 -210.846718) (xy 1.32192 -210.777183) (xy 1.313934 -210.706309) (xy 0.509016 -210.706309)
			(xy 0.509016 -211.706307) (xy 3.31393 -211.706307) (xy 3.31393 -211.634985) (xy 3.321916 -211.564111)
			(xy 3.337786 -211.494576) (xy 3.361343 -211.427256) (xy 3.392288 -211.362997) (xy 3.430234 -211.302606)
			(xy 3.474703 -211.246844) (xy 3.525136 -211.196411) (xy 3.580898 -211.151942) (xy 3.641289 -211.113996)
			(xy 3.705548 -211.083051) (xy 3.772868 -211.059494) (xy 3.842403 -211.043624) (xy 3.913277 -211.035638)
			(xy 3.948938 -211.035138) (xy 3.984599 -211.035638) (xy 4.055473 -211.043624) (xy 4.125008 -211.059494)
			(xy 4.192328 -211.083051) (xy 4.256587 -211.113996) (xy 4.316978 -211.151942) (xy 4.37274 -211.196411)
			(xy 4.423173 -211.246844) (xy 4.467642 -211.302606) (xy 4.505588 -211.362997) (xy 4.536533 -211.427256)
			(xy 4.56009 -211.494576) (xy 4.57596 -211.564111) (xy 4.583946 -211.634985) (xy 4.583946 -211.706307)
			(xy 4.57596 -211.777181) (xy 4.56009 -211.846716) (xy 4.536533 -211.914036) (xy 4.505588 -211.978295)
			(xy 4.467642 -212.038686) (xy 4.423173 -212.094448) (xy 4.37274 -212.144881) (xy 4.316978 -212.18935)
			(xy 4.256587 -212.227296) (xy 4.192328 -212.258241) (xy 4.125008 -212.281798) (xy 4.055473 -212.297668)
			(xy 3.984599 -212.305654) (xy 3.913277 -212.305654) (xy 3.842403 -212.297668) (xy 3.772868 -212.281798)
			(xy 3.705548 -212.258241) (xy 3.641289 -212.227296) (xy 3.580898 -212.18935) (xy 3.525136 -212.144881)
			(xy 3.474703 -212.094448) (xy 3.430234 -212.038686) (xy 3.392288 -211.978295) (xy 3.361343 -211.914036)
			(xy 3.337786 -211.846716) (xy 3.321916 -211.777181) (xy 3.31393 -211.706307) (xy 0.509016 -211.706307)
			(xy 0.509016 -212.706305) (xy 1.313934 -212.706305) (xy 1.313934 -212.634983) (xy 1.32192 -212.564109)
			(xy 1.33779 -212.494574) (xy 1.361347 -212.427254) (xy 1.392292 -212.362995) (xy 1.430238 -212.302604)
			(xy 1.474707 -212.246842) (xy 1.52514 -212.196409) (xy 1.580902 -212.15194) (xy 1.641293 -212.113994)
			(xy 1.705552 -212.083049) (xy 1.772872 -212.059492) (xy 1.842407 -212.043622) (xy 1.913281 -212.035636)
			(xy 1.948942 -212.035136) (xy 1.984603 -212.035636) (xy 2.055477 -212.043622) (xy 2.125012 -212.059492)
			(xy 2.192332 -212.083049) (xy 2.256591 -212.113994) (xy 2.316982 -212.15194) (xy 2.372744 -212.196409)
			(xy 2.423177 -212.246842) (xy 2.467646 -212.302604) (xy 2.505592 -212.362995) (xy 2.536537 -212.427254)
			(xy 2.560094 -212.494574) (xy 2.575964 -212.564109) (xy 2.58395 -212.634983) (xy 2.58395 -212.706305)
			(xy 2.575964 -212.777179) (xy 2.560094 -212.846714) (xy 2.536537 -212.914034) (xy 2.505592 -212.978293)
			(xy 2.467646 -213.038684) (xy 2.423177 -213.094446) (xy 2.372744 -213.144879) (xy 2.316982 -213.189348)
			(xy 2.256591 -213.227294) (xy 2.192332 -213.258239) (xy 2.125012 -213.281796) (xy 2.055477 -213.297666)
			(xy 1.984603 -213.305652) (xy 1.913281 -213.305652) (xy 1.842407 -213.297666) (xy 1.772872 -213.281796)
			(xy 1.705552 -213.258239) (xy 1.641293 -213.227294) (xy 1.580902 -213.189348) (xy 1.52514 -213.144879)
			(xy 1.474707 -213.094446) (xy 1.430238 -213.038684) (xy 1.392292 -212.978293) (xy 1.361347 -212.914034)
			(xy 1.33779 -212.846714) (xy 1.32192 -212.777179) (xy 1.313934 -212.706305) (xy 0.509016 -212.706305)
			(xy 0.509016 -213.706303) (xy 3.31393 -213.706303) (xy 3.31393 -213.634981) (xy 3.321916 -213.564107)
			(xy 3.337786 -213.494572) (xy 3.361343 -213.427252) (xy 3.392288 -213.362993) (xy 3.430234 -213.302602)
			(xy 3.474703 -213.24684) (xy 3.525136 -213.196407) (xy 3.580898 -213.151938) (xy 3.641289 -213.113992)
			(xy 3.705548 -213.083047) (xy 3.772868 -213.05949) (xy 3.842403 -213.04362) (xy 3.913277 -213.035634)
			(xy 3.948938 -213.035134) (xy 3.984599 -213.035634) (xy 4.055473 -213.04362) (xy 4.125008 -213.05949)
			(xy 4.192328 -213.083047) (xy 4.256587 -213.113992) (xy 4.316978 -213.151938) (xy 4.37274 -213.196407)
			(xy 4.423173 -213.24684) (xy 4.467642 -213.302602) (xy 4.505588 -213.362993) (xy 4.536533 -213.427252)
			(xy 4.56009 -213.494572) (xy 4.57596 -213.564107) (xy 4.583946 -213.634981) (xy 4.583946 -213.706303)
			(xy 4.57596 -213.777177) (xy 4.56009 -213.846712) (xy 4.536533 -213.914032) (xy 4.505588 -213.978291)
			(xy 4.467642 -214.038682) (xy 4.423173 -214.094444) (xy 4.37274 -214.144877) (xy 4.316978 -214.189346)
			(xy 4.256587 -214.227292) (xy 4.192328 -214.258237) (xy 4.125008 -214.281794) (xy 4.055473 -214.297664)
			(xy 3.984599 -214.30565) (xy 3.913277 -214.30565) (xy 3.842403 -214.297664) (xy 3.772868 -214.281794)
			(xy 3.705548 -214.258237) (xy 3.641289 -214.227292) (xy 3.580898 -214.189346) (xy 3.525136 -214.144877)
			(xy 3.474703 -214.094444) (xy 3.430234 -214.038682) (xy 3.392288 -213.978291) (xy 3.361343 -213.914032)
			(xy 3.337786 -213.846712) (xy 3.321916 -213.777177) (xy 3.31393 -213.706303) (xy 0.509016 -213.706303)
			(xy 0.509016 -214.706301) (xy 1.313934 -214.706301) (xy 1.313934 -214.634979) (xy 1.32192 -214.564105)
			(xy 1.33779 -214.49457) (xy 1.361347 -214.42725) (xy 1.392292 -214.362991) (xy 1.430238 -214.3026)
			(xy 1.474707 -214.246838) (xy 1.52514 -214.196405) (xy 1.580902 -214.151936) (xy 1.641293 -214.11399)
			(xy 1.705552 -214.083045) (xy 1.772872 -214.059488) (xy 1.842407 -214.043618) (xy 1.913281 -214.035632)
			(xy 1.948942 -214.035132) (xy 1.984603 -214.035632) (xy 2.055477 -214.043618) (xy 2.125012 -214.059488)
			(xy 2.192332 -214.083045) (xy 2.256591 -214.11399) (xy 2.316982 -214.151936) (xy 2.372744 -214.196405)
			(xy 2.423177 -214.246838) (xy 2.467646 -214.3026) (xy 2.505592 -214.362991) (xy 2.536537 -214.42725)
			(xy 2.560094 -214.49457) (xy 2.575964 -214.564105) (xy 2.58395 -214.634979) (xy 2.58395 -214.706301)
			(xy 7.813794 -214.706301) (xy 7.813794 -214.634979) (xy 7.82178 -214.564105) (xy 7.83765 -214.49457)
			(xy 7.861207 -214.42725) (xy 7.892152 -214.362991) (xy 7.930098 -214.3026) (xy 7.974567 -214.246838)
			(xy 8.025 -214.196405) (xy 8.080762 -214.151936) (xy 8.141153 -214.11399) (xy 8.205412 -214.083045)
			(xy 8.272732 -214.059488) (xy 8.342267 -214.043618) (xy 8.413141 -214.035632) (xy 8.448802 -214.035132)
			(xy 8.484463 -214.035632) (xy 8.555337 -214.043618) (xy 8.624872 -214.059488) (xy 8.692192 -214.083045)
			(xy 8.756451 -214.11399) (xy 8.816842 -214.151936) (xy 8.872604 -214.196405) (xy 8.923037 -214.246838)
			(xy 8.967506 -214.3026) (xy 9.005452 -214.362991) (xy 9.036397 -214.42725) (xy 9.059954 -214.49457)
			(xy 9.075824 -214.564105) (xy 9.08381 -214.634979) (xy 9.08381 -214.706301) (xy 9.075824 -214.777175)
			(xy 9.059954 -214.84671) (xy 9.036397 -214.91403) (xy 9.005452 -214.978289) (xy 8.967506 -215.03868)
			(xy 8.923037 -215.094442) (xy 8.872604 -215.144875) (xy 8.816842 -215.189344) (xy 8.756451 -215.22729)
			(xy 8.692192 -215.258235) (xy 8.624872 -215.281792) (xy 8.555337 -215.297662) (xy 8.484463 -215.305648)
			(xy 8.413141 -215.305648) (xy 8.342267 -215.297662) (xy 8.272732 -215.281792) (xy 8.205412 -215.258235)
			(xy 8.141153 -215.22729) (xy 8.080762 -215.189344) (xy 8.025 -215.144875) (xy 7.974567 -215.094442)
			(xy 7.930098 -215.03868) (xy 7.892152 -214.978289) (xy 7.861207 -214.91403) (xy 7.83765 -214.84671)
			(xy 7.82178 -214.777175) (xy 7.813794 -214.706301) (xy 2.58395 -214.706301) (xy 2.575964 -214.777175)
			(xy 2.560094 -214.84671) (xy 2.536537 -214.91403) (xy 2.505592 -214.978289) (xy 2.467646 -215.03868)
			(xy 2.423177 -215.094442) (xy 2.372744 -215.144875) (xy 2.316982 -215.189344) (xy 2.256591 -215.22729)
			(xy 2.192332 -215.258235) (xy 2.125012 -215.281792) (xy 2.055477 -215.297662) (xy 1.984603 -215.305648)
			(xy 1.913281 -215.305648) (xy 1.842407 -215.297662) (xy 1.772872 -215.281792) (xy 1.705552 -215.258235)
			(xy 1.641293 -215.22729) (xy 1.580902 -215.189344) (xy 1.52514 -215.144875) (xy 1.474707 -215.094442)
			(xy 1.430238 -215.03868) (xy 1.392292 -214.978289) (xy 1.361347 -214.91403) (xy 1.33779 -214.84671)
			(xy 1.32192 -214.777175) (xy 1.313934 -214.706301) (xy 0.509016 -214.706301) (xy 0.509016 -215.706299)
			(xy 3.31393 -215.706299) (xy 3.31393 -215.634977) (xy 3.321916 -215.564103) (xy 3.337786 -215.494568)
			(xy 3.361343 -215.427248) (xy 3.392288 -215.362989) (xy 3.430234 -215.302598) (xy 3.474703 -215.246836)
			(xy 3.525136 -215.196403) (xy 3.580898 -215.151934) (xy 3.641289 -215.113988) (xy 3.705548 -215.083043)
			(xy 3.772868 -215.059486) (xy 3.842403 -215.043616) (xy 3.913277 -215.03563) (xy 3.948938 -215.03513)
			(xy 3.984599 -215.03563) (xy 4.055473 -215.043616) (xy 4.125008 -215.059486) (xy 4.192328 -215.083043)
			(xy 4.256587 -215.113988) (xy 4.316978 -215.151934) (xy 4.37274 -215.196403) (xy 4.423173 -215.246836)
			(xy 4.467642 -215.302598) (xy 4.505588 -215.362989) (xy 4.536533 -215.427248) (xy 4.56009 -215.494568)
			(xy 4.57596 -215.564103) (xy 4.583946 -215.634977) (xy 4.583946 -215.706299) (xy 5.813798 -215.706299)
			(xy 5.813798 -215.634977) (xy 5.821784 -215.564103) (xy 5.837654 -215.494568) (xy 5.861211 -215.427248)
			(xy 5.892156 -215.362989) (xy 5.930102 -215.302598) (xy 5.974571 -215.246836) (xy 6.025004 -215.196403)
			(xy 6.080766 -215.151934) (xy 6.141157 -215.113988) (xy 6.205416 -215.083043) (xy 6.272736 -215.059486)
			(xy 6.342271 -215.043616) (xy 6.413145 -215.03563) (xy 6.448806 -215.03513) (xy 6.484467 -215.03563)
			(xy 6.555341 -215.043616) (xy 6.624876 -215.059486) (xy 6.692196 -215.083043) (xy 6.756455 -215.113988)
			(xy 6.816846 -215.151934) (xy 6.872608 -215.196403) (xy 6.923041 -215.246836) (xy 6.96751 -215.302598)
			(xy 7.005456 -215.362989) (xy 7.036401 -215.427248) (xy 7.059958 -215.494568) (xy 7.075828 -215.564103)
			(xy 7.083814 -215.634977) (xy 7.083814 -215.706299) (xy 7.075828 -215.777173) (xy 7.059958 -215.846708)
			(xy 7.036401 -215.914028) (xy 7.005456 -215.978287) (xy 6.96751 -216.038678) (xy 6.923041 -216.09444)
			(xy 6.872608 -216.144873) (xy 6.816846 -216.189342) (xy 6.756455 -216.227288) (xy 6.692196 -216.258233)
			(xy 6.624876 -216.28179) (xy 6.555341 -216.29766) (xy 6.484467 -216.305646) (xy 6.413145 -216.305646)
			(xy 6.342271 -216.29766) (xy 6.272736 -216.28179) (xy 6.205416 -216.258233) (xy 6.141157 -216.227288)
			(xy 6.080766 -216.189342) (xy 6.025004 -216.144873) (xy 5.974571 -216.09444) (xy 5.930102 -216.038678)
			(xy 5.892156 -215.978287) (xy 5.861211 -215.914028) (xy 5.837654 -215.846708) (xy 5.821784 -215.777173)
			(xy 5.813798 -215.706299) (xy 4.583946 -215.706299) (xy 4.57596 -215.777173) (xy 4.56009 -215.846708)
			(xy 4.536533 -215.914028) (xy 4.505588 -215.978287) (xy 4.467642 -216.038678) (xy 4.423173 -216.09444)
			(xy 4.37274 -216.144873) (xy 4.316978 -216.189342) (xy 4.256587 -216.227288) (xy 4.192328 -216.258233)
			(xy 4.125008 -216.28179) (xy 4.055473 -216.29766) (xy 3.984599 -216.305646) (xy 3.913277 -216.305646)
			(xy 3.842403 -216.29766) (xy 3.772868 -216.28179) (xy 3.705548 -216.258233) (xy 3.641289 -216.227288)
			(xy 3.580898 -216.189342) (xy 3.525136 -216.144873) (xy 3.474703 -216.09444) (xy 3.430234 -216.038678)
			(xy 3.392288 -215.978287) (xy 3.361343 -215.914028) (xy 3.337786 -215.846708) (xy 3.321916 -215.777173)
			(xy 3.31393 -215.706299) (xy 0.509016 -215.706299) (xy 0.509016 -217.706295) (xy 3.31393 -217.706295)
			(xy 3.31393 -217.634973) (xy 3.321916 -217.564099) (xy 3.337786 -217.494564) (xy 3.361343 -217.427244)
			(xy 3.392288 -217.362985) (xy 3.430234 -217.302594) (xy 3.474703 -217.246832) (xy 3.525136 -217.196399)
			(xy 3.580898 -217.15193) (xy 3.641289 -217.113984) (xy 3.705548 -217.083039) (xy 3.772868 -217.059482)
			(xy 3.842403 -217.043612) (xy 3.913277 -217.035626) (xy 3.948938 -217.035126) (xy 3.984599 -217.035626)
			(xy 4.055473 -217.043612) (xy 4.125008 -217.059482) (xy 4.192328 -217.083039) (xy 4.256587 -217.113984)
			(xy 4.316978 -217.15193) (xy 4.37274 -217.196399) (xy 4.423173 -217.246832) (xy 4.467642 -217.302594)
			(xy 4.505588 -217.362985) (xy 4.536533 -217.427244) (xy 4.56009 -217.494564) (xy 4.57596 -217.564099)
			(xy 4.583946 -217.634973) (xy 4.583946 -217.706295) (xy 5.813798 -217.706295) (xy 5.813798 -217.634973)
			(xy 5.821784 -217.564099) (xy 5.837654 -217.494564) (xy 5.861211 -217.427244) (xy 5.892156 -217.362985)
			(xy 5.930102 -217.302594) (xy 5.974571 -217.246832) (xy 6.025004 -217.196399) (xy 6.080766 -217.15193)
			(xy 6.141157 -217.113984) (xy 6.205416 -217.083039) (xy 6.272736 -217.059482) (xy 6.342271 -217.043612)
			(xy 6.413145 -217.035626) (xy 6.448806 -217.035126) (xy 6.484467 -217.035626) (xy 6.555341 -217.043612)
			(xy 6.624876 -217.059482) (xy 6.692196 -217.083039) (xy 6.756455 -217.113984) (xy 6.816846 -217.15193)
			(xy 6.872608 -217.196399) (xy 6.923041 -217.246832) (xy 6.96751 -217.302594) (xy 7.005456 -217.362985)
			(xy 7.036401 -217.427244) (xy 7.059958 -217.494564) (xy 7.075828 -217.564099) (xy 7.083814 -217.634973)
			(xy 7.083814 -217.706295) (xy 7.075828 -217.777169) (xy 7.059958 -217.846704) (xy 7.036401 -217.914024)
			(xy 7.005456 -217.978283) (xy 6.96751 -218.038674) (xy 6.923041 -218.094436) (xy 6.872608 -218.144869)
			(xy 6.816846 -218.189338) (xy 6.756455 -218.227284) (xy 6.692196 -218.258229) (xy 6.624876 -218.281786)
			(xy 6.555341 -218.297656) (xy 6.484467 -218.305642) (xy 6.413145 -218.305642) (xy 6.342271 -218.297656)
			(xy 6.272736 -218.281786) (xy 6.205416 -218.258229) (xy 6.141157 -218.227284) (xy 6.080766 -218.189338)
			(xy 6.025004 -218.144869) (xy 5.974571 -218.094436) (xy 5.930102 -218.038674) (xy 5.892156 -217.978283)
			(xy 5.861211 -217.914024) (xy 5.837654 -217.846704) (xy 5.821784 -217.777169) (xy 5.813798 -217.706295)
			(xy 4.583946 -217.706295) (xy 4.57596 -217.777169) (xy 4.56009 -217.846704) (xy 4.536533 -217.914024)
			(xy 4.505588 -217.978283) (xy 4.467642 -218.038674) (xy 4.423173 -218.094436) (xy 4.37274 -218.144869)
			(xy 4.316978 -218.189338) (xy 4.256587 -218.227284) (xy 4.192328 -218.258229) (xy 4.125008 -218.281786)
			(xy 4.055473 -218.297656) (xy 3.984599 -218.305642) (xy 3.913277 -218.305642) (xy 3.842403 -218.297656)
			(xy 3.772868 -218.281786) (xy 3.705548 -218.258229) (xy 3.641289 -218.227284) (xy 3.580898 -218.189338)
			(xy 3.525136 -218.144869) (xy 3.474703 -218.094436) (xy 3.430234 -218.038674) (xy 3.392288 -217.978283)
			(xy 3.361343 -217.914024) (xy 3.337786 -217.846704) (xy 3.321916 -217.777169) (xy 3.31393 -217.706295)
			(xy 0.509016 -217.706295) (xy 0.509016 -218.706293) (xy 1.313934 -218.706293) (xy 1.313934 -218.634971)
			(xy 1.32192 -218.564097) (xy 1.33779 -218.494562) (xy 1.361347 -218.427242) (xy 1.392292 -218.362983)
			(xy 1.430238 -218.302592) (xy 1.474707 -218.24683) (xy 1.52514 -218.196397) (xy 1.580902 -218.151928)
			(xy 1.641293 -218.113982) (xy 1.705552 -218.083037) (xy 1.772872 -218.05948) (xy 1.842407 -218.04361)
			(xy 1.913281 -218.035624) (xy 1.948942 -218.035124) (xy 1.984603 -218.035624) (xy 2.055477 -218.04361)
			(xy 2.125012 -218.05948) (xy 2.192332 -218.083037) (xy 2.256591 -218.113982) (xy 2.316982 -218.151928)
			(xy 2.372744 -218.196397) (xy 2.423177 -218.24683) (xy 2.467646 -218.302592) (xy 2.505592 -218.362983)
			(xy 2.536537 -218.427242) (xy 2.560094 -218.494562) (xy 2.575964 -218.564097) (xy 2.58395 -218.634971)
			(xy 2.58395 -218.706293) (xy 7.813794 -218.706293) (xy 7.813794 -218.634971) (xy 7.82178 -218.564097)
			(xy 7.83765 -218.494562) (xy 7.861207 -218.427242) (xy 7.892152 -218.362983) (xy 7.930098 -218.302592)
			(xy 7.974567 -218.24683) (xy 8.025 -218.196397) (xy 8.080762 -218.151928) (xy 8.141153 -218.113982)
			(xy 8.205412 -218.083037) (xy 8.272732 -218.05948) (xy 8.342267 -218.04361) (xy 8.413141 -218.035624)
			(xy 8.448802 -218.035124) (xy 8.484463 -218.035624) (xy 8.555337 -218.04361) (xy 8.624872 -218.05948)
			(xy 8.692192 -218.083037) (xy 8.756451 -218.113982) (xy 8.816842 -218.151928) (xy 8.872604 -218.196397)
			(xy 8.923037 -218.24683) (xy 8.967506 -218.302592) (xy 9.005452 -218.362983) (xy 9.036397 -218.427242)
			(xy 9.059954 -218.494562) (xy 9.075824 -218.564097) (xy 9.08381 -218.634971) (xy 9.08381 -218.706293)
			(xy 9.075824 -218.777167) (xy 9.059954 -218.846702) (xy 9.036397 -218.914022) (xy 9.005452 -218.978281)
			(xy 8.967506 -219.038672) (xy 8.923037 -219.094434) (xy 8.872604 -219.144867) (xy 8.816842 -219.189336)
			(xy 8.756451 -219.227282) (xy 8.692192 -219.258227) (xy 8.624872 -219.281784) (xy 8.555337 -219.297654)
			(xy 8.484463 -219.30564) (xy 8.413141 -219.30564) (xy 8.342267 -219.297654) (xy 8.272732 -219.281784)
			(xy 8.205412 -219.258227) (xy 8.141153 -219.227282) (xy 8.080762 -219.189336) (xy 8.025 -219.144867)
			(xy 7.974567 -219.094434) (xy 7.930098 -219.038672) (xy 7.892152 -218.978281) (xy 7.861207 -218.914022)
			(xy 7.83765 -218.846702) (xy 7.82178 -218.777167) (xy 7.813794 -218.706293) (xy 2.58395 -218.706293)
			(xy 2.575964 -218.777167) (xy 2.560094 -218.846702) (xy 2.536537 -218.914022) (xy 2.505592 -218.978281)
			(xy 2.467646 -219.038672) (xy 2.423177 -219.094434) (xy 2.372744 -219.144867) (xy 2.316982 -219.189336)
			(xy 2.256591 -219.227282) (xy 2.192332 -219.258227) (xy 2.125012 -219.281784) (xy 2.055477 -219.297654)
			(xy 1.984603 -219.30564) (xy 1.913281 -219.30564) (xy 1.842407 -219.297654) (xy 1.772872 -219.281784)
			(xy 1.705552 -219.258227) (xy 1.641293 -219.227282) (xy 1.580902 -219.189336) (xy 1.52514 -219.144867)
			(xy 1.474707 -219.094434) (xy 1.430238 -219.038672) (xy 1.392292 -218.978281) (xy 1.361347 -218.914022)
			(xy 1.33779 -218.846702) (xy 1.32192 -218.777167) (xy 1.313934 -218.706293) (xy 0.509016 -218.706293)
			(xy 0.509016 -219.706291) (xy 5.813798 -219.706291) (xy 5.813798 -219.634969) (xy 5.821784 -219.564095)
			(xy 5.837654 -219.49456) (xy 5.861211 -219.42724) (xy 5.892156 -219.362981) (xy 5.930102 -219.30259)
			(xy 5.974571 -219.246828) (xy 6.025004 -219.196395) (xy 6.080766 -219.151926) (xy 6.141157 -219.11398)
			(xy 6.205416 -219.083035) (xy 6.272736 -219.059478) (xy 6.342271 -219.043608) (xy 6.413145 -219.035622)
			(xy 6.448806 -219.035122) (xy 6.484467 -219.035622) (xy 6.555341 -219.043608) (xy 6.624876 -219.059478)
			(xy 6.692196 -219.083035) (xy 6.756455 -219.11398) (xy 6.816846 -219.151926) (xy 6.872608 -219.196395)
			(xy 6.923041 -219.246828) (xy 6.96751 -219.30259) (xy 7.005456 -219.362981) (xy 7.036401 -219.42724)
			(xy 7.059958 -219.49456) (xy 7.075828 -219.564095) (xy 7.083814 -219.634969) (xy 7.083814 -219.706291)
			(xy 7.075828 -219.777165) (xy 7.059958 -219.8467) (xy 7.036401 -219.91402) (xy 7.005459 -219.978273)
			(xy 11.666408 -219.978273) (xy 11.673867 -219.907485) (xy 11.689185 -219.837973) (xy 11.71217 -219.770606)
			(xy 11.742535 -219.706228) (xy 11.7799 -219.645644) (xy 11.823798 -219.589611) (xy 11.873678 -219.538832)
			(xy 11.928917 -219.493941) (xy 11.988825 -219.4555) (xy 12.05265 -219.42399) (xy 12.119596 -219.399805)
			(xy 12.188823 -219.383248) (xy 12.259467 -219.374526) (xy 12.330643 -219.373748) (xy 12.40146 -219.380924)
			(xy 12.471033 -219.395963) (xy 12.538491 -219.418679) (xy 12.60299 -219.448786) (xy 12.663724 -219.485908)
			(xy 12.719931 -219.529581) (xy 12.77091 -219.579258) (xy 12.816021 -219.634317) (xy 12.854702 -219.69407)
			(xy 12.886467 -219.757769) (xy 12.91092 -219.824617) (xy 12.927754 -219.893777) (xy 12.936759 -219.964386)
			(xy 12.937822 -220.035558) (xy 12.93093 -220.106403) (xy 12.916168 -220.176036) (xy 12.893723 -220.243584)
			(xy 12.863874 -220.308203) (xy 12.826996 -220.369085) (xy 12.805664 -220.397578) (xy 12.827608 -220.425602)
			(xy 12.86581 -220.485663) (xy 12.897064 -220.549614) (xy 12.920981 -220.616656) (xy 12.937261 -220.685949)
			(xy 12.9457 -220.756628) (xy 12.946194 -220.827806) (xy 12.938735 -220.898594) (xy 12.923417 -220.968107)
			(xy 12.900431 -221.035474) (xy 12.870066 -221.099852) (xy 12.832701 -221.160437) (xy 12.788804 -221.216469)
			(xy 12.738923 -221.267249) (xy 12.683684 -221.31214) (xy 12.623776 -221.350581) (xy 12.55995 -221.382091)
			(xy 12.493005 -221.406276) (xy 12.423777 -221.422833) (xy 12.353133 -221.431555) (xy 12.281957 -221.432333)
			(xy 12.21114 -221.425158) (xy 12.141567 -221.410118) (xy 12.074108 -221.387402) (xy 12.009609 -221.357295)
			(xy 11.948875 -221.320173) (xy 11.892668 -221.2765) (xy 11.841689 -221.226823) (xy 11.796577 -221.171763)
			(xy 11.757897 -221.11201) (xy 11.726131 -221.048311) (xy 11.701679 -220.981463) (xy 11.684845 -220.912302)
			(xy 11.67584 -220.841693) (xy 11.674777 -220.770521) (xy 11.681669 -220.699675) (xy 11.696431 -220.630043)
			(xy 11.718876 -220.562494) (xy 11.748725 -220.497875) (xy 11.785604 -220.436993) (xy 11.806936 -220.4085)
			(xy 11.784992 -220.380476) (xy 11.746791 -220.320415) (xy 11.715537 -220.256464) (xy 11.69162 -220.189422)
			(xy 11.67534 -220.120129) (xy 11.666901 -220.049451) (xy 11.666408 -219.978273) (xy 7.005459 -219.978273)
			(xy 7.005456 -219.978279) (xy 6.96751 -220.03867) (xy 6.923041 -220.094432) (xy 6.872608 -220.144865)
			(xy 6.816846 -220.189334) (xy 6.756455 -220.22728) (xy 6.692196 -220.258225) (xy 6.624876 -220.281782)
			(xy 6.555341 -220.297652) (xy 6.484467 -220.305638) (xy 6.413145 -220.305638) (xy 6.342271 -220.297652)
			(xy 6.272736 -220.281782) (xy 6.205416 -220.258225) (xy 6.141157 -220.22728) (xy 6.080766 -220.189334)
			(xy 6.025004 -220.144865) (xy 5.974571 -220.094432) (xy 5.930102 -220.03867) (xy 5.892156 -219.978279)
			(xy 5.861211 -219.91402) (xy 5.837654 -219.8467) (xy 5.821784 -219.777165) (xy 5.813798 -219.706291)
			(xy 0.509016 -219.706291) (xy 0.509016 -220.706289) (xy 1.313934 -220.706289) (xy 1.313934 -220.634967)
			(xy 1.32192 -220.564093) (xy 1.33779 -220.494558) (xy 1.361347 -220.427238) (xy 1.392292 -220.362979)
			(xy 1.430238 -220.302588) (xy 1.474707 -220.246826) (xy 1.52514 -220.196393) (xy 1.580902 -220.151924)
			(xy 1.641293 -220.113978) (xy 1.705552 -220.083033) (xy 1.772872 -220.059476) (xy 1.842407 -220.043606)
			(xy 1.913281 -220.03562) (xy 1.948942 -220.03512) (xy 1.984603 -220.03562) (xy 2.055477 -220.043606)
			(xy 2.125012 -220.059476) (xy 2.192332 -220.083033) (xy 2.256591 -220.113978) (xy 2.316982 -220.151924)
			(xy 2.372744 -220.196393) (xy 2.423177 -220.246826) (xy 2.467646 -220.302588) (xy 2.505592 -220.362979)
			(xy 2.536537 -220.427238) (xy 2.560094 -220.494558) (xy 2.575964 -220.564093) (xy 2.58395 -220.634967)
			(xy 2.58395 -220.706289) (xy 7.813794 -220.706289) (xy 7.813794 -220.634967) (xy 7.82178 -220.564093)
			(xy 7.83765 -220.494558) (xy 7.861207 -220.427238) (xy 7.892152 -220.362979) (xy 7.930098 -220.302588)
			(xy 7.974567 -220.246826) (xy 8.025 -220.196393) (xy 8.080762 -220.151924) (xy 8.141153 -220.113978)
			(xy 8.205412 -220.083033) (xy 8.272732 -220.059476) (xy 8.342267 -220.043606) (xy 8.413141 -220.03562)
			(xy 8.448802 -220.03512) (xy 8.484463 -220.03562) (xy 8.555337 -220.043606) (xy 8.624872 -220.059476)
			(xy 8.692192 -220.083033) (xy 8.756451 -220.113978) (xy 8.816842 -220.151924) (xy 8.872604 -220.196393)
			(xy 8.923037 -220.246826) (xy 8.967506 -220.302588) (xy 9.005452 -220.362979) (xy 9.036397 -220.427238)
			(xy 9.059954 -220.494558) (xy 9.075824 -220.564093) (xy 9.08381 -220.634967) (xy 9.08381 -220.706289)
			(xy 9.075824 -220.777163) (xy 9.059954 -220.846698) (xy 9.036397 -220.914018) (xy 9.005452 -220.978277)
			(xy 8.967506 -221.038668) (xy 8.923037 -221.09443) (xy 8.872604 -221.144863) (xy 8.816842 -221.189332)
			(xy 8.756451 -221.227278) (xy 8.692192 -221.258223) (xy 8.624872 -221.28178) (xy 8.555337 -221.29765)
			(xy 8.484463 -221.305636) (xy 8.413141 -221.305636) (xy 8.342267 -221.29765) (xy 8.272732 -221.28178)
			(xy 8.205412 -221.258223) (xy 8.141153 -221.227278) (xy 8.080762 -221.189332) (xy 8.025 -221.144863)
			(xy 7.974567 -221.09443) (xy 7.930098 -221.038668) (xy 7.892152 -220.978277) (xy 7.861207 -220.914018)
			(xy 7.83765 -220.846698) (xy 7.82178 -220.777163) (xy 7.813794 -220.706289) (xy 2.58395 -220.706289)
			(xy 2.575964 -220.777163) (xy 2.560094 -220.846698) (xy 2.536537 -220.914018) (xy 2.505592 -220.978277)
			(xy 2.467646 -221.038668) (xy 2.423177 -221.09443) (xy 2.372744 -221.144863) (xy 2.316982 -221.189332)
			(xy 2.256591 -221.227278) (xy 2.192332 -221.258223) (xy 2.125012 -221.28178) (xy 2.055477 -221.29765)
			(xy 1.984603 -221.305636) (xy 1.913281 -221.305636) (xy 1.842407 -221.29765) (xy 1.772872 -221.28178)
			(xy 1.705552 -221.258223) (xy 1.641293 -221.227278) (xy 1.580902 -221.189332) (xy 1.52514 -221.144863)
			(xy 1.474707 -221.09443) (xy 1.430238 -221.038668) (xy 1.392292 -220.978277) (xy 1.361347 -220.914018)
			(xy 1.33779 -220.846698) (xy 1.32192 -220.777163) (xy 1.313934 -220.706289) (xy 0.509016 -220.706289)
			(xy 0.509016 -221.706287) (xy 3.31393 -221.706287) (xy 3.31393 -221.634965) (xy 3.321916 -221.564091)
			(xy 3.337786 -221.494556) (xy 3.361343 -221.427236) (xy 3.392288 -221.362977) (xy 3.430234 -221.302586)
			(xy 3.474703 -221.246824) (xy 3.525136 -221.196391) (xy 3.580898 -221.151922) (xy 3.641289 -221.113976)
			(xy 3.705548 -221.083031) (xy 3.772868 -221.059474) (xy 3.842403 -221.043604) (xy 3.913277 -221.035618)
			(xy 3.948938 -221.035118) (xy 3.984599 -221.035618) (xy 4.055473 -221.043604) (xy 4.125008 -221.059474)
			(xy 4.192328 -221.083031) (xy 4.256587 -221.113976) (xy 4.316978 -221.151922) (xy 4.37274 -221.196391)
			(xy 4.423173 -221.246824) (xy 4.467642 -221.302586) (xy 4.505588 -221.362977) (xy 4.536533 -221.427236)
			(xy 4.56009 -221.494556) (xy 4.57596 -221.564091) (xy 4.583946 -221.634965) (xy 4.583946 -221.706287)
			(xy 4.57596 -221.777161) (xy 4.56009 -221.846696) (xy 4.536533 -221.914016) (xy 4.505588 -221.978275)
			(xy 4.467642 -222.038666) (xy 4.423173 -222.094428) (xy 4.37274 -222.144861) (xy 4.316978 -222.18933)
			(xy 4.256587 -222.227276) (xy 4.192328 -222.258221) (xy 4.125008 -222.281778) (xy 4.055473 -222.297648)
			(xy 3.984599 -222.305634) (xy 3.913277 -222.305634) (xy 3.842403 -222.297648) (xy 3.772868 -222.281778)
			(xy 3.705548 -222.258221) (xy 3.641289 -222.227276) (xy 3.580898 -222.18933) (xy 3.525136 -222.144861)
			(xy 3.474703 -222.094428) (xy 3.430234 -222.038666) (xy 3.392288 -221.978275) (xy 3.361343 -221.914016)
			(xy 3.337786 -221.846696) (xy 3.321916 -221.777161) (xy 3.31393 -221.706287) (xy 0.509016 -221.706287)
			(xy 0.509016 -222.706285) (xy 1.313934 -222.706285) (xy 1.313934 -222.634963) (xy 1.32192 -222.564089)
			(xy 1.33779 -222.494554) (xy 1.361347 -222.427234) (xy 1.392292 -222.362975) (xy 1.430238 -222.302584)
			(xy 1.474707 -222.246822) (xy 1.52514 -222.196389) (xy 1.580902 -222.15192) (xy 1.641293 -222.113974)
			(xy 1.705552 -222.083029) (xy 1.772872 -222.059472) (xy 1.842407 -222.043602) (xy 1.913281 -222.035616)
			(xy 1.948942 -222.035116) (xy 1.984603 -222.035616) (xy 2.055477 -222.043602) (xy 2.125012 -222.059472)
			(xy 2.192332 -222.083029) (xy 2.256591 -222.113974) (xy 2.316982 -222.15192) (xy 2.372744 -222.196389)
			(xy 2.423177 -222.246822) (xy 2.467646 -222.302584) (xy 2.505592 -222.362975) (xy 2.536537 -222.427234)
			(xy 2.560094 -222.494554) (xy 2.575964 -222.564089) (xy 2.58395 -222.634963) (xy 2.58395 -222.706285)
			(xy 7.813794 -222.706285) (xy 7.813794 -222.634963) (xy 7.82178 -222.564089) (xy 7.83765 -222.494554)
			(xy 7.861207 -222.427234) (xy 7.892152 -222.362975) (xy 7.930098 -222.302584) (xy 7.974567 -222.246822)
			(xy 8.025 -222.196389) (xy 8.080762 -222.15192) (xy 8.141153 -222.113974) (xy 8.205412 -222.083029)
			(xy 8.272732 -222.059472) (xy 8.342267 -222.043602) (xy 8.413141 -222.035616) (xy 8.448802 -222.035116)
			(xy 8.484463 -222.035616) (xy 8.555337 -222.043602) (xy 8.624872 -222.059472) (xy 8.692192 -222.083029)
			(xy 8.756451 -222.113974) (xy 8.816842 -222.15192) (xy 8.872604 -222.196389) (xy 8.923037 -222.246822)
			(xy 8.967506 -222.302584) (xy 9.005452 -222.362975) (xy 9.036397 -222.427234) (xy 9.059954 -222.494554)
			(xy 9.075824 -222.564089) (xy 9.08381 -222.634963) (xy 9.08381 -222.706285) (xy 9.075824 -222.777159)
			(xy 9.059954 -222.846694) (xy 9.036397 -222.914014) (xy 9.005452 -222.978273) (xy 8.967506 -223.038664)
			(xy 8.923037 -223.094426) (xy 8.872604 -223.144859) (xy 8.816842 -223.189328) (xy 8.756451 -223.227274)
			(xy 8.692192 -223.258219) (xy 8.624872 -223.281776) (xy 8.555337 -223.297646) (xy 8.484463 -223.305632)
			(xy 8.413141 -223.305632) (xy 8.342267 -223.297646) (xy 8.272732 -223.281776) (xy 8.205412 -223.258219)
			(xy 8.141153 -223.227274) (xy 8.080762 -223.189328) (xy 8.025 -223.144859) (xy 7.974567 -223.094426)
			(xy 7.930098 -223.038664) (xy 7.892152 -222.978273) (xy 7.861207 -222.914014) (xy 7.83765 -222.846694)
			(xy 7.82178 -222.777159) (xy 7.813794 -222.706285) (xy 2.58395 -222.706285) (xy 2.575964 -222.777159)
			(xy 2.560094 -222.846694) (xy 2.536537 -222.914014) (xy 2.505592 -222.978273) (xy 2.467646 -223.038664)
			(xy 2.423177 -223.094426) (xy 2.372744 -223.144859) (xy 2.316982 -223.189328) (xy 2.256591 -223.227274)
			(xy 2.192332 -223.258219) (xy 2.125012 -223.281776) (xy 2.055477 -223.297646) (xy 1.984603 -223.305632)
			(xy 1.913281 -223.305632) (xy 1.842407 -223.297646) (xy 1.772872 -223.281776) (xy 1.705552 -223.258219)
			(xy 1.641293 -223.227274) (xy 1.580902 -223.189328) (xy 1.52514 -223.144859) (xy 1.474707 -223.094426)
			(xy 1.430238 -223.038664) (xy 1.392292 -222.978273) (xy 1.361347 -222.914014) (xy 1.33779 -222.846694)
			(xy 1.32192 -222.777159) (xy 1.313934 -222.706285) (xy 0.509016 -222.706285) (xy 0.509016 -223.706283)
			(xy 3.31393 -223.706283) (xy 3.31393 -223.634961) (xy 3.321916 -223.564087) (xy 3.337786 -223.494552)
			(xy 3.361343 -223.427232) (xy 3.392288 -223.362973) (xy 3.430234 -223.302582) (xy 3.474703 -223.24682)
			(xy 3.525136 -223.196387) (xy 3.580898 -223.151918) (xy 3.641289 -223.113972) (xy 3.705548 -223.083027)
			(xy 3.772868 -223.05947) (xy 3.842403 -223.0436) (xy 3.913277 -223.035614) (xy 3.948938 -223.035114)
			(xy 3.984599 -223.035614) (xy 4.055473 -223.0436) (xy 4.125008 -223.05947) (xy 4.192328 -223.083027)
			(xy 4.256587 -223.113972) (xy 4.316978 -223.151918) (xy 4.37274 -223.196387) (xy 4.423173 -223.24682)
			(xy 4.467642 -223.302582) (xy 4.505588 -223.362973) (xy 4.536533 -223.427232) (xy 4.56009 -223.494552)
			(xy 4.57596 -223.564087) (xy 4.583946 -223.634961) (xy 4.583946 -223.706283) (xy 5.813798 -223.706283)
			(xy 5.813798 -223.634961) (xy 5.821784 -223.564087) (xy 5.837654 -223.494552) (xy 5.861211 -223.427232)
			(xy 5.892156 -223.362973) (xy 5.930102 -223.302582) (xy 5.974571 -223.24682) (xy 6.025004 -223.196387)
			(xy 6.080766 -223.151918) (xy 6.141157 -223.113972) (xy 6.205416 -223.083027) (xy 6.272736 -223.05947)
			(xy 6.342271 -223.0436) (xy 6.413145 -223.035614) (xy 6.448806 -223.035114) (xy 6.484467 -223.035614)
			(xy 6.555341 -223.0436) (xy 6.624876 -223.05947) (xy 6.692196 -223.083027) (xy 6.756455 -223.113972)
			(xy 6.816846 -223.151918) (xy 6.872608 -223.196387) (xy 6.923041 -223.24682) (xy 6.96751 -223.302582)
			(xy 7.005456 -223.362973) (xy 7.036401 -223.427232) (xy 7.059958 -223.494552) (xy 7.075828 -223.564087)
			(xy 7.083814 -223.634961) (xy 7.083814 -223.706283) (xy 7.075828 -223.777157) (xy 7.059958 -223.846692)
			(xy 7.036401 -223.914012) (xy 7.005456 -223.978271) (xy 6.96751 -224.038662) (xy 6.923041 -224.094424)
			(xy 6.872608 -224.144857) (xy 6.816846 -224.189326) (xy 6.756455 -224.227272) (xy 6.692196 -224.258217)
			(xy 6.624876 -224.281774) (xy 6.555341 -224.297644) (xy 6.484467 -224.30563) (xy 6.413145 -224.30563)
			(xy 6.342271 -224.297644) (xy 6.272736 -224.281774) (xy 6.205416 -224.258217) (xy 6.141157 -224.227272)
			(xy 6.080766 -224.189326) (xy 6.025004 -224.144857) (xy 5.974571 -224.094424) (xy 5.930102 -224.038662)
			(xy 5.892156 -223.978271) (xy 5.861211 -223.914012) (xy 5.837654 -223.846692) (xy 5.821784 -223.777157)
			(xy 5.813798 -223.706283) (xy 4.583946 -223.706283) (xy 4.57596 -223.777157) (xy 4.56009 -223.846692)
			(xy 4.536533 -223.914012) (xy 4.505588 -223.978271) (xy 4.467642 -224.038662) (xy 4.423173 -224.094424)
			(xy 4.37274 -224.144857) (xy 4.316978 -224.189326) (xy 4.256587 -224.227272) (xy 4.192328 -224.258217)
			(xy 4.125008 -224.281774) (xy 4.055473 -224.297644) (xy 3.984599 -224.30563) (xy 3.913277 -224.30563)
			(xy 3.842403 -224.297644) (xy 3.772868 -224.281774) (xy 3.705548 -224.258217) (xy 3.641289 -224.227272)
			(xy 3.580898 -224.189326) (xy 3.525136 -224.144857) (xy 3.474703 -224.094424) (xy 3.430234 -224.038662)
			(xy 3.392288 -223.978271) (xy 3.361343 -223.914012) (xy 3.337786 -223.846692) (xy 3.321916 -223.777157)
			(xy 3.31393 -223.706283) (xy 0.509016 -223.706283) (xy 0.509016 -224.706281) (xy 7.813794 -224.706281)
			(xy 7.813794 -224.634959) (xy 7.82178 -224.564085) (xy 7.83765 -224.49455) (xy 7.861207 -224.42723)
			(xy 7.892152 -224.362971) (xy 7.930098 -224.30258) (xy 7.974567 -224.246818) (xy 8.025 -224.196385)
			(xy 8.080762 -224.151916) (xy 8.141153 -224.11397) (xy 8.205412 -224.083025) (xy 8.272732 -224.059468)
			(xy 8.342267 -224.043598) (xy 8.413141 -224.035612) (xy 8.448802 -224.035112) (xy 8.484463 -224.035612)
			(xy 8.555337 -224.043598) (xy 8.624872 -224.059468) (xy 8.692192 -224.083025) (xy 8.756451 -224.11397)
			(xy 8.816842 -224.151916) (xy 8.872604 -224.196385) (xy 8.923037 -224.246818) (xy 8.967506 -224.30258)
			(xy 9.005452 -224.362971) (xy 9.036397 -224.42723) (xy 9.059954 -224.49455) (xy 9.075824 -224.564085)
			(xy 9.08381 -224.634959) (xy 9.08381 -224.706281) (xy 9.075824 -224.777155) (xy 9.059954 -224.84669)
			(xy 9.036397 -224.91401) (xy 9.005452 -224.978269) (xy 8.967506 -225.03866) (xy 8.923037 -225.094422)
			(xy 8.872604 -225.144855) (xy 8.816842 -225.189324) (xy 8.756451 -225.22727) (xy 8.692192 -225.258215)
			(xy 8.624872 -225.281772) (xy 8.555337 -225.297642) (xy 8.484463 -225.305628) (xy 8.413141 -225.305628)
			(xy 8.342267 -225.297642) (xy 8.272732 -225.281772) (xy 8.205412 -225.258215) (xy 8.141153 -225.22727)
			(xy 8.080762 -225.189324) (xy 8.025 -225.144855) (xy 7.974567 -225.094422) (xy 7.930098 -225.03866)
			(xy 7.892152 -224.978269) (xy 7.861207 -224.91401) (xy 7.83765 -224.84669) (xy 7.82178 -224.777155)
			(xy 7.813794 -224.706281) (xy 0.509016 -224.706281) (xy 0.509016 -225.706279) (xy 3.31393 -225.706279)
			(xy 3.31393 -225.634957) (xy 3.321916 -225.564083) (xy 3.337786 -225.494548) (xy 3.361343 -225.427228)
			(xy 3.392288 -225.362969) (xy 3.430234 -225.302578) (xy 3.474703 -225.246816) (xy 3.525136 -225.196383)
			(xy 3.580898 -225.151914) (xy 3.641289 -225.113968) (xy 3.705548 -225.083023) (xy 3.772868 -225.059466)
			(xy 3.842403 -225.043596) (xy 3.913277 -225.03561) (xy 3.948938 -225.03511) (xy 3.984599 -225.03561)
			(xy 4.055473 -225.043596) (xy 4.125008 -225.059466) (xy 4.192328 -225.083023) (xy 4.256587 -225.113968)
			(xy 4.316978 -225.151914) (xy 4.37274 -225.196383) (xy 4.423173 -225.246816) (xy 4.467642 -225.302578)
			(xy 4.505588 -225.362969) (xy 4.536533 -225.427228) (xy 4.56009 -225.494548) (xy 4.57596 -225.564083)
			(xy 4.583946 -225.634957) (xy 4.583946 -225.706279) (xy 5.813798 -225.706279) (xy 5.813798 -225.634957)
			(xy 5.821784 -225.564083) (xy 5.837654 -225.494548) (xy 5.861211 -225.427228) (xy 5.892156 -225.362969)
			(xy 5.930102 -225.302578) (xy 5.974571 -225.246816) (xy 6.025004 -225.196383) (xy 6.080766 -225.151914)
			(xy 6.141157 -225.113968) (xy 6.205416 -225.083023) (xy 6.272736 -225.059466) (xy 6.342271 -225.043596)
			(xy 6.413145 -225.03561) (xy 6.448806 -225.03511) (xy 6.484467 -225.03561) (xy 6.555341 -225.043596)
			(xy 6.624876 -225.059466) (xy 6.692196 -225.083023) (xy 6.756455 -225.113968) (xy 6.816846 -225.151914)
			(xy 6.872608 -225.196383) (xy 6.923041 -225.246816) (xy 6.96751 -225.302578) (xy 7.005456 -225.362969)
			(xy 7.036401 -225.427228) (xy 7.059958 -225.494548) (xy 7.075828 -225.564083) (xy 7.083814 -225.634957)
			(xy 7.083814 -225.706279) (xy 7.075828 -225.777153) (xy 7.059958 -225.846688) (xy 7.036401 -225.914008)
			(xy 7.005456 -225.978267) (xy 6.96751 -226.038658) (xy 6.923041 -226.09442) (xy 6.872608 -226.144853)
			(xy 6.816846 -226.189322) (xy 6.756455 -226.227268) (xy 6.692196 -226.258213) (xy 6.624876 -226.28177)
			(xy 6.555341 -226.29764) (xy 6.484467 -226.305626) (xy 6.413145 -226.305626) (xy 6.342271 -226.29764)
			(xy 6.272736 -226.28177) (xy 6.205416 -226.258213) (xy 6.141157 -226.227268) (xy 6.080766 -226.189322)
			(xy 6.025004 -226.144853) (xy 5.974571 -226.09442) (xy 5.930102 -226.038658) (xy 5.892156 -225.978267)
			(xy 5.861211 -225.914008) (xy 5.837654 -225.846688) (xy 5.821784 -225.777153) (xy 5.813798 -225.706279)
			(xy 4.583946 -225.706279) (xy 4.57596 -225.777153) (xy 4.56009 -225.846688) (xy 4.536533 -225.914008)
			(xy 4.505588 -225.978267) (xy 4.467642 -226.038658) (xy 4.423173 -226.09442) (xy 4.37274 -226.144853)
			(xy 4.316978 -226.189322) (xy 4.256587 -226.227268) (xy 4.192328 -226.258213) (xy 4.125008 -226.28177)
			(xy 4.055473 -226.29764) (xy 3.984599 -226.305626) (xy 3.913277 -226.305626) (xy 3.842403 -226.29764)
			(xy 3.772868 -226.28177) (xy 3.705548 -226.258213) (xy 3.641289 -226.227268) (xy 3.580898 -226.189322)
			(xy 3.525136 -226.144853) (xy 3.474703 -226.09442) (xy 3.430234 -226.038658) (xy 3.392288 -225.978267)
			(xy 3.361343 -225.914008) (xy 3.337786 -225.846688) (xy 3.321916 -225.777153) (xy 3.31393 -225.706279)
			(xy 0.509016 -225.706279) (xy 0.509016 -226.706277) (xy 1.313934 -226.706277) (xy 1.313934 -226.634955)
			(xy 1.32192 -226.564081) (xy 1.33779 -226.494546) (xy 1.361347 -226.427226) (xy 1.392292 -226.362967)
			(xy 1.430238 -226.302576) (xy 1.474707 -226.246814) (xy 1.52514 -226.196381) (xy 1.580902 -226.151912)
			(xy 1.641293 -226.113966) (xy 1.705552 -226.083021) (xy 1.772872 -226.059464) (xy 1.842407 -226.043594)
			(xy 1.913281 -226.035608) (xy 1.948942 -226.035108) (xy 1.984603 -226.035608) (xy 2.055477 -226.043594)
			(xy 2.125012 -226.059464) (xy 2.192332 -226.083021) (xy 2.256591 -226.113966) (xy 2.316982 -226.151912)
			(xy 2.372744 -226.196381) (xy 2.423177 -226.246814) (xy 2.467646 -226.302576) (xy 2.505592 -226.362967)
			(xy 2.536537 -226.427226) (xy 2.560094 -226.494546) (xy 2.575964 -226.564081) (xy 2.58395 -226.634955)
			(xy 2.58395 -226.706277) (xy 2.575964 -226.777151) (xy 2.560094 -226.846686) (xy 2.536537 -226.914006)
			(xy 2.505592 -226.978265) (xy 2.467646 -227.038656) (xy 2.423177 -227.094418) (xy 2.372744 -227.144851)
			(xy 2.316982 -227.18932) (xy 2.256591 -227.227266) (xy 2.192332 -227.258211) (xy 2.125012 -227.281768)
			(xy 2.055477 -227.297638) (xy 1.984603 -227.305624) (xy 1.913281 -227.305624) (xy 1.842407 -227.297638)
			(xy 1.772872 -227.281768) (xy 1.705552 -227.258211) (xy 1.641293 -227.227266) (xy 1.580902 -227.18932)
			(xy 1.52514 -227.144851) (xy 1.474707 -227.094418) (xy 1.430238 -227.038656) (xy 1.392292 -226.978265)
			(xy 1.361347 -226.914006) (xy 1.33779 -226.846686) (xy 1.32192 -226.777151) (xy 1.313934 -226.706277)
			(xy 0.509016 -226.706277) (xy 0.509016 -227.706275) (xy 3.31393 -227.706275) (xy 3.31393 -227.634953)
			(xy 3.321916 -227.564079) (xy 3.337786 -227.494544) (xy 3.361343 -227.427224) (xy 3.392288 -227.362965)
			(xy 3.430234 -227.302574) (xy 3.474703 -227.246812) (xy 3.525136 -227.196379) (xy 3.580898 -227.15191)
			(xy 3.641289 -227.113964) (xy 3.705548 -227.083019) (xy 3.772868 -227.059462) (xy 3.842403 -227.043592)
			(xy 3.913277 -227.035606) (xy 3.948938 -227.035106) (xy 3.984599 -227.035606) (xy 4.055473 -227.043592)
			(xy 4.125008 -227.059462) (xy 4.192328 -227.083019) (xy 4.256587 -227.113964) (xy 4.316978 -227.15191)
			(xy 4.37274 -227.196379) (xy 4.423173 -227.246812) (xy 4.467642 -227.302574) (xy 4.505588 -227.362965)
			(xy 4.536533 -227.427224) (xy 4.56009 -227.494544) (xy 4.57596 -227.564079) (xy 4.583946 -227.634953)
			(xy 4.583946 -227.706275) (xy 5.813798 -227.706275) (xy 5.813798 -227.634953) (xy 5.821784 -227.564079)
			(xy 5.837654 -227.494544) (xy 5.861211 -227.427224) (xy 5.892156 -227.362965) (xy 5.930102 -227.302574)
			(xy 5.974571 -227.246812) (xy 6.025004 -227.196379) (xy 6.080766 -227.15191) (xy 6.141157 -227.113964)
			(xy 6.205416 -227.083019) (xy 6.272736 -227.059462) (xy 6.342271 -227.043592) (xy 6.413145 -227.035606)
			(xy 6.448806 -227.035106) (xy 6.484467 -227.035606) (xy 6.555341 -227.043592) (xy 6.624876 -227.059462)
			(xy 6.692196 -227.083019) (xy 6.756455 -227.113964) (xy 6.816846 -227.15191) (xy 6.872608 -227.196379)
			(xy 6.923041 -227.246812) (xy 6.96751 -227.302574) (xy 7.005456 -227.362965) (xy 7.036401 -227.427224)
			(xy 7.059958 -227.494544) (xy 7.075828 -227.564079) (xy 7.083814 -227.634953) (xy 7.083814 -227.706275)
			(xy 7.075828 -227.777149) (xy 7.059958 -227.846684) (xy 7.036401 -227.914004) (xy 7.005456 -227.978263)
			(xy 6.96751 -228.038654) (xy 6.923041 -228.094416) (xy 6.872608 -228.144849) (xy 6.816846 -228.189318)
			(xy 6.756455 -228.227264) (xy 6.692196 -228.258209) (xy 6.624876 -228.281766) (xy 6.555341 -228.297636)
			(xy 6.484467 -228.305622) (xy 6.413145 -228.305622) (xy 6.342271 -228.297636) (xy 6.272736 -228.281766)
			(xy 6.205416 -228.258209) (xy 6.141157 -228.227264) (xy 6.080766 -228.189318) (xy 6.025004 -228.144849)
			(xy 5.974571 -228.094416) (xy 5.930102 -228.038654) (xy 5.892156 -227.978263) (xy 5.861211 -227.914004)
			(xy 5.837654 -227.846684) (xy 5.821784 -227.777149) (xy 5.813798 -227.706275) (xy 4.583946 -227.706275)
			(xy 4.57596 -227.777149) (xy 4.56009 -227.846684) (xy 4.536533 -227.914004) (xy 4.505588 -227.978263)
			(xy 4.467642 -228.038654) (xy 4.423173 -228.094416) (xy 4.37274 -228.144849) (xy 4.316978 -228.189318)
			(xy 4.256587 -228.227264) (xy 4.192328 -228.258209) (xy 4.125008 -228.281766) (xy 4.055473 -228.297636)
			(xy 3.984599 -228.305622) (xy 3.913277 -228.305622) (xy 3.842403 -228.297636) (xy 3.772868 -228.281766)
			(xy 3.705548 -228.258209) (xy 3.641289 -228.227264) (xy 3.580898 -228.189318) (xy 3.525136 -228.144849)
			(xy 3.474703 -228.094416) (xy 3.430234 -228.038654) (xy 3.392288 -227.978263) (xy 3.361343 -227.914004)
			(xy 3.337786 -227.846684) (xy 3.321916 -227.777149) (xy 3.31393 -227.706275) (xy 0.509016 -227.706275)
			(xy 0.509016 -228.706273) (xy 1.313934 -228.706273) (xy 1.313934 -228.634951) (xy 1.32192 -228.564077)
			(xy 1.33779 -228.494542) (xy 1.361347 -228.427222) (xy 1.392292 -228.362963) (xy 1.430238 -228.302572)
			(xy 1.474707 -228.24681) (xy 1.52514 -228.196377) (xy 1.580902 -228.151908) (xy 1.641293 -228.113962)
			(xy 1.705552 -228.083017) (xy 1.772872 -228.05946) (xy 1.842407 -228.04359) (xy 1.913281 -228.035604)
			(xy 1.948942 -228.035104) (xy 1.984603 -228.035604) (xy 2.055477 -228.04359) (xy 2.125012 -228.05946)
			(xy 2.192332 -228.083017) (xy 2.256591 -228.113962) (xy 2.316982 -228.151908) (xy 2.372744 -228.196377)
			(xy 2.423177 -228.24681) (xy 2.467646 -228.302572) (xy 2.505592 -228.362963) (xy 2.536537 -228.427222)
			(xy 2.560094 -228.494542) (xy 2.575964 -228.564077) (xy 2.58395 -228.634951) (xy 2.58395 -228.706273)
			(xy 7.813794 -228.706273) (xy 7.813794 -228.634951) (xy 7.82178 -228.564077) (xy 7.83765 -228.494542)
			(xy 7.861207 -228.427222) (xy 7.892152 -228.362963) (xy 7.930098 -228.302572) (xy 7.974567 -228.24681)
			(xy 8.025 -228.196377) (xy 8.080762 -228.151908) (xy 8.141153 -228.113962) (xy 8.205412 -228.083017)
			(xy 8.272732 -228.05946) (xy 8.342267 -228.04359) (xy 8.413141 -228.035604) (xy 8.448802 -228.035104)
			(xy 8.484463 -228.035604) (xy 8.555337 -228.04359) (xy 8.624872 -228.05946) (xy 8.692192 -228.083017)
			(xy 8.756451 -228.113962) (xy 8.816842 -228.151908) (xy 8.872604 -228.196377) (xy 8.923037 -228.24681)
			(xy 8.967506 -228.302572) (xy 9.005452 -228.362963) (xy 9.036397 -228.427222) (xy 9.059954 -228.494542)
			(xy 9.075824 -228.564077) (xy 9.08381 -228.634951) (xy 9.08381 -228.706273) (xy 9.075824 -228.777147)
			(xy 9.059954 -228.846682) (xy 9.036397 -228.914002) (xy 9.005452 -228.978261) (xy 8.967506 -229.038652)
			(xy 8.923037 -229.094414) (xy 8.872604 -229.144847) (xy 8.816842 -229.189316) (xy 8.756451 -229.227262)
			(xy 8.692192 -229.258207) (xy 8.624872 -229.281764) (xy 8.555337 -229.297634) (xy 8.484463 -229.30562)
			(xy 8.413141 -229.30562) (xy 8.342267 -229.297634) (xy 8.272732 -229.281764) (xy 8.205412 -229.258207)
			(xy 8.141153 -229.227262) (xy 8.080762 -229.189316) (xy 8.025 -229.144847) (xy 7.974567 -229.094414)
			(xy 7.930098 -229.038652) (xy 7.892152 -228.978261) (xy 7.861207 -228.914002) (xy 7.83765 -228.846682)
			(xy 7.82178 -228.777147) (xy 7.813794 -228.706273) (xy 2.58395 -228.706273) (xy 2.575964 -228.777147)
			(xy 2.560094 -228.846682) (xy 2.536537 -228.914002) (xy 2.505592 -228.978261) (xy 2.467646 -229.038652)
			(xy 2.423177 -229.094414) (xy 2.372744 -229.144847) (xy 2.316982 -229.189316) (xy 2.256591 -229.227262)
			(xy 2.192332 -229.258207) (xy 2.125012 -229.281764) (xy 2.055477 -229.297634) (xy 1.984603 -229.30562)
			(xy 1.913281 -229.30562) (xy 1.842407 -229.297634) (xy 1.772872 -229.281764) (xy 1.705552 -229.258207)
			(xy 1.641293 -229.227262) (xy 1.580902 -229.189316) (xy 1.52514 -229.144847) (xy 1.474707 -229.094414)
			(xy 1.430238 -229.038652) (xy 1.392292 -228.978261) (xy 1.361347 -228.914002) (xy 1.33779 -228.846682)
			(xy 1.32192 -228.777147) (xy 1.313934 -228.706273) (xy 0.509016 -228.706273) (xy 0.509016 -229.706271)
			(xy 5.813798 -229.706271) (xy 5.813798 -229.634949) (xy 5.821784 -229.564075) (xy 5.837654 -229.49454)
			(xy 5.861211 -229.42722) (xy 5.892156 -229.362961) (xy 5.930102 -229.30257) (xy 5.974571 -229.246808)
			(xy 6.025004 -229.196375) (xy 6.080766 -229.151906) (xy 6.141157 -229.11396) (xy 6.205416 -229.083015)
			(xy 6.272736 -229.059458) (xy 6.342271 -229.043588) (xy 6.413145 -229.035602) (xy 6.448806 -229.035102)
			(xy 6.484467 -229.035602) (xy 6.555341 -229.043588) (xy 6.624876 -229.059458) (xy 6.692196 -229.083015)
			(xy 6.756455 -229.11396) (xy 6.816846 -229.151906) (xy 6.872608 -229.196375) (xy 6.923041 -229.246808)
			(xy 6.96751 -229.30257) (xy 7.005456 -229.362961) (xy 7.036401 -229.42722) (xy 7.059958 -229.49454)
			(xy 7.075828 -229.564075) (xy 7.083814 -229.634949) (xy 7.083814 -229.706271) (xy 7.075828 -229.777145)
			(xy 7.059958 -229.84668) (xy 7.036401 -229.914) (xy 7.005456 -229.978259) (xy 6.96751 -230.03865)
			(xy 6.923041 -230.094412) (xy 6.872608 -230.144845) (xy 6.816846 -230.189314) (xy 6.756455 -230.22726)
			(xy 6.692196 -230.258205) (xy 6.624876 -230.281762) (xy 6.555341 -230.297632) (xy 6.484467 -230.305618)
			(xy 6.413145 -230.305618) (xy 6.342271 -230.297632) (xy 6.272736 -230.281762) (xy 6.205416 -230.258205)
			(xy 6.141157 -230.22726) (xy 6.080766 -230.189314) (xy 6.025004 -230.144845) (xy 5.974571 -230.094412)
			(xy 5.930102 -230.03865) (xy 5.892156 -229.978259) (xy 5.861211 -229.914) (xy 5.837654 -229.84668)
			(xy 5.821784 -229.777145) (xy 5.813798 -229.706271) (xy 0.509016 -229.706271) (xy 0.509016 -230.706269)
			(xy 1.313934 -230.706269) (xy 1.313934 -230.634947) (xy 1.32192 -230.564073) (xy 1.33779 -230.494538)
			(xy 1.361347 -230.427218) (xy 1.392292 -230.362959) (xy 1.430238 -230.302568) (xy 1.474707 -230.246806)
			(xy 1.52514 -230.196373) (xy 1.580902 -230.151904) (xy 1.641293 -230.113958) (xy 1.705552 -230.083013)
			(xy 1.772872 -230.059456) (xy 1.842407 -230.043586) (xy 1.913281 -230.0356) (xy 1.948942 -230.0351)
			(xy 1.984603 -230.0356) (xy 2.055477 -230.043586) (xy 2.125012 -230.059456) (xy 2.192332 -230.083013)
			(xy 2.256591 -230.113958) (xy 2.316982 -230.151904) (xy 2.372744 -230.196373) (xy 2.423177 -230.246806)
			(xy 2.467646 -230.302568) (xy 2.505592 -230.362959) (xy 2.536537 -230.427218) (xy 2.560094 -230.494538)
			(xy 2.575964 -230.564073) (xy 2.58395 -230.634947) (xy 2.58395 -230.706269) (xy 7.813794 -230.706269)
			(xy 7.813794 -230.634947) (xy 7.82178 -230.564073) (xy 7.83765 -230.494538) (xy 7.861207 -230.427218)
			(xy 7.892152 -230.362959) (xy 7.930098 -230.302568) (xy 7.974567 -230.246806) (xy 8.025 -230.196373)
			(xy 8.080762 -230.151904) (xy 8.141153 -230.113958) (xy 8.205412 -230.083013) (xy 8.272732 -230.059456)
			(xy 8.342267 -230.043586) (xy 8.413141 -230.0356) (xy 8.448802 -230.0351) (xy 8.484463 -230.0356)
			(xy 8.555337 -230.043586) (xy 8.624872 -230.059456) (xy 8.692192 -230.083013) (xy 8.756451 -230.113958)
			(xy 8.816842 -230.151904) (xy 8.872604 -230.196373) (xy 8.923037 -230.246806) (xy 8.967506 -230.302568)
			(xy 9.005452 -230.362959) (xy 9.036397 -230.427218) (xy 9.059954 -230.494538) (xy 9.075824 -230.564073)
			(xy 9.08381 -230.634947) (xy 9.08381 -230.706269) (xy 9.075824 -230.777143) (xy 9.059954 -230.846678)
			(xy 9.036397 -230.913998) (xy 9.005452 -230.978257) (xy 8.967506 -231.038648) (xy 8.923037 -231.09441)
			(xy 8.872604 -231.144843) (xy 8.816842 -231.189312) (xy 8.756451 -231.227258) (xy 8.692192 -231.258203)
			(xy 8.624872 -231.28176) (xy 8.555337 -231.29763) (xy 8.484463 -231.305616) (xy 8.413141 -231.305616)
			(xy 8.342267 -231.29763) (xy 8.272732 -231.28176) (xy 8.205412 -231.258203) (xy 8.141153 -231.227258)
			(xy 8.080762 -231.189312) (xy 8.025 -231.144843) (xy 7.974567 -231.09441) (xy 7.930098 -231.038648)
			(xy 7.892152 -230.978257) (xy 7.861207 -230.913998) (xy 7.83765 -230.846678) (xy 7.82178 -230.777143)
			(xy 7.813794 -230.706269) (xy 2.58395 -230.706269) (xy 2.575964 -230.777143) (xy 2.560094 -230.846678)
			(xy 2.536537 -230.913998) (xy 2.505592 -230.978257) (xy 2.467646 -231.038648) (xy 2.423177 -231.09441)
			(xy 2.372744 -231.144843) (xy 2.316982 -231.189312) (xy 2.256591 -231.227258) (xy 2.192332 -231.258203)
			(xy 2.125012 -231.28176) (xy 2.055477 -231.29763) (xy 1.984603 -231.305616) (xy 1.913281 -231.305616)
			(xy 1.842407 -231.29763) (xy 1.772872 -231.28176) (xy 1.705552 -231.258203) (xy 1.641293 -231.227258)
			(xy 1.580902 -231.189312) (xy 1.52514 -231.144843) (xy 1.474707 -231.09441) (xy 1.430238 -231.038648)
			(xy 1.392292 -230.978257) (xy 1.361347 -230.913998) (xy 1.33779 -230.846678) (xy 1.32192 -230.777143)
			(xy 1.313934 -230.706269) (xy 0.509016 -230.706269) (xy 0.509016 -231.706267) (xy 3.31393 -231.706267)
			(xy 3.31393 -231.634945) (xy 3.321916 -231.564071) (xy 3.337786 -231.494536) (xy 3.361343 -231.427216)
			(xy 3.392288 -231.362957) (xy 3.430234 -231.302566) (xy 3.474703 -231.246804) (xy 3.525136 -231.196371)
			(xy 3.580898 -231.151902) (xy 3.641289 -231.113956) (xy 3.705548 -231.083011) (xy 3.772868 -231.059454)
			(xy 3.842403 -231.043584) (xy 3.913277 -231.035598) (xy 3.948938 -231.035098) (xy 3.984599 -231.035598)
			(xy 4.055473 -231.043584) (xy 4.125008 -231.059454) (xy 4.192328 -231.083011) (xy 4.256587 -231.113956)
			(xy 4.316978 -231.151902) (xy 4.37274 -231.196371) (xy 4.423173 -231.246804) (xy 4.467642 -231.302566)
			(xy 4.505588 -231.362957) (xy 4.536533 -231.427216) (xy 4.56009 -231.494536) (xy 4.57596 -231.564071)
			(xy 4.583946 -231.634945) (xy 4.583946 -231.706267) (xy 4.57596 -231.777141) (xy 4.56009 -231.846676)
			(xy 4.536533 -231.913996) (xy 4.505588 -231.978255) (xy 4.467642 -232.038646) (xy 4.423173 -232.094408)
			(xy 4.37274 -232.144841) (xy 4.316978 -232.18931) (xy 4.256587 -232.227256) (xy 4.192328 -232.258201)
			(xy 4.125008 -232.281758) (xy 4.055473 -232.297628) (xy 3.984599 -232.305614) (xy 3.913277 -232.305614)
			(xy 3.842403 -232.297628) (xy 3.772868 -232.281758) (xy 3.705548 -232.258201) (xy 3.641289 -232.227256)
			(xy 3.580898 -232.18931) (xy 3.525136 -232.144841) (xy 3.474703 -232.094408) (xy 3.430234 -232.038646)
			(xy 3.392288 -231.978255) (xy 3.361343 -231.913996) (xy 3.337786 -231.846676) (xy 3.321916 -231.777141)
			(xy 3.31393 -231.706267) (xy 0.509016 -231.706267) (xy 0.509016 -232.706265) (xy 1.313934 -232.706265)
			(xy 1.313934 -232.634943) (xy 1.32192 -232.564069) (xy 1.33779 -232.494534) (xy 1.361347 -232.427214)
			(xy 1.392292 -232.362955) (xy 1.430238 -232.302564) (xy 1.474707 -232.246802) (xy 1.52514 -232.196369)
			(xy 1.580902 -232.1519) (xy 1.641293 -232.113954) (xy 1.705552 -232.083009) (xy 1.772872 -232.059452)
			(xy 1.842407 -232.043582) (xy 1.913281 -232.035596) (xy 1.948942 -232.035096) (xy 1.984603 -232.035596)
			(xy 2.055477 -232.043582) (xy 2.125012 -232.059452) (xy 2.192332 -232.083009) (xy 2.256591 -232.113954)
			(xy 2.316982 -232.1519) (xy 2.372744 -232.196369) (xy 2.423177 -232.246802) (xy 2.467646 -232.302564)
			(xy 2.505592 -232.362955) (xy 2.536537 -232.427214) (xy 2.560094 -232.494534) (xy 2.575964 -232.564069)
			(xy 2.58395 -232.634943) (xy 2.58395 -232.706265) (xy 7.813794 -232.706265) (xy 7.813794 -232.634943)
			(xy 7.82178 -232.564069) (xy 7.83765 -232.494534) (xy 7.861207 -232.427214) (xy 7.892152 -232.362955)
			(xy 7.930098 -232.302564) (xy 7.974567 -232.246802) (xy 8.025 -232.196369) (xy 8.080762 -232.1519)
			(xy 8.141153 -232.113954) (xy 8.205412 -232.083009) (xy 8.272732 -232.059452) (xy 8.342267 -232.043582)
			(xy 8.413141 -232.035596) (xy 8.448802 -232.035096) (xy 8.484463 -232.035596) (xy 8.555337 -232.043582)
			(xy 8.624872 -232.059452) (xy 8.692192 -232.083009) (xy 8.756451 -232.113954) (xy 8.816842 -232.1519)
			(xy 8.872604 -232.196369) (xy 8.923037 -232.246802) (xy 8.967506 -232.302564) (xy 9.005452 -232.362955)
			(xy 9.036397 -232.427214) (xy 9.059954 -232.494534) (xy 9.075824 -232.564069) (xy 9.08381 -232.634943)
			(xy 9.08381 -232.706265) (xy 9.075824 -232.777139) (xy 9.059954 -232.846674) (xy 9.036397 -232.913994)
			(xy 9.005452 -232.978253) (xy 8.967506 -233.038644) (xy 8.923037 -233.094406) (xy 8.872604 -233.144839)
			(xy 8.816842 -233.189308) (xy 8.756451 -233.227254) (xy 8.692192 -233.258199) (xy 8.624872 -233.281756)
			(xy 8.555337 -233.297626) (xy 8.484463 -233.305612) (xy 8.413141 -233.305612) (xy 8.342267 -233.297626)
			(xy 8.272732 -233.281756) (xy 8.205412 -233.258199) (xy 8.141153 -233.227254) (xy 8.080762 -233.189308)
			(xy 8.025 -233.144839) (xy 7.974567 -233.094406) (xy 7.930098 -233.038644) (xy 7.892152 -232.978253)
			(xy 7.861207 -232.913994) (xy 7.83765 -232.846674) (xy 7.82178 -232.777139) (xy 7.813794 -232.706265)
			(xy 2.58395 -232.706265) (xy 2.575964 -232.777139) (xy 2.560094 -232.846674) (xy 2.536537 -232.913994)
			(xy 2.505592 -232.978253) (xy 2.467646 -233.038644) (xy 2.423177 -233.094406) (xy 2.372744 -233.144839)
			(xy 2.316982 -233.189308) (xy 2.256591 -233.227254) (xy 2.192332 -233.258199) (xy 2.125012 -233.281756)
			(xy 2.055477 -233.297626) (xy 1.984603 -233.305612) (xy 1.913281 -233.305612) (xy 1.842407 -233.297626)
			(xy 1.772872 -233.281756) (xy 1.705552 -233.258199) (xy 1.641293 -233.227254) (xy 1.580902 -233.189308)
			(xy 1.52514 -233.144839) (xy 1.474707 -233.094406) (xy 1.430238 -233.038644) (xy 1.392292 -232.978253)
			(xy 1.361347 -232.913994) (xy 1.33779 -232.846674) (xy 1.32192 -232.777139) (xy 1.313934 -232.706265)
			(xy 0.509016 -232.706265) (xy 0.509016 -233.706263) (xy 3.31393 -233.706263) (xy 3.31393 -233.634941)
			(xy 3.321916 -233.564067) (xy 3.337786 -233.494532) (xy 3.361343 -233.427212) (xy 3.392288 -233.362953)
			(xy 3.430234 -233.302562) (xy 3.474703 -233.2468) (xy 3.525136 -233.196367) (xy 3.580898 -233.151898)
			(xy 3.641289 -233.113952) (xy 3.705548 -233.083007) (xy 3.772868 -233.05945) (xy 3.842403 -233.04358)
			(xy 3.913277 -233.035594) (xy 3.948938 -233.035094) (xy 3.984599 -233.035594) (xy 4.055473 -233.04358)
			(xy 4.125008 -233.05945) (xy 4.192328 -233.083007) (xy 4.256587 -233.113952) (xy 4.316978 -233.151898)
			(xy 4.37274 -233.196367) (xy 4.423173 -233.2468) (xy 4.467642 -233.302562) (xy 4.505588 -233.362953)
			(xy 4.536533 -233.427212) (xy 4.56009 -233.494532) (xy 4.57596 -233.564067) (xy 4.583946 -233.634941)
			(xy 4.583946 -233.706263) (xy 5.813798 -233.706263) (xy 5.813798 -233.634941) (xy 5.821784 -233.564067)
			(xy 5.837654 -233.494532) (xy 5.861211 -233.427212) (xy 5.892156 -233.362953) (xy 5.930102 -233.302562)
			(xy 5.974571 -233.2468) (xy 6.025004 -233.196367) (xy 6.080766 -233.151898) (xy 6.141157 -233.113952)
			(xy 6.205416 -233.083007) (xy 6.272736 -233.05945) (xy 6.342271 -233.04358) (xy 6.413145 -233.035594)
			(xy 6.448806 -233.035094) (xy 6.484467 -233.035594) (xy 6.555341 -233.04358) (xy 6.624876 -233.05945)
			(xy 6.692196 -233.083007) (xy 6.756455 -233.113952) (xy 6.816846 -233.151898) (xy 6.872608 -233.196367)
			(xy 6.923041 -233.2468) (xy 6.96751 -233.302562) (xy 7.005456 -233.362953) (xy 7.036401 -233.427212)
			(xy 7.059958 -233.494532) (xy 7.075828 -233.564067) (xy 7.083814 -233.634941) (xy 7.083814 -233.706263)
			(xy 7.075828 -233.777137) (xy 7.059958 -233.846672) (xy 7.036401 -233.913992) (xy 7.005456 -233.978251)
			(xy 6.96751 -234.038642) (xy 6.923041 -234.094404) (xy 6.872608 -234.144837) (xy 6.816846 -234.189306)
			(xy 6.756455 -234.227252) (xy 6.692196 -234.258197) (xy 6.624876 -234.281754) (xy 6.555341 -234.297624)
			(xy 6.484467 -234.30561) (xy 6.413145 -234.30561) (xy 6.342271 -234.297624) (xy 6.272736 -234.281754)
			(xy 6.205416 -234.258197) (xy 6.141157 -234.227252) (xy 6.080766 -234.189306) (xy 6.025004 -234.144837)
			(xy 5.974571 -234.094404) (xy 5.930102 -234.038642) (xy 5.892156 -233.978251) (xy 5.861211 -233.913992)
			(xy 5.837654 -233.846672) (xy 5.821784 -233.777137) (xy 5.813798 -233.706263) (xy 4.583946 -233.706263)
			(xy 4.57596 -233.777137) (xy 4.56009 -233.846672) (xy 4.536533 -233.913992) (xy 4.505588 -233.978251)
			(xy 4.467642 -234.038642) (xy 4.423173 -234.094404) (xy 4.37274 -234.144837) (xy 4.316978 -234.189306)
			(xy 4.256587 -234.227252) (xy 4.192328 -234.258197) (xy 4.125008 -234.281754) (xy 4.055473 -234.297624)
			(xy 3.984599 -234.30561) (xy 3.913277 -234.30561) (xy 3.842403 -234.297624) (xy 3.772868 -234.281754)
			(xy 3.705548 -234.258197) (xy 3.641289 -234.227252) (xy 3.580898 -234.189306) (xy 3.525136 -234.144837)
			(xy 3.474703 -234.094404) (xy 3.430234 -234.038642) (xy 3.392288 -233.978251) (xy 3.361343 -233.913992)
			(xy 3.337786 -233.846672) (xy 3.321916 -233.777137) (xy 3.31393 -233.706263) (xy 0.509016 -233.706263)
			(xy 0.509016 -234.706261) (xy 7.813794 -234.706261) (xy 7.813794 -234.634939) (xy 7.82178 -234.564065)
			(xy 7.83765 -234.49453) (xy 7.861207 -234.42721) (xy 7.892152 -234.362951) (xy 7.930098 -234.30256)
			(xy 7.974567 -234.246798) (xy 8.025 -234.196365) (xy 8.080762 -234.151896) (xy 8.141153 -234.11395)
			(xy 8.205412 -234.083005) (xy 8.272732 -234.059448) (xy 8.342267 -234.043578) (xy 8.413141 -234.035592)
			(xy 8.448802 -234.035092) (xy 8.484463 -234.035592) (xy 8.555337 -234.043578) (xy 8.624872 -234.059448)
			(xy 8.692192 -234.083005) (xy 8.756451 -234.11395) (xy 8.816842 -234.151896) (xy 8.872604 -234.196365)
			(xy 8.923037 -234.246798) (xy 8.967506 -234.30256) (xy 9.005452 -234.362951) (xy 9.036397 -234.42721)
			(xy 9.059954 -234.49453) (xy 9.075824 -234.564065) (xy 9.08381 -234.634939) (xy 9.08381 -234.706261)
			(xy 9.075824 -234.777135) (xy 9.059954 -234.84667) (xy 9.036397 -234.91399) (xy 9.005452 -234.978249)
			(xy 8.967506 -235.03864) (xy 8.923037 -235.094402) (xy 8.872604 -235.144835) (xy 8.816842 -235.189304)
			(xy 8.756451 -235.22725) (xy 8.692192 -235.258195) (xy 8.624872 -235.281752) (xy 8.555337 -235.297622)
			(xy 8.484463 -235.305608) (xy 8.413141 -235.305608) (xy 8.342267 -235.297622) (xy 8.272732 -235.281752)
			(xy 8.205412 -235.258195) (xy 8.141153 -235.22725) (xy 8.080762 -235.189304) (xy 8.025 -235.144835)
			(xy 7.974567 -235.094402) (xy 7.930098 -235.03864) (xy 7.892152 -234.978249) (xy 7.861207 -234.91399)
			(xy 7.83765 -234.84667) (xy 7.82178 -234.777135) (xy 7.813794 -234.706261) (xy 0.509016 -234.706261)
			(xy 0.509016 -235.706259) (xy 3.31393 -235.706259) (xy 3.31393 -235.634937) (xy 3.321916 -235.564063)
			(xy 3.337786 -235.494528) (xy 3.361343 -235.427208) (xy 3.392288 -235.362949) (xy 3.430234 -235.302558)
			(xy 3.474703 -235.246796) (xy 3.525136 -235.196363) (xy 3.580898 -235.151894) (xy 3.641289 -235.113948)
			(xy 3.705548 -235.083003) (xy 3.772868 -235.059446) (xy 3.842403 -235.043576) (xy 3.913277 -235.03559)
			(xy 3.948938 -235.03509) (xy 3.984599 -235.03559) (xy 4.055473 -235.043576) (xy 4.125008 -235.059446)
			(xy 4.192328 -235.083003) (xy 4.256587 -235.113948) (xy 4.316978 -235.151894) (xy 4.37274 -235.196363)
			(xy 4.423173 -235.246796) (xy 4.467642 -235.302558) (xy 4.505588 -235.362949) (xy 4.536533 -235.427208)
			(xy 4.56009 -235.494528) (xy 4.57596 -235.564063) (xy 4.583946 -235.634937) (xy 4.583946 -235.706259)
			(xy 5.813798 -235.706259) (xy 5.813798 -235.634937) (xy 5.821784 -235.564063) (xy 5.837654 -235.494528)
			(xy 5.861211 -235.427208) (xy 5.892156 -235.362949) (xy 5.930102 -235.302558) (xy 5.974571 -235.246796)
			(xy 6.025004 -235.196363) (xy 6.080766 -235.151894) (xy 6.141157 -235.113948) (xy 6.205416 -235.083003)
			(xy 6.272736 -235.059446) (xy 6.342271 -235.043576) (xy 6.413145 -235.03559) (xy 6.448806 -235.03509)
			(xy 6.484467 -235.03559) (xy 6.555341 -235.043576) (xy 6.624876 -235.059446) (xy 6.692196 -235.083003)
			(xy 6.756455 -235.113948) (xy 6.816846 -235.151894) (xy 6.872608 -235.196363) (xy 6.923041 -235.246796)
			(xy 6.96751 -235.302558) (xy 7.005456 -235.362949) (xy 7.036401 -235.427208) (xy 7.059958 -235.494528)
			(xy 7.075828 -235.564063) (xy 7.083814 -235.634937) (xy 7.083814 -235.706259) (xy 7.075828 -235.777133)
			(xy 7.059958 -235.846668) (xy 7.036401 -235.913988) (xy 7.005456 -235.978247) (xy 6.96751 -236.038638)
			(xy 6.923041 -236.0944) (xy 6.872608 -236.144833) (xy 6.816846 -236.189302) (xy 6.756455 -236.227248)
			(xy 6.692196 -236.258193) (xy 6.624876 -236.28175) (xy 6.555341 -236.29762) (xy 6.484467 -236.305606)
			(xy 6.413145 -236.305606) (xy 6.342271 -236.29762) (xy 6.272736 -236.28175) (xy 6.205416 -236.258193)
			(xy 6.141157 -236.227248) (xy 6.080766 -236.189302) (xy 6.025004 -236.144833) (xy 5.974571 -236.0944)
			(xy 5.930102 -236.038638) (xy 5.892156 -235.978247) (xy 5.861211 -235.913988) (xy 5.837654 -235.846668)
			(xy 5.821784 -235.777133) (xy 5.813798 -235.706259) (xy 4.583946 -235.706259) (xy 4.57596 -235.777133)
			(xy 4.56009 -235.846668) (xy 4.536533 -235.913988) (xy 4.505588 -235.978247) (xy 4.467642 -236.038638)
			(xy 4.423173 -236.0944) (xy 4.37274 -236.144833) (xy 4.316978 -236.189302) (xy 4.256587 -236.227248)
			(xy 4.192328 -236.258193) (xy 4.125008 -236.28175) (xy 4.055473 -236.29762) (xy 3.984599 -236.305606)
			(xy 3.913277 -236.305606) (xy 3.842403 -236.29762) (xy 3.772868 -236.28175) (xy 3.705548 -236.258193)
			(xy 3.641289 -236.227248) (xy 3.580898 -236.189302) (xy 3.525136 -236.144833) (xy 3.474703 -236.0944)
			(xy 3.430234 -236.038638) (xy 3.392288 -235.978247) (xy 3.361343 -235.913988) (xy 3.337786 -235.846668)
			(xy 3.321916 -235.777133) (xy 3.31393 -235.706259) (xy 0.509016 -235.706259) (xy 0.509016 -236.706257)
			(xy 1.313934 -236.706257) (xy 1.313934 -236.634935) (xy 1.32192 -236.564061) (xy 1.33779 -236.494526)
			(xy 1.361347 -236.427206) (xy 1.392292 -236.362947) (xy 1.430238 -236.302556) (xy 1.474707 -236.246794)
			(xy 1.52514 -236.196361) (xy 1.580902 -236.151892) (xy 1.641293 -236.113946) (xy 1.705552 -236.083001)
			(xy 1.772872 -236.059444) (xy 1.842407 -236.043574) (xy 1.913281 -236.035588) (xy 1.948942 -236.035088)
			(xy 1.984603 -236.035588) (xy 2.055477 -236.043574) (xy 2.125012 -236.059444) (xy 2.192332 -236.083001)
			(xy 2.256591 -236.113946) (xy 2.316982 -236.151892) (xy 2.372744 -236.196361) (xy 2.423177 -236.246794)
			(xy 2.467646 -236.302556) (xy 2.505592 -236.362947) (xy 2.536537 -236.427206) (xy 2.560094 -236.494526)
			(xy 2.575964 -236.564061) (xy 2.58395 -236.634935) (xy 2.58395 -236.706257) (xy 2.575964 -236.777131)
			(xy 2.560094 -236.846666) (xy 2.536537 -236.913986) (xy 2.505592 -236.978245) (xy 2.467646 -237.038636)
			(xy 2.423177 -237.094398) (xy 2.372744 -237.144831) (xy 2.316982 -237.1893) (xy 2.256591 -237.227246)
			(xy 2.192332 -237.258191) (xy 2.125012 -237.281748) (xy 2.055477 -237.297618) (xy 1.984603 -237.305604)
			(xy 1.913281 -237.305604) (xy 1.842407 -237.297618) (xy 1.772872 -237.281748) (xy 1.705552 -237.258191)
			(xy 1.641293 -237.227246) (xy 1.580902 -237.1893) (xy 1.52514 -237.144831) (xy 1.474707 -237.094398)
			(xy 1.430238 -237.038636) (xy 1.392292 -236.978245) (xy 1.361347 -236.913986) (xy 1.33779 -236.846666)
			(xy 1.32192 -236.777131) (xy 1.313934 -236.706257) (xy 0.509016 -236.706257) (xy 0.509016 -237.706255)
			(xy 3.31393 -237.706255) (xy 3.31393 -237.634933) (xy 3.321916 -237.564059) (xy 3.337786 -237.494524)
			(xy 3.361343 -237.427204) (xy 3.392288 -237.362945) (xy 3.430234 -237.302554) (xy 3.474703 -237.246792)
			(xy 3.525136 -237.196359) (xy 3.580898 -237.15189) (xy 3.641289 -237.113944) (xy 3.705548 -237.082999)
			(xy 3.772868 -237.059442) (xy 3.842403 -237.043572) (xy 3.913277 -237.035586) (xy 3.948938 -237.035086)
			(xy 3.984599 -237.035586) (xy 4.055473 -237.043572) (xy 4.125008 -237.059442) (xy 4.192328 -237.082999)
			(xy 4.256587 -237.113944) (xy 4.316978 -237.15189) (xy 4.37274 -237.196359) (xy 4.423173 -237.246792)
			(xy 4.467642 -237.302554) (xy 4.505588 -237.362945) (xy 4.536533 -237.427204) (xy 4.56009 -237.494524)
			(xy 4.57596 -237.564059) (xy 4.583946 -237.634933) (xy 4.583946 -237.706255) (xy 5.813798 -237.706255)
			(xy 5.813798 -237.634933) (xy 5.821784 -237.564059) (xy 5.837654 -237.494524) (xy 5.861211 -237.427204)
			(xy 5.892156 -237.362945) (xy 5.930102 -237.302554) (xy 5.974571 -237.246792) (xy 6.025004 -237.196359)
			(xy 6.080766 -237.15189) (xy 6.141157 -237.113944) (xy 6.205416 -237.082999) (xy 6.272736 -237.059442)
			(xy 6.342271 -237.043572) (xy 6.413145 -237.035586) (xy 6.448806 -237.035086) (xy 6.484467 -237.035586)
			(xy 6.555341 -237.043572) (xy 6.624876 -237.059442) (xy 6.692196 -237.082999) (xy 6.756455 -237.113944)
			(xy 6.816846 -237.15189) (xy 6.872608 -237.196359) (xy 6.923041 -237.246792) (xy 6.96751 -237.302554)
			(xy 7.005456 -237.362945) (xy 7.036401 -237.427204) (xy 7.059958 -237.494524) (xy 7.075828 -237.564059)
			(xy 7.083814 -237.634933) (xy 7.083814 -237.706255) (xy 7.075828 -237.777129) (xy 7.059958 -237.846664)
			(xy 7.036401 -237.913984) (xy 7.005456 -237.978243) (xy 6.96751 -238.038634) (xy 6.923041 -238.094396)
			(xy 6.872608 -238.144829) (xy 6.816846 -238.189298) (xy 6.756455 -238.227244) (xy 6.692196 -238.258189)
			(xy 6.624876 -238.281746) (xy 6.555341 -238.297616) (xy 6.484467 -238.305602) (xy 6.413145 -238.305602)
			(xy 6.342271 -238.297616) (xy 6.272736 -238.281746) (xy 6.205416 -238.258189) (xy 6.141157 -238.227244)
			(xy 6.080766 -238.189298) (xy 6.025004 -238.144829) (xy 5.974571 -238.094396) (xy 5.930102 -238.038634)
			(xy 5.892156 -237.978243) (xy 5.861211 -237.913984) (xy 5.837654 -237.846664) (xy 5.821784 -237.777129)
			(xy 5.813798 -237.706255) (xy 4.583946 -237.706255) (xy 4.57596 -237.777129) (xy 4.56009 -237.846664)
			(xy 4.536533 -237.913984) (xy 4.505588 -237.978243) (xy 4.467642 -238.038634) (xy 4.423173 -238.094396)
			(xy 4.37274 -238.144829) (xy 4.316978 -238.189298) (xy 4.256587 -238.227244) (xy 4.192328 -238.258189)
			(xy 4.125008 -238.281746) (xy 4.055473 -238.297616) (xy 3.984599 -238.305602) (xy 3.913277 -238.305602)
			(xy 3.842403 -238.297616) (xy 3.772868 -238.281746) (xy 3.705548 -238.258189) (xy 3.641289 -238.227244)
			(xy 3.580898 -238.189298) (xy 3.525136 -238.144829) (xy 3.474703 -238.094396) (xy 3.430234 -238.038634)
			(xy 3.392288 -237.978243) (xy 3.361343 -237.913984) (xy 3.337786 -237.846664) (xy 3.321916 -237.777129)
			(xy 3.31393 -237.706255) (xy 0.509016 -237.706255) (xy 0.509016 -238.706253) (xy 1.313934 -238.706253)
			(xy 1.313934 -238.634931) (xy 1.32192 -238.564057) (xy 1.33779 -238.494522) (xy 1.361347 -238.427202)
			(xy 1.392292 -238.362943) (xy 1.430238 -238.302552) (xy 1.474707 -238.24679) (xy 1.52514 -238.196357)
			(xy 1.580902 -238.151888) (xy 1.641293 -238.113942) (xy 1.705552 -238.082997) (xy 1.772872 -238.05944)
			(xy 1.842407 -238.04357) (xy 1.913281 -238.035584) (xy 1.948942 -238.035084) (xy 1.984603 -238.035584)
			(xy 2.055477 -238.04357) (xy 2.125012 -238.05944) (xy 2.192332 -238.082997) (xy 2.256591 -238.113942)
			(xy 2.316982 -238.151888) (xy 2.372744 -238.196357) (xy 2.423177 -238.24679) (xy 2.467646 -238.302552)
			(xy 2.505592 -238.362943) (xy 2.536537 -238.427202) (xy 2.560094 -238.494522) (xy 2.575964 -238.564057)
			(xy 2.58395 -238.634931) (xy 2.58395 -238.706253) (xy 7.813794 -238.706253) (xy 7.813794 -238.634931)
			(xy 7.82178 -238.564057) (xy 7.83765 -238.494522) (xy 7.861207 -238.427202) (xy 7.892152 -238.362943)
			(xy 7.930098 -238.302552) (xy 7.974567 -238.24679) (xy 8.025 -238.196357) (xy 8.080762 -238.151888)
			(xy 8.141153 -238.113942) (xy 8.205412 -238.082997) (xy 8.272732 -238.05944) (xy 8.342267 -238.04357)
			(xy 8.413141 -238.035584) (xy 8.448802 -238.035084) (xy 8.484463 -238.035584) (xy 8.555337 -238.04357)
			(xy 8.624872 -238.05944) (xy 8.692192 -238.082997) (xy 8.756451 -238.113942) (xy 8.816842 -238.151888)
			(xy 8.872604 -238.196357) (xy 8.923037 -238.24679) (xy 8.967506 -238.302552) (xy 9.005452 -238.362943)
			(xy 9.036397 -238.427202) (xy 9.059954 -238.494522) (xy 9.075824 -238.564057) (xy 9.08381 -238.634931)
			(xy 9.08381 -238.706253) (xy 9.075824 -238.777127) (xy 9.059954 -238.846662) (xy 9.036397 -238.913982)
			(xy 9.005452 -238.978241) (xy 8.967506 -239.038632) (xy 8.923037 -239.094394) (xy 8.872604 -239.144827)
			(xy 8.816842 -239.189296) (xy 8.756451 -239.227242) (xy 8.692192 -239.258187) (xy 8.624872 -239.281744)
			(xy 8.555337 -239.297614) (xy 8.484463 -239.3056) (xy 8.413141 -239.3056) (xy 8.342267 -239.297614)
			(xy 8.272732 -239.281744) (xy 8.205412 -239.258187) (xy 8.141153 -239.227242) (xy 8.080762 -239.189296)
			(xy 8.025 -239.144827) (xy 7.974567 -239.094394) (xy 7.930098 -239.038632) (xy 7.892152 -238.978241)
			(xy 7.861207 -238.913982) (xy 7.83765 -238.846662) (xy 7.82178 -238.777127) (xy 7.813794 -238.706253)
			(xy 2.58395 -238.706253) (xy 2.575964 -238.777127) (xy 2.560094 -238.846662) (xy 2.536537 -238.913982)
			(xy 2.505592 -238.978241) (xy 2.467646 -239.038632) (xy 2.423177 -239.094394) (xy 2.372744 -239.144827)
			(xy 2.316982 -239.189296) (xy 2.256591 -239.227242) (xy 2.192332 -239.258187) (xy 2.125012 -239.281744)
			(xy 2.055477 -239.297614) (xy 1.984603 -239.3056) (xy 1.913281 -239.3056) (xy 1.842407 -239.297614)
			(xy 1.772872 -239.281744) (xy 1.705552 -239.258187) (xy 1.641293 -239.227242) (xy 1.580902 -239.189296)
			(xy 1.52514 -239.144827) (xy 1.474707 -239.094394) (xy 1.430238 -239.038632) (xy 1.392292 -238.978241)
			(xy 1.361347 -238.913982) (xy 1.33779 -238.846662) (xy 1.32192 -238.777127) (xy 1.313934 -238.706253)
			(xy 0.509016 -238.706253) (xy 0.509016 -239.706251) (xy 5.813798 -239.706251) (xy 5.813798 -239.634929)
			(xy 5.821784 -239.564055) (xy 5.837654 -239.49452) (xy 5.861211 -239.4272) (xy 5.892156 -239.362941)
			(xy 5.930102 -239.30255) (xy 5.974571 -239.246788) (xy 6.025004 -239.196355) (xy 6.080766 -239.151886)
			(xy 6.141157 -239.11394) (xy 6.205416 -239.082995) (xy 6.272736 -239.059438) (xy 6.342271 -239.043568)
			(xy 6.413145 -239.035582) (xy 6.448806 -239.035082) (xy 6.484467 -239.035582) (xy 6.555341 -239.043568)
			(xy 6.624876 -239.059438) (xy 6.692196 -239.082995) (xy 6.756455 -239.11394) (xy 6.816846 -239.151886)
			(xy 6.872608 -239.196355) (xy 6.923041 -239.246788) (xy 6.96751 -239.30255) (xy 7.005456 -239.362941)
			(xy 7.036401 -239.4272) (xy 7.059958 -239.49452) (xy 7.075828 -239.564055) (xy 7.083814 -239.634929)
			(xy 7.083814 -239.706251) (xy 7.075828 -239.777125) (xy 7.059958 -239.84666) (xy 7.036401 -239.91398)
			(xy 7.005456 -239.978239) (xy 6.96751 -240.03863) (xy 6.923041 -240.094392) (xy 6.872608 -240.144825)
			(xy 6.816846 -240.189294) (xy 6.756455 -240.22724) (xy 6.692196 -240.258185) (xy 6.624876 -240.281742)
			(xy 6.555341 -240.297612) (xy 6.484467 -240.305598) (xy 6.413145 -240.305598) (xy 6.342271 -240.297612)
			(xy 6.272736 -240.281742) (xy 6.205416 -240.258185) (xy 6.141157 -240.22724) (xy 6.080766 -240.189294)
			(xy 6.025004 -240.144825) (xy 5.974571 -240.094392) (xy 5.930102 -240.03863) (xy 5.892156 -239.978239)
			(xy 5.861211 -239.91398) (xy 5.837654 -239.84666) (xy 5.821784 -239.777125) (xy 5.813798 -239.706251)
			(xy 0.509016 -239.706251) (xy 0.509016 -240.706249) (xy 1.313934 -240.706249) (xy 1.313934 -240.634927)
			(xy 1.32192 -240.564053) (xy 1.33779 -240.494518) (xy 1.361347 -240.427198) (xy 1.392292 -240.362939)
			(xy 1.430238 -240.302548) (xy 1.474707 -240.246786) (xy 1.52514 -240.196353) (xy 1.580902 -240.151884)
			(xy 1.641293 -240.113938) (xy 1.705552 -240.082993) (xy 1.772872 -240.059436) (xy 1.842407 -240.043566)
			(xy 1.913281 -240.03558) (xy 1.948942 -240.03508) (xy 1.984603 -240.03558) (xy 2.055477 -240.043566)
			(xy 2.125012 -240.059436) (xy 2.192332 -240.082993) (xy 2.256591 -240.113938) (xy 2.316982 -240.151884)
			(xy 2.372744 -240.196353) (xy 2.423177 -240.246786) (xy 2.467646 -240.302548) (xy 2.505592 -240.362939)
			(xy 2.536537 -240.427198) (xy 2.560094 -240.494518) (xy 2.575964 -240.564053) (xy 2.58395 -240.634927)
			(xy 2.58395 -240.706249) (xy 7.813794 -240.706249) (xy 7.813794 -240.634927) (xy 7.82178 -240.564053)
			(xy 7.83765 -240.494518) (xy 7.861207 -240.427198) (xy 7.892152 -240.362939) (xy 7.930098 -240.302548)
			(xy 7.974567 -240.246786) (xy 8.025 -240.196353) (xy 8.080762 -240.151884) (xy 8.141153 -240.113938)
			(xy 8.205412 -240.082993) (xy 8.272732 -240.059436) (xy 8.342267 -240.043566) (xy 8.413141 -240.03558)
			(xy 8.448802 -240.03508) (xy 8.484463 -240.03558) (xy 8.555337 -240.043566) (xy 8.624872 -240.059436)
			(xy 8.692192 -240.082993) (xy 8.756451 -240.113938) (xy 8.816842 -240.151884) (xy 8.872604 -240.196353)
			(xy 8.923037 -240.246786) (xy 8.967506 -240.302548) (xy 9.005452 -240.362939) (xy 9.036397 -240.427198)
			(xy 9.059954 -240.494518) (xy 9.075824 -240.564053) (xy 9.08381 -240.634927) (xy 9.08381 -240.706249)
			(xy 9.075824 -240.777123) (xy 9.059954 -240.846658) (xy 9.036397 -240.913978) (xy 9.005452 -240.978237)
			(xy 8.967506 -241.038628) (xy 8.923037 -241.09439) (xy 8.872604 -241.144823) (xy 8.816842 -241.189292)
			(xy 8.756451 -241.227238) (xy 8.692192 -241.258183) (xy 8.624872 -241.28174) (xy 8.555337 -241.29761)
			(xy 8.484463 -241.305596) (xy 8.413141 -241.305596) (xy 8.342267 -241.29761) (xy 8.272732 -241.28174)
			(xy 8.205412 -241.258183) (xy 8.141153 -241.227238) (xy 8.080762 -241.189292) (xy 8.025 -241.144823)
			(xy 7.974567 -241.09439) (xy 7.930098 -241.038628) (xy 7.892152 -240.978237) (xy 7.861207 -240.913978)
			(xy 7.83765 -240.846658) (xy 7.82178 -240.777123) (xy 7.813794 -240.706249) (xy 2.58395 -240.706249)
			(xy 2.575964 -240.777123) (xy 2.560094 -240.846658) (xy 2.536537 -240.913978) (xy 2.505592 -240.978237)
			(xy 2.467646 -241.038628) (xy 2.423177 -241.09439) (xy 2.372744 -241.144823) (xy 2.316982 -241.189292)
			(xy 2.256591 -241.227238) (xy 2.192332 -241.258183) (xy 2.125012 -241.28174) (xy 2.055477 -241.29761)
			(xy 1.984603 -241.305596) (xy 1.913281 -241.305596) (xy 1.842407 -241.29761) (xy 1.772872 -241.28174)
			(xy 1.705552 -241.258183) (xy 1.641293 -241.227238) (xy 1.580902 -241.189292) (xy 1.52514 -241.144823)
			(xy 1.474707 -241.09439) (xy 1.430238 -241.038628) (xy 1.392292 -240.978237) (xy 1.361347 -240.913978)
			(xy 1.33779 -240.846658) (xy 1.32192 -240.777123) (xy 1.313934 -240.706249) (xy 0.509016 -240.706249)
			(xy 0.509016 -241.706247) (xy 3.31393 -241.706247) (xy 3.31393 -241.634925) (xy 3.321916 -241.564051)
			(xy 3.337786 -241.494516) (xy 3.361343 -241.427196) (xy 3.392288 -241.362937) (xy 3.430234 -241.302546)
			(xy 3.474703 -241.246784) (xy 3.525136 -241.196351) (xy 3.580898 -241.151882) (xy 3.641289 -241.113936)
			(xy 3.705548 -241.082991) (xy 3.772868 -241.059434) (xy 3.842403 -241.043564) (xy 3.913277 -241.035578)
			(xy 3.948938 -241.035078) (xy 3.984599 -241.035578) (xy 4.055473 -241.043564) (xy 4.125008 -241.059434)
			(xy 4.192328 -241.082991) (xy 4.256587 -241.113936) (xy 4.316978 -241.151882) (xy 4.37274 -241.196351)
			(xy 4.423173 -241.246784) (xy 4.467642 -241.302546) (xy 4.505588 -241.362937) (xy 4.536533 -241.427196)
			(xy 4.56009 -241.494516) (xy 4.57596 -241.564051) (xy 4.583946 -241.634925) (xy 4.583946 -241.706247)
			(xy 4.57596 -241.777121) (xy 4.56009 -241.846656) (xy 4.536533 -241.913976) (xy 4.505588 -241.978235)
			(xy 4.467642 -242.038626) (xy 4.423173 -242.094388) (xy 4.37274 -242.144821) (xy 4.316978 -242.18929)
			(xy 4.256587 -242.227236) (xy 4.192328 -242.258181) (xy 4.125008 -242.281738) (xy 4.055473 -242.297608)
			(xy 3.984599 -242.305594) (xy 3.913277 -242.305594) (xy 3.842403 -242.297608) (xy 3.772868 -242.281738)
			(xy 3.705548 -242.258181) (xy 3.641289 -242.227236) (xy 3.580898 -242.18929) (xy 3.525136 -242.144821)
			(xy 3.474703 -242.094388) (xy 3.430234 -242.038626) (xy 3.392288 -241.978235) (xy 3.361343 -241.913976)
			(xy 3.337786 -241.846656) (xy 3.321916 -241.777121) (xy 3.31393 -241.706247) (xy 0.509016 -241.706247)
			(xy 0.509016 -242.706245) (xy 1.313934 -242.706245) (xy 1.313934 -242.634923) (xy 1.32192 -242.564049)
			(xy 1.33779 -242.494514) (xy 1.361347 -242.427194) (xy 1.392292 -242.362935) (xy 1.430238 -242.302544)
			(xy 1.474707 -242.246782) (xy 1.52514 -242.196349) (xy 1.580902 -242.15188) (xy 1.641293 -242.113934)
			(xy 1.705552 -242.082989) (xy 1.772872 -242.059432) (xy 1.842407 -242.043562) (xy 1.913281 -242.035576)
			(xy 1.948942 -242.035076) (xy 1.984603 -242.035576) (xy 2.055477 -242.043562) (xy 2.125012 -242.059432)
			(xy 2.192332 -242.082989) (xy 2.256591 -242.113934) (xy 2.316982 -242.15188) (xy 2.372744 -242.196349)
			(xy 2.423177 -242.246782) (xy 2.467646 -242.302544) (xy 2.505592 -242.362935) (xy 2.536537 -242.427194)
			(xy 2.560094 -242.494514) (xy 2.575964 -242.564049) (xy 2.58395 -242.634923) (xy 2.58395 -242.706245)
			(xy 7.813794 -242.706245) (xy 7.813794 -242.634923) (xy 7.82178 -242.564049) (xy 7.83765 -242.494514)
			(xy 7.861207 -242.427194) (xy 7.892152 -242.362935) (xy 7.930098 -242.302544) (xy 7.974567 -242.246782)
			(xy 8.025 -242.196349) (xy 8.080762 -242.15188) (xy 8.141153 -242.113934) (xy 8.205412 -242.082989)
			(xy 8.272732 -242.059432) (xy 8.342267 -242.043562) (xy 8.413141 -242.035576) (xy 8.448802 -242.035076)
			(xy 8.484463 -242.035576) (xy 8.555337 -242.043562) (xy 8.624872 -242.059432) (xy 8.692192 -242.082989)
			(xy 8.756451 -242.113934) (xy 8.816842 -242.15188) (xy 8.872604 -242.196349) (xy 8.923037 -242.246782)
			(xy 8.967506 -242.302544) (xy 9.005452 -242.362935) (xy 9.036397 -242.427194) (xy 9.059954 -242.494514)
			(xy 9.075824 -242.564049) (xy 9.08381 -242.634923) (xy 9.08381 -242.706245) (xy 9.075824 -242.777119)
			(xy 9.059954 -242.846654) (xy 9.036397 -242.913974) (xy 9.005452 -242.978233) (xy 8.967506 -243.038624)
			(xy 8.923037 -243.094386) (xy 8.872604 -243.144819) (xy 8.816842 -243.189288) (xy 8.756451 -243.227234)
			(xy 8.692192 -243.258179) (xy 8.624872 -243.281736) (xy 8.555337 -243.297606) (xy 8.484463 -243.305592)
			(xy 8.413141 -243.305592) (xy 8.342267 -243.297606) (xy 8.272732 -243.281736) (xy 8.205412 -243.258179)
			(xy 8.141153 -243.227234) (xy 8.080762 -243.189288) (xy 8.025 -243.144819) (xy 7.974567 -243.094386)
			(xy 7.930098 -243.038624) (xy 7.892152 -242.978233) (xy 7.861207 -242.913974) (xy 7.83765 -242.846654)
			(xy 7.82178 -242.777119) (xy 7.813794 -242.706245) (xy 2.58395 -242.706245) (xy 2.575964 -242.777119)
			(xy 2.560094 -242.846654) (xy 2.536537 -242.913974) (xy 2.505592 -242.978233) (xy 2.467646 -243.038624)
			(xy 2.423177 -243.094386) (xy 2.372744 -243.144819) (xy 2.316982 -243.189288) (xy 2.256591 -243.227234)
			(xy 2.192332 -243.258179) (xy 2.125012 -243.281736) (xy 2.055477 -243.297606) (xy 1.984603 -243.305592)
			(xy 1.913281 -243.305592) (xy 1.842407 -243.297606) (xy 1.772872 -243.281736) (xy 1.705552 -243.258179)
			(xy 1.641293 -243.227234) (xy 1.580902 -243.189288) (xy 1.52514 -243.144819) (xy 1.474707 -243.094386)
			(xy 1.430238 -243.038624) (xy 1.392292 -242.978233) (xy 1.361347 -242.913974) (xy 1.33779 -242.846654)
			(xy 1.32192 -242.777119) (xy 1.313934 -242.706245) (xy 0.509016 -242.706245) (xy 0.509016 -243.706243)
			(xy 3.31393 -243.706243) (xy 3.31393 -243.634921) (xy 3.321916 -243.564047) (xy 3.337786 -243.494512)
			(xy 3.361343 -243.427192) (xy 3.392288 -243.362933) (xy 3.430234 -243.302542) (xy 3.474703 -243.24678)
			(xy 3.525136 -243.196347) (xy 3.580898 -243.151878) (xy 3.641289 -243.113932) (xy 3.705548 -243.082987)
			(xy 3.772868 -243.05943) (xy 3.842403 -243.04356) (xy 3.913277 -243.035574) (xy 3.948938 -243.035074)
			(xy 3.984599 -243.035574) (xy 4.055473 -243.04356) (xy 4.125008 -243.05943) (xy 4.192328 -243.082987)
			(xy 4.256587 -243.113932) (xy 4.316978 -243.151878) (xy 4.37274 -243.196347) (xy 4.423173 -243.24678)
			(xy 4.467642 -243.302542) (xy 4.505588 -243.362933) (xy 4.536533 -243.427192) (xy 4.56009 -243.494512)
			(xy 4.57596 -243.564047) (xy 4.583946 -243.634921) (xy 4.583946 -243.706243) (xy 5.813798 -243.706243)
			(xy 5.813798 -243.634921) (xy 5.821784 -243.564047) (xy 5.837654 -243.494512) (xy 5.861211 -243.427192)
			(xy 5.892156 -243.362933) (xy 5.930102 -243.302542) (xy 5.974571 -243.24678) (xy 6.025004 -243.196347)
			(xy 6.080766 -243.151878) (xy 6.141157 -243.113932) (xy 6.205416 -243.082987) (xy 6.272736 -243.05943)
			(xy 6.342271 -243.04356) (xy 6.413145 -243.035574) (xy 6.448806 -243.035074) (xy 6.484467 -243.035574)
			(xy 6.555341 -243.04356) (xy 6.624876 -243.05943) (xy 6.692196 -243.082987) (xy 6.756455 -243.113932)
			(xy 6.816846 -243.151878) (xy 6.872608 -243.196347) (xy 6.923041 -243.24678) (xy 6.96751 -243.302542)
			(xy 7.005456 -243.362933) (xy 7.036401 -243.427192) (xy 7.059958 -243.494512) (xy 7.075828 -243.564047)
			(xy 7.083814 -243.634921) (xy 7.083814 -243.706243) (xy 7.075828 -243.777117) (xy 7.059958 -243.846652)
			(xy 7.036401 -243.913972) (xy 7.005456 -243.978231) (xy 6.96751 -244.038622) (xy 6.923041 -244.094384)
			(xy 6.872608 -244.144817) (xy 6.816846 -244.189286) (xy 6.756455 -244.227232) (xy 6.692196 -244.258177)
			(xy 6.624876 -244.281734) (xy 6.555341 -244.297604) (xy 6.484467 -244.30559) (xy 6.413145 -244.30559)
			(xy 6.342271 -244.297604) (xy 6.272736 -244.281734) (xy 6.205416 -244.258177) (xy 6.141157 -244.227232)
			(xy 6.080766 -244.189286) (xy 6.025004 -244.144817) (xy 5.974571 -244.094384) (xy 5.930102 -244.038622)
			(xy 5.892156 -243.978231) (xy 5.861211 -243.913972) (xy 5.837654 -243.846652) (xy 5.821784 -243.777117)
			(xy 5.813798 -243.706243) (xy 4.583946 -243.706243) (xy 4.57596 -243.777117) (xy 4.56009 -243.846652)
			(xy 4.536533 -243.913972) (xy 4.505588 -243.978231) (xy 4.467642 -244.038622) (xy 4.423173 -244.094384)
			(xy 4.37274 -244.144817) (xy 4.316978 -244.189286) (xy 4.256587 -244.227232) (xy 4.192328 -244.258177)
			(xy 4.125008 -244.281734) (xy 4.055473 -244.297604) (xy 3.984599 -244.30559) (xy 3.913277 -244.30559)
			(xy 3.842403 -244.297604) (xy 3.772868 -244.281734) (xy 3.705548 -244.258177) (xy 3.641289 -244.227232)
			(xy 3.580898 -244.189286) (xy 3.525136 -244.144817) (xy 3.474703 -244.094384) (xy 3.430234 -244.038622)
			(xy 3.392288 -243.978231) (xy 3.361343 -243.913972) (xy 3.337786 -243.846652) (xy 3.321916 -243.777117)
			(xy 3.31393 -243.706243) (xy 0.509016 -243.706243) (xy 0.509016 -244.706241) (xy 7.813794 -244.706241)
			(xy 7.813794 -244.634919) (xy 7.82178 -244.564045) (xy 7.83765 -244.49451) (xy 7.861207 -244.42719)
			(xy 7.892152 -244.362931) (xy 7.930098 -244.30254) (xy 7.974567 -244.246778) (xy 8.025 -244.196345)
			(xy 8.080762 -244.151876) (xy 8.141153 -244.11393) (xy 8.205412 -244.082985) (xy 8.272732 -244.059428)
			(xy 8.342267 -244.043558) (xy 8.413141 -244.035572) (xy 8.448802 -244.035072) (xy 8.484463 -244.035572)
			(xy 8.555337 -244.043558) (xy 8.624872 -244.059428) (xy 8.692192 -244.082985) (xy 8.756451 -244.11393)
			(xy 8.816842 -244.151876) (xy 8.872604 -244.196345) (xy 8.923037 -244.246778) (xy 8.967506 -244.30254)
			(xy 9.005452 -244.362931) (xy 9.036397 -244.42719) (xy 9.059954 -244.49451) (xy 9.075824 -244.564045)
			(xy 9.08381 -244.634919) (xy 9.08381 -244.706241) (xy 9.075824 -244.777115) (xy 9.059954 -244.84665)
			(xy 9.036397 -244.91397) (xy 9.005452 -244.978229) (xy 8.967506 -245.03862) (xy 8.923037 -245.094382)
			(xy 8.872604 -245.144815) (xy 8.816842 -245.189284) (xy 8.756451 -245.22723) (xy 8.692192 -245.258175)
			(xy 8.624872 -245.281732) (xy 8.555337 -245.297602) (xy 8.484463 -245.305588) (xy 8.413141 -245.305588)
			(xy 8.342267 -245.297602) (xy 8.272732 -245.281732) (xy 8.205412 -245.258175) (xy 8.141153 -245.22723)
			(xy 8.080762 -245.189284) (xy 8.025 -245.144815) (xy 7.974567 -245.094382) (xy 7.930098 -245.03862)
			(xy 7.892152 -244.978229) (xy 7.861207 -244.91397) (xy 7.83765 -244.84665) (xy 7.82178 -244.777115)
			(xy 7.813794 -244.706241) (xy 0.509016 -244.706241) (xy 0.509016 -245.706239) (xy 3.31393 -245.706239)
			(xy 3.31393 -245.634917) (xy 3.321916 -245.564043) (xy 3.337786 -245.494508) (xy 3.361343 -245.427188)
			(xy 3.392288 -245.362929) (xy 3.430234 -245.302538) (xy 3.474703 -245.246776) (xy 3.525136 -245.196343)
			(xy 3.580898 -245.151874) (xy 3.641289 -245.113928) (xy 3.705548 -245.082983) (xy 3.772868 -245.059426)
			(xy 3.842403 -245.043556) (xy 3.913277 -245.03557) (xy 3.948938 -245.03507) (xy 3.984599 -245.03557)
			(xy 4.055473 -245.043556) (xy 4.125008 -245.059426) (xy 4.192328 -245.082983) (xy 4.256587 -245.113928)
			(xy 4.316978 -245.151874) (xy 4.37274 -245.196343) (xy 4.423173 -245.246776) (xy 4.467642 -245.302538)
			(xy 4.505588 -245.362929) (xy 4.536533 -245.427188) (xy 4.56009 -245.494508) (xy 4.57596 -245.564043)
			(xy 4.583946 -245.634917) (xy 4.583946 -245.706239) (xy 5.813798 -245.706239) (xy 5.813798 -245.634917)
			(xy 5.821784 -245.564043) (xy 5.837654 -245.494508) (xy 5.861211 -245.427188) (xy 5.892156 -245.362929)
			(xy 5.930102 -245.302538) (xy 5.974571 -245.246776) (xy 6.025004 -245.196343) (xy 6.080766 -245.151874)
			(xy 6.141157 -245.113928) (xy 6.205416 -245.082983) (xy 6.272736 -245.059426) (xy 6.342271 -245.043556)
			(xy 6.413145 -245.03557) (xy 6.448806 -245.03507) (xy 6.484467 -245.03557) (xy 6.555341 -245.043556)
			(xy 6.624876 -245.059426) (xy 6.692196 -245.082983) (xy 6.756455 -245.113928) (xy 6.816846 -245.151874)
			(xy 6.872608 -245.196343) (xy 6.923041 -245.246776) (xy 6.96751 -245.302538) (xy 7.005456 -245.362929)
			(xy 7.036401 -245.427188) (xy 7.059958 -245.494508) (xy 7.075828 -245.564043) (xy 7.083814 -245.634917)
			(xy 7.083814 -245.706239) (xy 7.075828 -245.777113) (xy 7.059958 -245.846648) (xy 7.036401 -245.913968)
			(xy 7.005456 -245.978227) (xy 6.96751 -246.038618) (xy 6.923041 -246.09438) (xy 6.872608 -246.144813)
			(xy 6.816846 -246.189282) (xy 6.756455 -246.227228) (xy 6.692196 -246.258173) (xy 6.624876 -246.28173)
			(xy 6.555341 -246.2976) (xy 6.484467 -246.305586) (xy 6.413145 -246.305586) (xy 6.342271 -246.2976)
			(xy 6.272736 -246.28173) (xy 6.205416 -246.258173) (xy 6.141157 -246.227228) (xy 6.080766 -246.189282)
			(xy 6.025004 -246.144813) (xy 5.974571 -246.09438) (xy 5.930102 -246.038618) (xy 5.892156 -245.978227)
			(xy 5.861211 -245.913968) (xy 5.837654 -245.846648) (xy 5.821784 -245.777113) (xy 5.813798 -245.706239)
			(xy 4.583946 -245.706239) (xy 4.57596 -245.777113) (xy 4.56009 -245.846648) (xy 4.536533 -245.913968)
			(xy 4.505588 -245.978227) (xy 4.467642 -246.038618) (xy 4.423173 -246.09438) (xy 4.37274 -246.144813)
			(xy 4.316978 -246.189282) (xy 4.256587 -246.227228) (xy 4.192328 -246.258173) (xy 4.125008 -246.28173)
			(xy 4.055473 -246.2976) (xy 3.984599 -246.305586) (xy 3.913277 -246.305586) (xy 3.842403 -246.2976)
			(xy 3.772868 -246.28173) (xy 3.705548 -246.258173) (xy 3.641289 -246.227228) (xy 3.580898 -246.189282)
			(xy 3.525136 -246.144813) (xy 3.474703 -246.09438) (xy 3.430234 -246.038618) (xy 3.392288 -245.978227)
			(xy 3.361343 -245.913968) (xy 3.337786 -245.846648) (xy 3.321916 -245.777113) (xy 3.31393 -245.706239)
			(xy 0.509016 -245.706239) (xy 0.509016 -246.706237) (xy 1.313934 -246.706237) (xy 1.313934 -246.634915)
			(xy 1.32192 -246.564041) (xy 1.33779 -246.494506) (xy 1.361347 -246.427186) (xy 1.392292 -246.362927)
			(xy 1.430238 -246.302536) (xy 1.474707 -246.246774) (xy 1.52514 -246.196341) (xy 1.580902 -246.151872)
			(xy 1.641293 -246.113926) (xy 1.705552 -246.082981) (xy 1.772872 -246.059424) (xy 1.842407 -246.043554)
			(xy 1.913281 -246.035568) (xy 1.948942 -246.035068) (xy 1.984603 -246.035568) (xy 2.055477 -246.043554)
			(xy 2.125012 -246.059424) (xy 2.192332 -246.082981) (xy 2.256591 -246.113926) (xy 2.316982 -246.151872)
			(xy 2.372744 -246.196341) (xy 2.423177 -246.246774) (xy 2.467646 -246.302536) (xy 2.505592 -246.362927)
			(xy 2.536537 -246.427186) (xy 2.560094 -246.494506) (xy 2.575964 -246.564041) (xy 2.58395 -246.634915)
			(xy 2.58395 -246.706237) (xy 2.575964 -246.777111) (xy 2.560094 -246.846646) (xy 2.536537 -246.913966)
			(xy 2.505592 -246.978225) (xy 2.467646 -247.038616) (xy 2.423177 -247.094378) (xy 2.372744 -247.144811)
			(xy 2.316982 -247.18928) (xy 2.256591 -247.227226) (xy 2.192332 -247.258171) (xy 2.125012 -247.281728)
			(xy 2.055477 -247.297598) (xy 1.984603 -247.305584) (xy 1.913281 -247.305584) (xy 1.842407 -247.297598)
			(xy 1.772872 -247.281728) (xy 1.705552 -247.258171) (xy 1.641293 -247.227226) (xy 1.580902 -247.18928)
			(xy 1.52514 -247.144811) (xy 1.474707 -247.094378) (xy 1.430238 -247.038616) (xy 1.392292 -246.978225)
			(xy 1.361347 -246.913966) (xy 1.33779 -246.846646) (xy 1.32192 -246.777111) (xy 1.313934 -246.706237)
			(xy 0.509016 -246.706237) (xy 0.509016 -247.706235) (xy 3.31393 -247.706235) (xy 3.31393 -247.634913)
			(xy 3.321916 -247.564039) (xy 3.337786 -247.494504) (xy 3.361343 -247.427184) (xy 3.392288 -247.362925)
			(xy 3.430234 -247.302534) (xy 3.474703 -247.246772) (xy 3.525136 -247.196339) (xy 3.580898 -247.15187)
			(xy 3.641289 -247.113924) (xy 3.705548 -247.082979) (xy 3.772868 -247.059422) (xy 3.842403 -247.043552)
			(xy 3.913277 -247.035566) (xy 3.948938 -247.035066) (xy 3.984599 -247.035566) (xy 4.055473 -247.043552)
			(xy 4.125008 -247.059422) (xy 4.192328 -247.082979) (xy 4.256587 -247.113924) (xy 4.316978 -247.15187)
			(xy 4.37274 -247.196339) (xy 4.423173 -247.246772) (xy 4.467642 -247.302534) (xy 4.505588 -247.362925)
			(xy 4.536533 -247.427184) (xy 4.56009 -247.494504) (xy 4.57596 -247.564039) (xy 4.583946 -247.634913)
			(xy 4.583946 -247.706235) (xy 5.813798 -247.706235) (xy 5.813798 -247.634913) (xy 5.821784 -247.564039)
			(xy 5.837654 -247.494504) (xy 5.861211 -247.427184) (xy 5.892156 -247.362925) (xy 5.930102 -247.302534)
			(xy 5.974571 -247.246772) (xy 6.025004 -247.196339) (xy 6.080766 -247.15187) (xy 6.141157 -247.113924)
			(xy 6.205416 -247.082979) (xy 6.272736 -247.059422) (xy 6.342271 -247.043552) (xy 6.413145 -247.035566)
			(xy 6.448806 -247.035066) (xy 6.484467 -247.035566) (xy 6.555341 -247.043552) (xy 6.624876 -247.059422)
			(xy 6.692196 -247.082979) (xy 6.756455 -247.113924) (xy 6.816846 -247.15187) (xy 6.872608 -247.196339)
			(xy 6.923041 -247.246772) (xy 6.96751 -247.302534) (xy 7.005456 -247.362925) (xy 7.036401 -247.427184)
			(xy 7.059958 -247.494504) (xy 7.075828 -247.564039) (xy 7.083814 -247.634913) (xy 7.083814 -247.706235)
			(xy 7.075828 -247.777109) (xy 7.059958 -247.846644) (xy 7.036401 -247.913964) (xy 7.005456 -247.978223)
			(xy 6.96751 -248.038614) (xy 6.923041 -248.094376) (xy 6.872608 -248.144809) (xy 6.816846 -248.189278)
			(xy 6.756455 -248.227224) (xy 6.692196 -248.258169) (xy 6.624876 -248.281726) (xy 6.555341 -248.297596)
			(xy 6.484467 -248.305582) (xy 6.413145 -248.305582) (xy 6.342271 -248.297596) (xy 6.272736 -248.281726)
			(xy 6.205416 -248.258169) (xy 6.141157 -248.227224) (xy 6.080766 -248.189278) (xy 6.025004 -248.144809)
			(xy 5.974571 -248.094376) (xy 5.930102 -248.038614) (xy 5.892156 -247.978223) (xy 5.861211 -247.913964)
			(xy 5.837654 -247.846644) (xy 5.821784 -247.777109) (xy 5.813798 -247.706235) (xy 4.583946 -247.706235)
			(xy 4.57596 -247.777109) (xy 4.56009 -247.846644) (xy 4.536533 -247.913964) (xy 4.505588 -247.978223)
			(xy 4.467642 -248.038614) (xy 4.423173 -248.094376) (xy 4.37274 -248.144809) (xy 4.316978 -248.189278)
			(xy 4.256587 -248.227224) (xy 4.192328 -248.258169) (xy 4.125008 -248.281726) (xy 4.055473 -248.297596)
			(xy 3.984599 -248.305582) (xy 3.913277 -248.305582) (xy 3.842403 -248.297596) (xy 3.772868 -248.281726)
			(xy 3.705548 -248.258169) (xy 3.641289 -248.227224) (xy 3.580898 -248.189278) (xy 3.525136 -248.144809)
			(xy 3.474703 -248.094376) (xy 3.430234 -248.038614) (xy 3.392288 -247.978223) (xy 3.361343 -247.913964)
			(xy 3.337786 -247.846644) (xy 3.321916 -247.777109) (xy 3.31393 -247.706235) (xy 0.509016 -247.706235)
			(xy 0.509016 -248.706233) (xy 1.313934 -248.706233) (xy 1.313934 -248.634911) (xy 1.32192 -248.564037)
			(xy 1.33779 -248.494502) (xy 1.361347 -248.427182) (xy 1.392292 -248.362923) (xy 1.430238 -248.302532)
			(xy 1.474707 -248.24677) (xy 1.52514 -248.196337) (xy 1.580902 -248.151868) (xy 1.641293 -248.113922)
			(xy 1.705552 -248.082977) (xy 1.772872 -248.05942) (xy 1.842407 -248.04355) (xy 1.913281 -248.035564)
			(xy 1.948942 -248.035064) (xy 1.984603 -248.035564) (xy 2.055477 -248.04355) (xy 2.125012 -248.05942)
			(xy 2.192332 -248.082977) (xy 2.256591 -248.113922) (xy 2.316982 -248.151868) (xy 2.372744 -248.196337)
			(xy 2.423177 -248.24677) (xy 2.467646 -248.302532) (xy 2.505592 -248.362923) (xy 2.536537 -248.427182)
			(xy 2.560094 -248.494502) (xy 2.575964 -248.564037) (xy 2.58395 -248.634911) (xy 2.58395 -248.706233)
			(xy 2.575964 -248.777107) (xy 2.560094 -248.846642) (xy 2.536537 -248.913962) (xy 2.505592 -248.978221)
			(xy 2.467646 -249.038612) (xy 2.423177 -249.094374) (xy 2.372744 -249.144807) (xy 2.316982 -249.189276)
			(xy 2.256591 -249.227222) (xy 2.192332 -249.258167) (xy 2.125012 -249.281724) (xy 2.055477 -249.297594)
			(xy 1.984603 -249.30558) (xy 1.913281 -249.30558) (xy 1.842407 -249.297594) (xy 1.772872 -249.281724)
			(xy 1.705552 -249.258167) (xy 1.641293 -249.227222) (xy 1.580902 -249.189276) (xy 1.52514 -249.144807)
			(xy 1.474707 -249.094374) (xy 1.430238 -249.038612) (xy 1.392292 -248.978221) (xy 1.361347 -248.913962)
			(xy 1.33779 -248.846642) (xy 1.32192 -248.777107) (xy 1.313934 -248.706233) (xy 0.509016 -248.706233)
			(xy 0.509016 -251.652726) (xy 3.313144 -251.652726) (xy 3.319107 -251.58188) (xy 3.33294 -251.512142)
			(xy 3.35447 -251.444383) (xy 3.383429 -251.379451) (xy 3.419454 -251.318157) (xy 3.462095 -251.261266)
			(xy 3.510819 -251.209491) (xy 3.565018 -251.163477) (xy 3.624014 -251.1238) (xy 3.655314 -251.10694)
			(xy 3.674734 -251.096276) (xy 3.709879 -251.069308) (xy 3.739815 -251.036654) (xy 3.763636 -250.999303)
			(xy 3.780619 -250.958389) (xy 3.790251 -250.915149) (xy 3.79224 -250.870894) (xy 3.786524 -250.826964)
			(xy 3.773279 -250.784691) (xy 3.763518 -250.764802) (xy 3.738506 -250.715541) (xy 3.694475 -250.614203)
			(xy 3.657468 -250.510095) (xy 3.627656 -250.403703) (xy 3.605179 -250.295523) (xy 3.590142 -250.186061)
			(xy 3.582615 -250.075827) (xy 3.582162 -250.020582) (xy 3.582667 -249.963207) (xy 3.590809 -249.848747)
			(xy 3.607047 -249.735153) (xy 3.6313 -249.622996) (xy 3.663446 -249.512841) (xy 3.703323 -249.405244)
			(xy 3.75073 -249.300745) (xy 3.805428 -249.199871) (xy 3.867141 -249.10313) (xy 3.93556 -249.011009)
			(xy 4.01034 -248.923972) (xy 4.091103 -248.842458) (xy 4.177444 -248.766876) (xy 4.268927 -248.697607)
			(xy 4.365092 -248.635) (xy 4.465455 -248.57937) (xy 4.569511 -248.530998) (xy 4.676734 -248.490126)
			(xy 4.786587 -248.456962) (xy 4.898514 -248.431671) (xy 5.011953 -248.414381) (xy 5.126333 -248.40518)
			(xy 5.241077 -248.404113) (xy 5.355608 -248.411186) (xy 5.46935 -248.426363) (xy 5.581728 -248.449568)
			(xy 5.692178 -248.480683) (xy 5.800143 -248.519554) (xy 5.90508 -248.565982) (xy 6.00646 -248.619736)
			(xy 6.103773 -248.680544) (xy 6.139045 -248.706233) (xy 7.813794 -248.706233) (xy 7.813794 -248.634911)
			(xy 7.82178 -248.564037) (xy 7.83765 -248.494502) (xy 7.861207 -248.427182) (xy 7.892152 -248.362923)
			(xy 7.930098 -248.302532) (xy 7.974567 -248.24677) (xy 8.025 -248.196337) (xy 8.080762 -248.151868)
			(xy 8.141153 -248.113922) (xy 8.205412 -248.082977) (xy 8.272732 -248.05942) (xy 8.342267 -248.04355)
			(xy 8.413141 -248.035564) (xy 8.448802 -248.035064) (xy 8.484463 -248.035564) (xy 8.555337 -248.04355)
			(xy 8.624872 -248.05942) (xy 8.692192 -248.082977) (xy 8.756451 -248.113922) (xy 8.816842 -248.151868)
			(xy 8.872604 -248.196337) (xy 8.923037 -248.24677) (xy 8.967506 -248.302532) (xy 9.005452 -248.362923)
			(xy 9.036397 -248.427182) (xy 9.059954 -248.494502) (xy 9.075824 -248.564037) (xy 9.08381 -248.634911)
			(xy 9.08381 -248.706233) (xy 9.075824 -248.777107) (xy 9.059954 -248.846642) (xy 9.036397 -248.913962)
			(xy 9.005452 -248.978221) (xy 8.967506 -249.038612) (xy 8.923037 -249.094374) (xy 8.872604 -249.144807)
			(xy 8.816842 -249.189276) (xy 8.756451 -249.227222) (xy 8.692192 -249.258167) (xy 8.624872 -249.281724)
			(xy 8.555337 -249.297594) (xy 8.484463 -249.30558) (xy 8.413141 -249.30558) (xy 8.342267 -249.297594)
			(xy 8.272732 -249.281724) (xy 8.205412 -249.258167) (xy 8.141153 -249.227222) (xy 8.080762 -249.189276)
			(xy 8.025 -249.144807) (xy 7.974567 -249.094374) (xy 7.930098 -249.038612) (xy 7.892152 -248.978221)
			(xy 7.861207 -248.913962) (xy 7.83765 -248.846642) (xy 7.82178 -248.777107) (xy 7.813794 -248.706233)
			(xy 6.139045 -248.706233) (xy 6.196529 -248.748099) (xy 6.284261 -248.822063) (xy 6.366526 -248.902061)
			(xy 6.442911 -248.987693) (xy 6.513031 -249.078525) (xy 6.576533 -249.174102) (xy 6.633098 -249.273941)
			(xy 6.68244 -249.37754) (xy 6.72431 -249.484377) (xy 6.758499 -249.593915) (xy 6.784834 -249.705601)
			(xy 6.803182 -249.818874) (xy 6.813452 -249.933163) (xy 6.81559 -250.047892) (xy 6.809587 -250.162485)
			(xy 6.795473 -250.276362) (xy 6.773318 -250.388953) (xy 6.743235 -250.499688) (xy 6.705375 -250.608012)
			(xy 6.659928 -250.713378) (xy 6.633972 -250.764548) (xy 6.624195 -250.784446) (xy 6.610935 -250.826745)
			(xy 6.605209 -250.870704) (xy 6.607191 -250.914989) (xy 6.616821 -250.95826) (xy 6.633807 -250.999206)
			(xy 6.657635 -251.036587) (xy 6.687583 -251.069271) (xy 6.722744 -251.096268) (xy 6.742176 -251.10694)
			(xy 6.773477 -251.123798) (xy 6.832484 -251.163456) (xy 6.886695 -251.209454) (xy 6.935433 -251.261215)
			(xy 6.978089 -251.318093) (xy 7.014129 -251.379377) (xy 7.043103 -251.444301) (xy 7.06465 -251.512053)
			(xy 7.078498 -251.581787) (xy 7.084477 -251.652631) (xy 7.08251 -251.7237) (xy 7.072622 -251.794105)
			(xy 7.054938 -251.862966) (xy 7.029677 -251.929423) (xy 6.997156 -251.992645) (xy 6.957782 -252.051842)
			(xy 6.912045 -252.106274) (xy 6.860519 -252.15526) (xy 6.803846 -252.198189) (xy 6.742736 -252.234523)
			(xy 6.677952 -252.263809) (xy 6.610304 -252.285681) (xy 6.540638 -252.299864) (xy 6.469823 -252.306183)
			(xy 6.398746 -252.304558) (xy 6.328294 -252.295009) (xy 6.259348 -252.277655) (xy 6.192771 -252.252714)
			(xy 6.129393 -252.220497) (xy 6.070008 -252.181408) (xy 6.015357 -252.135933) (xy 5.966124 -252.084643)
			(xy 5.922923 -252.028177) (xy 5.886296 -251.967243) (xy 5.856699 -251.9026) (xy 5.834503 -251.835058)
			(xy 5.82676 -251.80036) (xy 5.821807 -251.778751) (xy 5.805353 -251.737588) (xy 5.782007 -251.699904)
			(xy 5.752477 -251.666841) (xy 5.71766 -251.639402) (xy 5.67861 -251.618419) (xy 5.636512 -251.604529)
			(xy 5.592643 -251.598152) (xy 5.548333 -251.599483) (xy 5.526532 -251.60351) (xy 5.472591 -251.614244)
			(xy 5.36362 -251.629213) (xy 5.253883 -251.636735) (xy 5.143889 -251.636775) (xy 5.034146 -251.629333)
			(xy 4.925164 -251.614443) (xy 4.871212 -251.603764) (xy 4.849427 -251.599696) (xy 4.805133 -251.598335)
			(xy 4.761275 -251.604683) (xy 4.719185 -251.618545) (xy 4.680139 -251.639502) (xy 4.645323 -251.666917)
			(xy 4.615793 -251.699959) (xy 4.592445 -251.737624) (xy 4.575989 -251.77877) (xy 4.570984 -251.80036)
			(xy 4.563244 -251.835059) (xy 4.541045 -251.902602) (xy 4.511446 -251.967244) (xy 4.474817 -252.028179)
			(xy 4.431616 -252.084646) (xy 4.382382 -252.135937) (xy 4.327731 -252.181413) (xy 4.268345 -252.220505)
			(xy 4.204968 -252.252724) (xy 4.138391 -252.277668) (xy 4.069445 -252.295026) (xy 3.998993 -252.304579)
			(xy 3.927914 -252.30621) (xy 3.857098 -252.299897) (xy 3.787429 -252.285719) (xy 3.719778 -252.263855)
			(xy 3.65499 -252.234575) (xy 3.593874 -252.198248) (xy 3.537195 -252.155326) (xy 3.485661 -252.106346)
			(xy 3.439916 -252.051921) (xy 3.400531 -251.99273) (xy 3.367999 -251.929512) (xy 3.342726 -251.863059)
			(xy 3.325028 -251.7942) (xy 3.315126 -251.723796) (xy 3.313144 -251.652726) (xy 0.509016 -251.652726)
			(xy 0.509016 -252.706225) (xy 1.313934 -252.706225) (xy 1.313934 -252.634903) (xy 1.32192 -252.564029)
			(xy 1.33779 -252.494494) (xy 1.361347 -252.427174) (xy 1.392292 -252.362915) (xy 1.430238 -252.302524)
			(xy 1.474707 -252.246762) (xy 1.52514 -252.196329) (xy 1.580902 -252.15186) (xy 1.641293 -252.113914)
			(xy 1.705552 -252.082969) (xy 1.772872 -252.059412) (xy 1.842407 -252.043542) (xy 1.913281 -252.035556)
			(xy 1.948942 -252.035056) (xy 1.984603 -252.035556) (xy 2.055477 -252.043542) (xy 2.125012 -252.059412)
			(xy 2.192332 -252.082969) (xy 2.256591 -252.113914) (xy 2.316982 -252.15186) (xy 2.372744 -252.196329)
			(xy 2.423177 -252.246762) (xy 2.467646 -252.302524) (xy 2.505592 -252.362915) (xy 2.536537 -252.427174)
			(xy 2.560094 -252.494494) (xy 2.575964 -252.564029) (xy 2.58395 -252.634903) (xy 2.58395 -252.706225)
			(xy 7.813794 -252.706225) (xy 7.813794 -252.634903) (xy 7.82178 -252.564029) (xy 7.83765 -252.494494)
			(xy 7.861207 -252.427174) (xy 7.892152 -252.362915) (xy 7.930098 -252.302524) (xy 7.974567 -252.246762)
			(xy 8.025 -252.196329) (xy 8.080762 -252.15186) (xy 8.141153 -252.113914) (xy 8.205412 -252.082969)
			(xy 8.272732 -252.059412) (xy 8.342267 -252.043542) (xy 8.413141 -252.035556) (xy 8.448802 -252.035056)
			(xy 8.484463 -252.035556) (xy 8.555337 -252.043542) (xy 8.624872 -252.059412) (xy 8.692192 -252.082969)
			(xy 8.756451 -252.113914) (xy 8.816842 -252.15186) (xy 8.872604 -252.196329) (xy 8.923037 -252.246762)
			(xy 8.967506 -252.302524) (xy 9.005452 -252.362915) (xy 9.036397 -252.427174) (xy 9.059954 -252.494494)
			(xy 9.075824 -252.564029) (xy 9.08381 -252.634903) (xy 9.08381 -252.706225) (xy 9.075824 -252.777099)
			(xy 9.059954 -252.846634) (xy 9.036397 -252.913954) (xy 9.005452 -252.978213) (xy 8.967506 -253.038604)
			(xy 8.923037 -253.094366) (xy 8.872604 -253.144799) (xy 8.816842 -253.189268) (xy 8.756451 -253.227214)
			(xy 8.692192 -253.258159) (xy 8.624872 -253.281716) (xy 8.555337 -253.297586) (xy 8.484463 -253.305572)
			(xy 8.413141 -253.305572) (xy 8.342267 -253.297586) (xy 8.272732 -253.281716) (xy 8.205412 -253.258159)
			(xy 8.141153 -253.227214) (xy 8.080762 -253.189268) (xy 8.025 -253.144799) (xy 7.974567 -253.094366)
			(xy 7.930098 -253.038604) (xy 7.892152 -252.978213) (xy 7.861207 -252.913954) (xy 7.83765 -252.846634)
			(xy 7.82178 -252.777099) (xy 7.813794 -252.706225) (xy 2.58395 -252.706225) (xy 2.575964 -252.777099)
			(xy 2.560094 -252.846634) (xy 2.536537 -252.913954) (xy 2.505592 -252.978213) (xy 2.467646 -253.038604)
			(xy 2.423177 -253.094366) (xy 2.372744 -253.144799) (xy 2.316982 -253.189268) (xy 2.256591 -253.227214)
			(xy 2.192332 -253.258159) (xy 2.125012 -253.281716) (xy 2.055477 -253.297586) (xy 1.984603 -253.305572)
			(xy 1.913281 -253.305572) (xy 1.842407 -253.297586) (xy 1.772872 -253.281716) (xy 1.705552 -253.258159)
			(xy 1.641293 -253.227214) (xy 1.580902 -253.189268) (xy 1.52514 -253.144799) (xy 1.474707 -253.094366)
			(xy 1.430238 -253.038604) (xy 1.392292 -252.978213) (xy 1.361347 -252.913954) (xy 1.33779 -252.846634)
			(xy 1.32192 -252.777099) (xy 1.313934 -252.706225) (xy 0.509016 -252.706225) (xy 0.509016 -253.706223)
			(xy 5.813798 -253.706223) (xy 5.813798 -253.634901) (xy 5.821784 -253.564027) (xy 5.837654 -253.494492)
			(xy 5.861211 -253.427172) (xy 5.892156 -253.362913) (xy 5.930102 -253.302522) (xy 5.974571 -253.24676)
			(xy 6.025004 -253.196327) (xy 6.080766 -253.151858) (xy 6.141157 -253.113912) (xy 6.205416 -253.082967)
			(xy 6.272736 -253.05941) (xy 6.342271 -253.04354) (xy 6.413145 -253.035554) (xy 6.448806 -253.035054)
			(xy 6.484467 -253.035554) (xy 6.555341 -253.04354) (xy 6.624876 -253.05941) (xy 6.692196 -253.082967)
			(xy 6.756455 -253.113912) (xy 6.816846 -253.151858) (xy 6.872608 -253.196327) (xy 6.923041 -253.24676)
			(xy 6.96751 -253.302522) (xy 7.005456 -253.362913) (xy 7.036401 -253.427172) (xy 7.059958 -253.494492)
			(xy 7.075828 -253.564027) (xy 7.083814 -253.634901) (xy 7.083814 -253.706223) (xy 7.075828 -253.777097)
			(xy 7.059958 -253.846632) (xy 7.036401 -253.913952) (xy 7.005456 -253.978211) (xy 6.96751 -254.038602)
			(xy 6.923041 -254.094364) (xy 6.872608 -254.144797) (xy 6.816846 -254.189266) (xy 6.756455 -254.227212)
			(xy 6.692196 -254.258157) (xy 6.624876 -254.281714) (xy 6.555341 -254.297584) (xy 6.484467 -254.30557)
			(xy 6.413145 -254.30557) (xy 6.342271 -254.297584) (xy 6.272736 -254.281714) (xy 6.205416 -254.258157)
			(xy 6.141157 -254.227212) (xy 6.080766 -254.189266) (xy 6.025004 -254.144797) (xy 5.974571 -254.094364)
			(xy 5.930102 -254.038602) (xy 5.892156 -253.978211) (xy 5.861211 -253.913952) (xy 5.837654 -253.846632)
			(xy 5.821784 -253.777097) (xy 5.813798 -253.706223) (xy 0.509016 -253.706223) (xy 0.509016 -254.706221)
			(xy 1.313934 -254.706221) (xy 1.313934 -254.634899) (xy 1.32192 -254.564025) (xy 1.33779 -254.49449)
			(xy 1.361347 -254.42717) (xy 1.392292 -254.362911) (xy 1.430238 -254.30252) (xy 1.474707 -254.246758)
			(xy 1.52514 -254.196325) (xy 1.580902 -254.151856) (xy 1.641293 -254.11391) (xy 1.705552 -254.082965)
			(xy 1.772872 -254.059408) (xy 1.842407 -254.043538) (xy 1.913281 -254.035552) (xy 1.948942 -254.035052)
			(xy 1.984603 -254.035552) (xy 2.055477 -254.043538) (xy 2.125012 -254.059408) (xy 2.192332 -254.082965)
			(xy 2.256591 -254.11391) (xy 2.316982 -254.151856) (xy 2.372744 -254.196325) (xy 2.423177 -254.246758)
			(xy 2.467646 -254.30252) (xy 2.505592 -254.362911) (xy 2.536537 -254.42717) (xy 2.560094 -254.49449)
			(xy 2.575964 -254.564025) (xy 2.58395 -254.634899) (xy 2.58395 -254.706221) (xy 7.813794 -254.706221)
			(xy 7.813794 -254.634899) (xy 7.82178 -254.564025) (xy 7.83765 -254.49449) (xy 7.861207 -254.42717)
			(xy 7.892152 -254.362911) (xy 7.930098 -254.30252) (xy 7.974567 -254.246758) (xy 8.025 -254.196325)
			(xy 8.080762 -254.151856) (xy 8.141153 -254.11391) (xy 8.205412 -254.082965) (xy 8.272732 -254.059408)
			(xy 8.342267 -254.043538) (xy 8.413141 -254.035552) (xy 8.448802 -254.035052) (xy 8.484463 -254.035552)
			(xy 8.555337 -254.043538) (xy 8.624872 -254.059408) (xy 8.692192 -254.082965) (xy 8.756451 -254.11391)
			(xy 8.816842 -254.151856) (xy 8.872604 -254.196325) (xy 8.923037 -254.246758) (xy 8.967506 -254.30252)
			(xy 9.005452 -254.362911) (xy 9.036397 -254.42717) (xy 9.059954 -254.49449) (xy 9.075824 -254.564025)
			(xy 9.08381 -254.634899) (xy 9.08381 -254.706221) (xy 9.075824 -254.777095) (xy 9.059954 -254.84663)
			(xy 9.036397 -254.91395) (xy 9.005452 -254.978209) (xy 8.967506 -255.0386) (xy 8.923037 -255.094362)
			(xy 8.872604 -255.144795) (xy 8.816842 -255.189264) (xy 8.756451 -255.22721) (xy 8.692192 -255.258155)
			(xy 8.624872 -255.281712) (xy 8.555337 -255.297582) (xy 8.484463 -255.305568) (xy 8.413141 -255.305568)
			(xy 8.342267 -255.297582) (xy 8.272732 -255.281712) (xy 8.205412 -255.258155) (xy 8.141153 -255.22721)
			(xy 8.080762 -255.189264) (xy 8.025 -255.144795) (xy 7.974567 -255.094362) (xy 7.930098 -255.0386)
			(xy 7.892152 -254.978209) (xy 7.861207 -254.91395) (xy 7.83765 -254.84663) (xy 7.82178 -254.777095)
			(xy 7.813794 -254.706221) (xy 2.58395 -254.706221) (xy 2.575964 -254.777095) (xy 2.560094 -254.84663)
			(xy 2.536537 -254.91395) (xy 2.505592 -254.978209) (xy 2.467646 -255.0386) (xy 2.423177 -255.094362)
			(xy 2.372744 -255.144795) (xy 2.316982 -255.189264) (xy 2.256591 -255.22721) (xy 2.192332 -255.258155)
			(xy 2.125012 -255.281712) (xy 2.055477 -255.297582) (xy 1.984603 -255.305568) (xy 1.913281 -255.305568)
			(xy 1.842407 -255.297582) (xy 1.772872 -255.281712) (xy 1.705552 -255.258155) (xy 1.641293 -255.22721)
			(xy 1.580902 -255.189264) (xy 1.52514 -255.144795) (xy 1.474707 -255.094362) (xy 1.430238 -255.0386)
			(xy 1.392292 -254.978209) (xy 1.361347 -254.91395) (xy 1.33779 -254.84663) (xy 1.32192 -254.777095)
			(xy 1.313934 -254.706221) (xy 0.509016 -254.706221) (xy 0.509016 -255.706219) (xy 3.31393 -255.706219)
			(xy 3.31393 -255.634897) (xy 3.321916 -255.564023) (xy 3.337786 -255.494488) (xy 3.361343 -255.427168)
			(xy 3.392288 -255.362909) (xy 3.430234 -255.302518) (xy 3.474703 -255.246756) (xy 3.525136 -255.196323)
			(xy 3.580898 -255.151854) (xy 3.641289 -255.113908) (xy 3.705548 -255.082963) (xy 3.772868 -255.059406)
			(xy 3.842403 -255.043536) (xy 3.913277 -255.03555) (xy 3.948938 -255.03505) (xy 3.984599 -255.03555)
			(xy 4.055473 -255.043536) (xy 4.125008 -255.059406) (xy 4.192328 -255.082963) (xy 4.256587 -255.113908)
			(xy 4.316978 -255.151854) (xy 4.37274 -255.196323) (xy 4.423173 -255.246756) (xy 4.467642 -255.302518)
			(xy 4.505588 -255.362909) (xy 4.536533 -255.427168) (xy 4.56009 -255.494488) (xy 4.57596 -255.564023)
			(xy 4.583946 -255.634897) (xy 4.583946 -255.706219) (xy 4.57596 -255.777093) (xy 4.56009 -255.846628)
			(xy 4.536533 -255.913948) (xy 4.505588 -255.978207) (xy 4.467642 -256.038598) (xy 4.423173 -256.09436)
			(xy 4.37274 -256.144793) (xy 4.316978 -256.189262) (xy 4.256587 -256.227208) (xy 4.192328 -256.258153)
			(xy 4.125008 -256.28171) (xy 4.055473 -256.29758) (xy 3.984599 -256.305566) (xy 3.913277 -256.305566)
			(xy 3.842403 -256.29758) (xy 3.772868 -256.28171) (xy 3.705548 -256.258153) (xy 3.641289 -256.227208)
			(xy 3.580898 -256.189262) (xy 3.525136 -256.144793) (xy 3.474703 -256.09436) (xy 3.430234 -256.038598)
			(xy 3.392288 -255.978207) (xy 3.361343 -255.913948) (xy 3.337786 -255.846628) (xy 3.321916 -255.777093)
			(xy 3.31393 -255.706219) (xy 0.509016 -255.706219) (xy 0.509016 -256.706217) (xy 1.313934 -256.706217)
			(xy 1.313934 -256.634895) (xy 1.32192 -256.564021) (xy 1.33779 -256.494486) (xy 1.361347 -256.427166)
			(xy 1.392292 -256.362907) (xy 1.430238 -256.302516) (xy 1.474707 -256.246754) (xy 1.52514 -256.196321)
			(xy 1.580902 -256.151852) (xy 1.641293 -256.113906) (xy 1.705552 -256.082961) (xy 1.772872 -256.059404)
			(xy 1.842407 -256.043534) (xy 1.913281 -256.035548) (xy 1.948942 -256.035048) (xy 1.984603 -256.035548)
			(xy 2.055477 -256.043534) (xy 2.125012 -256.059404) (xy 2.192332 -256.082961) (xy 2.256591 -256.113906)
			(xy 2.316982 -256.151852) (xy 2.372744 -256.196321) (xy 2.423177 -256.246754) (xy 2.467646 -256.302516)
			(xy 2.505592 -256.362907) (xy 2.536537 -256.427166) (xy 2.560094 -256.494486) (xy 2.575964 -256.564021)
			(xy 2.58395 -256.634895) (xy 2.58395 -256.706217) (xy 7.813794 -256.706217) (xy 7.813794 -256.634895)
			(xy 7.82178 -256.564021) (xy 7.83765 -256.494486) (xy 7.861207 -256.427166) (xy 7.892152 -256.362907)
			(xy 7.930098 -256.302516) (xy 7.974567 -256.246754) (xy 8.025 -256.196321) (xy 8.080762 -256.151852)
			(xy 8.141153 -256.113906) (xy 8.205412 -256.082961) (xy 8.272732 -256.059404) (xy 8.342267 -256.043534)
			(xy 8.413141 -256.035548) (xy 8.448802 -256.035048) (xy 8.484463 -256.035548) (xy 8.555337 -256.043534)
			(xy 8.624872 -256.059404) (xy 8.692192 -256.082961) (xy 8.756451 -256.113906) (xy 8.816842 -256.151852)
			(xy 8.872604 -256.196321) (xy 8.923037 -256.246754) (xy 8.967506 -256.302516) (xy 9.005452 -256.362907)
			(xy 9.036397 -256.427166) (xy 9.059954 -256.494486) (xy 9.075824 -256.564021) (xy 9.08381 -256.634895)
			(xy 9.08381 -256.706217) (xy 9.075824 -256.777091) (xy 9.059954 -256.846626) (xy 9.036397 -256.913946)
			(xy 9.005452 -256.978205) (xy 8.967506 -257.038596) (xy 8.923037 -257.094358) (xy 8.872604 -257.144791)
			(xy 8.816842 -257.18926) (xy 8.756451 -257.227206) (xy 8.692192 -257.258151) (xy 8.624872 -257.281708)
			(xy 8.555337 -257.297578) (xy 8.484463 -257.305564) (xy 8.413141 -257.305564) (xy 8.342267 -257.297578)
			(xy 8.272732 -257.281708) (xy 8.205412 -257.258151) (xy 8.141153 -257.227206) (xy 8.080762 -257.18926)
			(xy 8.025 -257.144791) (xy 7.974567 -257.094358) (xy 7.930098 -257.038596) (xy 7.892152 -256.978205)
			(xy 7.861207 -256.913946) (xy 7.83765 -256.846626) (xy 7.82178 -256.777091) (xy 7.813794 -256.706217)
			(xy 2.58395 -256.706217) (xy 2.575964 -256.777091) (xy 2.560094 -256.846626) (xy 2.536537 -256.913946)
			(xy 2.505592 -256.978205) (xy 2.467646 -257.038596) (xy 2.423177 -257.094358) (xy 2.372744 -257.144791)
			(xy 2.316982 -257.18926) (xy 2.256591 -257.227206) (xy 2.192332 -257.258151) (xy 2.125012 -257.281708)
			(xy 2.055477 -257.297578) (xy 1.984603 -257.305564) (xy 1.913281 -257.305564) (xy 1.842407 -257.297578)
			(xy 1.772872 -257.281708) (xy 1.705552 -257.258151) (xy 1.641293 -257.227206) (xy 1.580902 -257.18926)
			(xy 1.52514 -257.144791) (xy 1.474707 -257.094358) (xy 1.430238 -257.038596) (xy 1.392292 -256.978205)
			(xy 1.361347 -256.913946) (xy 1.33779 -256.846626) (xy 1.32192 -256.777091) (xy 1.313934 -256.706217)
			(xy 0.509016 -256.706217) (xy 0.509016 -257.706215) (xy 3.31393 -257.706215) (xy 3.31393 -257.634893)
			(xy 3.321916 -257.564019) (xy 3.337786 -257.494484) (xy 3.361343 -257.427164) (xy 3.392288 -257.362905)
			(xy 3.430234 -257.302514) (xy 3.474703 -257.246752) (xy 3.525136 -257.196319) (xy 3.580898 -257.15185)
			(xy 3.641289 -257.113904) (xy 3.705548 -257.082959) (xy 3.772868 -257.059402) (xy 3.842403 -257.043532)
			(xy 3.913277 -257.035546) (xy 3.948938 -257.035046) (xy 3.984599 -257.035546) (xy 4.055473 -257.043532)
			(xy 4.125008 -257.059402) (xy 4.192328 -257.082959) (xy 4.256587 -257.113904) (xy 4.316978 -257.15185)
			(xy 4.37274 -257.196319) (xy 4.423173 -257.246752) (xy 4.467642 -257.302514) (xy 4.505588 -257.362905)
			(xy 4.536533 -257.427164) (xy 4.56009 -257.494484) (xy 4.57596 -257.564019) (xy 4.583946 -257.634893)
			(xy 4.583946 -257.706215) (xy 5.813798 -257.706215) (xy 5.813798 -257.634893) (xy 5.821784 -257.564019)
			(xy 5.837654 -257.494484) (xy 5.861211 -257.427164) (xy 5.892156 -257.362905) (xy 5.930102 -257.302514)
			(xy 5.974571 -257.246752) (xy 6.025004 -257.196319) (xy 6.080766 -257.15185) (xy 6.141157 -257.113904)
			(xy 6.205416 -257.082959) (xy 6.272736 -257.059402) (xy 6.342271 -257.043532) (xy 6.413145 -257.035546)
			(xy 6.448806 -257.035046) (xy 6.484467 -257.035546) (xy 6.555341 -257.043532) (xy 6.624876 -257.059402)
			(xy 6.692196 -257.082959) (xy 6.756455 -257.113904) (xy 6.816846 -257.15185) (xy 6.872608 -257.196319)
			(xy 6.923041 -257.246752) (xy 6.96751 -257.302514) (xy 7.005456 -257.362905) (xy 7.036401 -257.427164)
			(xy 7.059958 -257.494484) (xy 7.075828 -257.564019) (xy 7.083814 -257.634893) (xy 7.083814 -257.706215)
			(xy 7.075828 -257.777089) (xy 7.059958 -257.846624) (xy 7.036401 -257.913944) (xy 7.005456 -257.978203)
			(xy 6.96751 -258.038594) (xy 6.923041 -258.094356) (xy 6.872608 -258.144789) (xy 6.816846 -258.189258)
			(xy 6.756455 -258.227204) (xy 6.692196 -258.258149) (xy 6.624876 -258.281706) (xy 6.555341 -258.297576)
			(xy 6.484467 -258.305562) (xy 6.413145 -258.305562) (xy 6.342271 -258.297576) (xy 6.272736 -258.281706)
			(xy 6.205416 -258.258149) (xy 6.141157 -258.227204) (xy 6.080766 -258.189258) (xy 6.025004 -258.144789)
			(xy 5.974571 -258.094356) (xy 5.930102 -258.038594) (xy 5.892156 -257.978203) (xy 5.861211 -257.913944)
			(xy 5.837654 -257.846624) (xy 5.821784 -257.777089) (xy 5.813798 -257.706215) (xy 4.583946 -257.706215)
			(xy 4.57596 -257.777089) (xy 4.56009 -257.846624) (xy 4.536533 -257.913944) (xy 4.505588 -257.978203)
			(xy 4.467642 -258.038594) (xy 4.423173 -258.094356) (xy 4.37274 -258.144789) (xy 4.316978 -258.189258)
			(xy 4.256587 -258.227204) (xy 4.192328 -258.258149) (xy 4.125008 -258.281706) (xy 4.055473 -258.297576)
			(xy 3.984599 -258.305562) (xy 3.913277 -258.305562) (xy 3.842403 -258.297576) (xy 3.772868 -258.281706)
			(xy 3.705548 -258.258149) (xy 3.641289 -258.227204) (xy 3.580898 -258.189258) (xy 3.525136 -258.144789)
			(xy 3.474703 -258.094356) (xy 3.430234 -258.038594) (xy 3.392288 -257.978203) (xy 3.361343 -257.913944)
			(xy 3.337786 -257.846624) (xy 3.321916 -257.777089) (xy 3.31393 -257.706215) (xy 0.509016 -257.706215)
			(xy 0.509016 -259.706211) (xy 3.31393 -259.706211) (xy 3.31393 -259.634889) (xy 3.321916 -259.564015)
			(xy 3.337786 -259.49448) (xy 3.361343 -259.42716) (xy 3.392288 -259.362901) (xy 3.430234 -259.30251)
			(xy 3.474703 -259.246748) (xy 3.525136 -259.196315) (xy 3.580898 -259.151846) (xy 3.641289 -259.1139)
			(xy 3.705548 -259.082955) (xy 3.772868 -259.059398) (xy 3.842403 -259.043528) (xy 3.913277 -259.035542)
			(xy 3.948938 -259.035042) (xy 3.984599 -259.035542) (xy 4.055473 -259.043528) (xy 4.125008 -259.059398)
			(xy 4.192328 -259.082955) (xy 4.256587 -259.1139) (xy 4.316978 -259.151846) (xy 4.37274 -259.196315)
			(xy 4.423173 -259.246748) (xy 4.467642 -259.30251) (xy 4.505588 -259.362901) (xy 4.536533 -259.42716)
			(xy 4.56009 -259.49448) (xy 4.57596 -259.564015) (xy 4.583946 -259.634889) (xy 4.583946 -259.706211)
			(xy 5.813798 -259.706211) (xy 5.813798 -259.634889) (xy 5.821784 -259.564015) (xy 5.837654 -259.49448)
			(xy 5.861211 -259.42716) (xy 5.892156 -259.362901) (xy 5.930102 -259.30251) (xy 5.974571 -259.246748)
			(xy 6.025004 -259.196315) (xy 6.080766 -259.151846) (xy 6.141157 -259.1139) (xy 6.205416 -259.082955)
			(xy 6.272736 -259.059398) (xy 6.342271 -259.043528) (xy 6.413145 -259.035542) (xy 6.448806 -259.035042)
			(xy 6.484467 -259.035542) (xy 6.555341 -259.043528) (xy 6.624876 -259.059398) (xy 6.692196 -259.082955)
			(xy 6.756455 -259.1139) (xy 6.816846 -259.151846) (xy 6.872608 -259.196315) (xy 6.923041 -259.246748)
			(xy 6.96751 -259.30251) (xy 7.005456 -259.362901) (xy 7.036401 -259.42716) (xy 7.059958 -259.49448)
			(xy 7.075828 -259.564015) (xy 7.083814 -259.634889) (xy 7.083814 -259.706211) (xy 7.075828 -259.777085)
			(xy 7.059958 -259.84662) (xy 7.036401 -259.91394) (xy 7.005456 -259.978199) (xy 6.96751 -260.03859)
			(xy 6.923041 -260.094352) (xy 6.872608 -260.144785) (xy 6.816846 -260.189254) (xy 6.756455 -260.2272)
			(xy 6.692196 -260.258145) (xy 6.624876 -260.281702) (xy 6.555341 -260.297572) (xy 6.484467 -260.305558)
			(xy 6.413145 -260.305558) (xy 6.342271 -260.297572) (xy 6.272736 -260.281702) (xy 6.205416 -260.258145)
			(xy 6.141157 -260.2272) (xy 6.080766 -260.189254) (xy 6.025004 -260.144785) (xy 5.974571 -260.094352)
			(xy 5.930102 -260.03859) (xy 5.892156 -259.978199) (xy 5.861211 -259.91394) (xy 5.837654 -259.84662)
			(xy 5.821784 -259.777085) (xy 5.813798 -259.706211) (xy 4.583946 -259.706211) (xy 4.57596 -259.777085)
			(xy 4.56009 -259.84662) (xy 4.536533 -259.91394) (xy 4.505588 -259.978199) (xy 4.467642 -260.03859)
			(xy 4.423173 -260.094352) (xy 4.37274 -260.144785) (xy 4.316978 -260.189254) (xy 4.256587 -260.2272)
			(xy 4.192328 -260.258145) (xy 4.125008 -260.281702) (xy 4.055473 -260.297572) (xy 3.984599 -260.305558)
			(xy 3.913277 -260.305558) (xy 3.842403 -260.297572) (xy 3.772868 -260.281702) (xy 3.705548 -260.258145)
			(xy 3.641289 -260.2272) (xy 3.580898 -260.189254) (xy 3.525136 -260.144785) (xy 3.474703 -260.094352)
			(xy 3.430234 -260.03859) (xy 3.392288 -259.978199) (xy 3.361343 -259.91394) (xy 3.337786 -259.84662)
			(xy 3.321916 -259.777085) (xy 3.31393 -259.706211) (xy 0.509016 -259.706211) (xy 0.509016 -260.706209)
			(xy 1.313934 -260.706209) (xy 1.313934 -260.634887) (xy 1.32192 -260.564013) (xy 1.33779 -260.494478)
			(xy 1.361347 -260.427158) (xy 1.392292 -260.362899) (xy 1.430238 -260.302508) (xy 1.474707 -260.246746)
			(xy 1.52514 -260.196313) (xy 1.580902 -260.151844) (xy 1.641293 -260.113898) (xy 1.705552 -260.082953)
			(xy 1.772872 -260.059396) (xy 1.842407 -260.043526) (xy 1.913281 -260.03554) (xy 1.948942 -260.03504)
			(xy 1.984603 -260.03554) (xy 2.055477 -260.043526) (xy 2.125012 -260.059396) (xy 2.192332 -260.082953)
			(xy 2.256591 -260.113898) (xy 2.316982 -260.151844) (xy 2.372744 -260.196313) (xy 2.423177 -260.246746)
			(xy 2.467646 -260.302508) (xy 2.505592 -260.362899) (xy 2.536537 -260.427158) (xy 2.560094 -260.494478)
			(xy 2.575964 -260.564013) (xy 2.58395 -260.634887) (xy 2.58395 -260.706209) (xy 7.813794 -260.706209)
			(xy 7.813794 -260.634887) (xy 7.82178 -260.564013) (xy 7.83765 -260.494478) (xy 7.861207 -260.427158)
			(xy 7.892152 -260.362899) (xy 7.930098 -260.302508) (xy 7.974567 -260.246746) (xy 8.025 -260.196313)
			(xy 8.080762 -260.151844) (xy 8.141153 -260.113898) (xy 8.205412 -260.082953) (xy 8.272732 -260.059396)
			(xy 8.342267 -260.043526) (xy 8.413141 -260.03554) (xy 8.448802 -260.03504) (xy 8.484463 -260.03554)
			(xy 8.555337 -260.043526) (xy 8.624872 -260.059396) (xy 8.692192 -260.082953) (xy 8.756451 -260.113898)
			(xy 8.816842 -260.151844) (xy 8.872604 -260.196313) (xy 8.923037 -260.246746) (xy 8.967506 -260.302508)
			(xy 9.005452 -260.362899) (xy 9.036397 -260.427158) (xy 9.059954 -260.494478) (xy 9.075824 -260.564013)
			(xy 9.08381 -260.634887) (xy 9.08381 -260.706209) (xy 9.075824 -260.777083) (xy 9.059954 -260.846618)
			(xy 9.036397 -260.913938) (xy 9.005452 -260.978197) (xy 8.967506 -261.038588) (xy 8.923037 -261.09435)
			(xy 8.872604 -261.144783) (xy 8.816842 -261.189252) (xy 8.756451 -261.227198) (xy 8.692192 -261.258143)
			(xy 8.624872 -261.2817) (xy 8.555337 -261.29757) (xy 8.484463 -261.305556) (xy 8.413141 -261.305556)
			(xy 8.342267 -261.29757) (xy 8.272732 -261.2817) (xy 8.205412 -261.258143) (xy 8.141153 -261.227198)
			(xy 8.080762 -261.189252) (xy 8.025 -261.144783) (xy 7.974567 -261.09435) (xy 7.930098 -261.038588)
			(xy 7.892152 -260.978197) (xy 7.861207 -260.913938) (xy 7.83765 -260.846618) (xy 7.82178 -260.777083)
			(xy 7.813794 -260.706209) (xy 2.58395 -260.706209) (xy 2.575964 -260.777083) (xy 2.560094 -260.846618)
			(xy 2.536537 -260.913938) (xy 2.505592 -260.978197) (xy 2.467646 -261.038588) (xy 2.423177 -261.09435)
			(xy 2.372744 -261.144783) (xy 2.316982 -261.189252) (xy 2.256591 -261.227198) (xy 2.192332 -261.258143)
			(xy 2.125012 -261.2817) (xy 2.055477 -261.29757) (xy 1.984603 -261.305556) (xy 1.913281 -261.305556)
			(xy 1.842407 -261.29757) (xy 1.772872 -261.2817) (xy 1.705552 -261.258143) (xy 1.641293 -261.227198)
			(xy 1.580902 -261.189252) (xy 1.52514 -261.144783) (xy 1.474707 -261.09435) (xy 1.430238 -261.038588)
			(xy 1.392292 -260.978197) (xy 1.361347 -260.913938) (xy 1.33779 -260.846618) (xy 1.32192 -260.777083)
			(xy 1.313934 -260.706209) (xy 0.509016 -260.706209) (xy 0.509016 -267.898438) (xy 3.58445 -267.898438)
			(xy 3.586463 -267.784416) (xy 3.596513 -267.67082) (xy 3.614552 -267.558215) (xy 3.640489 -267.447164)
			(xy 3.674194 -267.338219) (xy 3.715501 -267.231922) (xy 3.764202 -267.128804) (xy 3.820056 -267.029379)
			(xy 3.882784 -266.93414) (xy 3.952075 -266.843564) (xy 4.027581 -266.758102) (xy 4.108928 -266.678178)
			(xy 4.19571 -266.604191) (xy 4.287495 -266.53651) (xy 4.383825 -266.475473) (xy 4.484221 -266.421382)
			(xy 4.588183 -266.374508) (xy 4.695192 -266.335084) (xy 4.804715 -266.303306) (xy 4.916207 -266.279334)
			(xy 5.029112 -266.263285) (xy 5.142868 -266.255241) (xy 5.199888 -266.254738) (xy 5.256908 -266.255241)
			(xy 5.370664 -266.263285) (xy 5.483569 -266.279334) (xy 5.595061 -266.303306) (xy 5.704584 -266.335084)
			(xy 5.811593 -266.374508) (xy 5.915555 -266.421382) (xy 6.015951 -266.475473) (xy 6.112281 -266.53651)
			(xy 6.204066 -266.604191) (xy 6.290848 -266.678178) (xy 6.372195 -266.758102) (xy 6.447701 -266.843564)
			(xy 6.516992 -266.93414) (xy 6.57972 -267.029379) (xy 6.635574 -267.128804) (xy 6.684275 -267.231922)
			(xy 6.725582 -267.338219) (xy 6.759287 -267.447164) (xy 6.785224 -267.558215) (xy 6.803263 -267.67082)
			(xy 6.813313 -267.784416) (xy 6.815326 -267.898438) (xy 6.80929 -268.012319) (xy 6.795237 -268.12549)
			(xy 6.773236 -268.237387) (xy 6.743396 -268.347454) (xy 6.705867 -268.455142) (xy 6.660835 -268.559915)
			(xy 6.608524 -268.66125) (xy 6.549196 -268.758642) (xy 6.483146 -268.851607) (xy 6.410702 -268.939681)
			(xy 6.332227 -269.022426) (xy 6.24811 -269.099429) (xy 6.158771 -269.170307) (xy 6.064654 -269.234707)
			(xy 5.96623 -269.292307) (xy 5.863988 -269.342821) (xy 5.758437 -269.385996) (xy 5.650103 -269.421619)
			(xy 5.539527 -269.449512) (xy 5.427258 -269.469535) (xy 5.313857 -269.481589) (xy 5.199888 -269.485614)
			(xy 5.085919 -269.481589) (xy 4.972518 -269.469535) (xy 4.860249 -269.449512) (xy 4.749673 -269.421619)
			(xy 4.641339 -269.385996) (xy 4.535788 -269.342821) (xy 4.433546 -269.292307) (xy 4.335122 -269.234707)
			(xy 4.241005 -269.170307) (xy 4.151666 -269.099429) (xy 4.067549 -269.022426) (xy 3.989074 -268.939681)
			(xy 3.91663 -268.851607) (xy 3.85058 -268.758642) (xy 3.791252 -268.66125) (xy 3.738941 -268.559915)
			(xy 3.693909 -268.455142) (xy 3.65638 -268.347454) (xy 3.62654 -268.237387) (xy 3.604539 -268.12549)
			(xy 3.590486 -268.012319) (xy 3.58445 -267.898438) (xy 0.509016 -267.898438) (xy 0.509016 -269.705429)
			(xy 1.31495 -269.705429) (xy 1.31495 -269.634107) (xy 1.322936 -269.563233) (xy 1.338806 -269.493698)
			(xy 1.362363 -269.426378) (xy 1.393308 -269.362119) (xy 1.431254 -269.301728) (xy 1.475723 -269.245966)
			(xy 1.526156 -269.195533) (xy 1.581918 -269.151064) (xy 1.642309 -269.113118) (xy 1.706568 -269.082173)
			(xy 1.773888 -269.058616) (xy 1.843423 -269.042746) (xy 1.914297 -269.03476) (xy 1.949958 -269.03426)
			(xy 1.985619 -269.03476) (xy 2.056493 -269.042746) (xy 2.126028 -269.058616) (xy 2.193348 -269.082173)
			(xy 2.257607 -269.113118) (xy 2.317998 -269.151064) (xy 2.37376 -269.195533) (xy 2.424193 -269.245966)
			(xy 2.468662 -269.301728) (xy 2.506608 -269.362119) (xy 2.537553 -269.426378) (xy 2.56111 -269.493698)
			(xy 2.57698 -269.563233) (xy 2.584966 -269.634107) (xy 2.584966 -269.705429) (xy 7.81481 -269.705429)
			(xy 7.81481 -269.634107) (xy 7.822796 -269.563233) (xy 7.838666 -269.493698) (xy 7.862223 -269.426378)
			(xy 7.893168 -269.362119) (xy 7.931114 -269.301728) (xy 7.975583 -269.245966) (xy 8.026016 -269.195533)
			(xy 8.081778 -269.151064) (xy 8.142169 -269.113118) (xy 8.206428 -269.082173) (xy 8.273748 -269.058616)
			(xy 8.343283 -269.042746) (xy 8.414157 -269.03476) (xy 8.449818 -269.03426) (xy 8.485479 -269.03476)
			(xy 8.556353 -269.042746) (xy 8.625888 -269.058616) (xy 8.693208 -269.082173) (xy 8.757467 -269.113118)
			(xy 8.817858 -269.151064) (xy 8.87362 -269.195533) (xy 8.924053 -269.245966) (xy 8.968522 -269.301728)
			(xy 9.006468 -269.362119) (xy 9.037413 -269.426378) (xy 9.06097 -269.493698) (xy 9.07684 -269.563233)
			(xy 9.084826 -269.634107) (xy 9.084826 -269.705429) (xy 9.07684 -269.776303) (xy 9.06097 -269.845838)
			(xy 9.037413 -269.913158) (xy 9.006468 -269.977417) (xy 8.968522 -270.037808) (xy 8.924053 -270.09357)
			(xy 8.87362 -270.144003) (xy 8.817858 -270.188472) (xy 8.757467 -270.226418) (xy 8.693208 -270.257363)
			(xy 8.625888 -270.28092) (xy 8.556353 -270.29679) (xy 8.485479 -270.304776) (xy 8.414157 -270.304776)
			(xy 8.343283 -270.29679) (xy 8.273748 -270.28092) (xy 8.206428 -270.257363) (xy 8.142169 -270.226418)
			(xy 8.081778 -270.188472) (xy 8.026016 -270.144003) (xy 7.975583 -270.09357) (xy 7.931114 -270.037808)
			(xy 7.893168 -269.977417) (xy 7.862223 -269.913158) (xy 7.838666 -269.845838) (xy 7.822796 -269.776303)
			(xy 7.81481 -269.705429) (xy 2.584966 -269.705429) (xy 2.57698 -269.776303) (xy 2.56111 -269.845838)
			(xy 2.537553 -269.913158) (xy 2.506608 -269.977417) (xy 2.468662 -270.037808) (xy 2.424193 -270.09357)
			(xy 2.37376 -270.144003) (xy 2.317998 -270.188472) (xy 2.257607 -270.226418) (xy 2.193348 -270.257363)
			(xy 2.126028 -270.28092) (xy 2.056493 -270.29679) (xy 1.985619 -270.304776) (xy 1.914297 -270.304776)
			(xy 1.843423 -270.29679) (xy 1.773888 -270.28092) (xy 1.706568 -270.257363) (xy 1.642309 -270.226418)
			(xy 1.581918 -270.188472) (xy 1.526156 -270.144003) (xy 1.475723 -270.09357) (xy 1.431254 -270.037808)
			(xy 1.393308 -269.977417) (xy 1.362363 -269.913158) (xy 1.338806 -269.845838) (xy 1.322936 -269.776303)
			(xy 1.31495 -269.705429) (xy 0.509016 -269.705429) (xy 0.509016 -270.705427) (xy 3.314946 -270.705427)
			(xy 3.314946 -270.634105) (xy 3.322932 -270.563231) (xy 3.338802 -270.493696) (xy 3.362359 -270.426376)
			(xy 3.393304 -270.362117) (xy 3.43125 -270.301726) (xy 3.475719 -270.245964) (xy 3.526152 -270.195531)
			(xy 3.581914 -270.151062) (xy 3.642305 -270.113116) (xy 3.706564 -270.082171) (xy 3.773884 -270.058614)
			(xy 3.843419 -270.042744) (xy 3.914293 -270.034758) (xy 3.949954 -270.034258) (xy 3.985615 -270.034758)
			(xy 4.056489 -270.042744) (xy 4.126024 -270.058614) (xy 4.193344 -270.082171) (xy 4.257603 -270.113116)
			(xy 4.317994 -270.151062) (xy 4.373756 -270.195531) (xy 4.424189 -270.245964) (xy 4.468658 -270.301726)
			(xy 4.506604 -270.362117) (xy 4.537549 -270.426376) (xy 4.561106 -270.493696) (xy 4.576976 -270.563231)
			(xy 4.584962 -270.634105) (xy 4.584962 -270.705427) (xy 5.814814 -270.705427) (xy 5.814814 -270.634105)
			(xy 5.8228 -270.563231) (xy 5.83867 -270.493696) (xy 5.862227 -270.426376) (xy 5.893172 -270.362117)
			(xy 5.931118 -270.301726) (xy 5.975587 -270.245964) (xy 6.02602 -270.195531) (xy 6.081782 -270.151062)
			(xy 6.142173 -270.113116) (xy 6.206432 -270.082171) (xy 6.273752 -270.058614) (xy 6.343287 -270.042744)
			(xy 6.414161 -270.034758) (xy 6.449822 -270.034258) (xy 6.485483 -270.034758) (xy 6.556357 -270.042744)
			(xy 6.625892 -270.058614) (xy 6.693212 -270.082171) (xy 6.757471 -270.113116) (xy 6.817862 -270.151062)
			(xy 6.873624 -270.195531) (xy 6.924057 -270.245964) (xy 6.968526 -270.301726) (xy 7.006472 -270.362117)
			(xy 7.037417 -270.426376) (xy 7.060974 -270.493696) (xy 7.076844 -270.563231) (xy 7.08483 -270.634105)
			(xy 7.08483 -270.705427) (xy 7.076844 -270.776301) (xy 7.060974 -270.845836) (xy 7.037417 -270.913156)
			(xy 7.006472 -270.977415) (xy 6.968526 -271.037806) (xy 6.924057 -271.093568) (xy 6.873624 -271.144001)
			(xy 6.817862 -271.18847) (xy 6.757471 -271.226416) (xy 6.693212 -271.257361) (xy 6.625892 -271.280918)
			(xy 6.556357 -271.296788) (xy 6.485483 -271.304774) (xy 6.414161 -271.304774) (xy 6.343287 -271.296788)
			(xy 6.273752 -271.280918) (xy 6.206432 -271.257361) (xy 6.142173 -271.226416) (xy 6.081782 -271.18847)
			(xy 6.02602 -271.144001) (xy 5.975587 -271.093568) (xy 5.931118 -271.037806) (xy 5.893172 -270.977415)
			(xy 5.862227 -270.913156) (xy 5.83867 -270.845836) (xy 5.8228 -270.776301) (xy 5.814814 -270.705427)
			(xy 4.584962 -270.705427) (xy 4.576976 -270.776301) (xy 4.561106 -270.845836) (xy 4.537549 -270.913156)
			(xy 4.506604 -270.977415) (xy 4.468658 -271.037806) (xy 4.424189 -271.093568) (xy 4.373756 -271.144001)
			(xy 4.317994 -271.18847) (xy 4.257603 -271.226416) (xy 4.193344 -271.257361) (xy 4.126024 -271.280918)
			(xy 4.056489 -271.296788) (xy 3.985615 -271.304774) (xy 3.914293 -271.304774) (xy 3.843419 -271.296788)
			(xy 3.773884 -271.280918) (xy 3.706564 -271.257361) (xy 3.642305 -271.226416) (xy 3.581914 -271.18847)
			(xy 3.526152 -271.144001) (xy 3.475719 -271.093568) (xy 3.43125 -271.037806) (xy 3.393304 -270.977415)
			(xy 3.362359 -270.913156) (xy 3.338802 -270.845836) (xy 3.322932 -270.776301) (xy 3.314946 -270.705427)
			(xy 0.509016 -270.705427) (xy 0.509016 -271.705425) (xy 7.81481 -271.705425) (xy 7.81481 -271.634103)
			(xy 7.822796 -271.563229) (xy 7.838666 -271.493694) (xy 7.862223 -271.426374) (xy 7.893168 -271.362115)
			(xy 7.931114 -271.301724) (xy 7.975583 -271.245962) (xy 8.026016 -271.195529) (xy 8.081778 -271.15106)
			(xy 8.142169 -271.113114) (xy 8.206428 -271.082169) (xy 8.273748 -271.058612) (xy 8.343283 -271.042742)
			(xy 8.414157 -271.034756) (xy 8.449818 -271.034256) (xy 8.485479 -271.034756) (xy 8.556353 -271.042742)
			(xy 8.625888 -271.058612) (xy 8.693208 -271.082169) (xy 8.757467 -271.113114) (xy 8.817858 -271.15106)
			(xy 8.87362 -271.195529) (xy 8.924053 -271.245962) (xy 8.968522 -271.301724) (xy 9.006468 -271.362115)
			(xy 9.037413 -271.426374) (xy 9.06097 -271.493694) (xy 9.07684 -271.563229) (xy 9.084826 -271.634103)
			(xy 9.084826 -271.705425) (xy 9.07684 -271.776299) (xy 9.06097 -271.845834) (xy 9.037413 -271.913154)
			(xy 9.006468 -271.977413) (xy 8.968522 -272.037804) (xy 8.924053 -272.093566) (xy 8.87362 -272.143999)
			(xy 8.817858 -272.188468) (xy 8.757467 -272.226414) (xy 8.693208 -272.257359) (xy 8.625888 -272.280916)
			(xy 8.556353 -272.296786) (xy 8.485479 -272.304772) (xy 8.414157 -272.304772) (xy 8.343283 -272.296786)
			(xy 8.273748 -272.280916) (xy 8.206428 -272.257359) (xy 8.142169 -272.226414) (xy 8.081778 -272.188468)
			(xy 8.026016 -272.143999) (xy 7.975583 -272.093566) (xy 7.931114 -272.037804) (xy 7.893168 -271.977413)
			(xy 7.862223 -271.913154) (xy 7.838666 -271.845834) (xy 7.822796 -271.776299) (xy 7.81481 -271.705425)
			(xy 0.509016 -271.705425) (xy 0.509016 -272.705423) (xy 3.314946 -272.705423) (xy 3.314946 -272.634101)
			(xy 3.322932 -272.563227) (xy 3.338802 -272.493692) (xy 3.362359 -272.426372) (xy 3.393304 -272.362113)
			(xy 3.43125 -272.301722) (xy 3.475719 -272.24596) (xy 3.526152 -272.195527) (xy 3.581914 -272.151058)
			(xy 3.642305 -272.113112) (xy 3.706564 -272.082167) (xy 3.773884 -272.05861) (xy 3.843419 -272.04274)
			(xy 3.914293 -272.034754) (xy 3.949954 -272.034254) (xy 3.985615 -272.034754) (xy 4.056489 -272.04274)
			(xy 4.126024 -272.05861) (xy 4.193344 -272.082167) (xy 4.257603 -272.113112) (xy 4.317994 -272.151058)
			(xy 4.373756 -272.195527) (xy 4.424189 -272.24596) (xy 4.468658 -272.301722) (xy 4.506604 -272.362113)
			(xy 4.537549 -272.426372) (xy 4.561106 -272.493692) (xy 4.576976 -272.563227) (xy 4.584962 -272.634101)
			(xy 4.584962 -272.705423) (xy 4.576976 -272.776297) (xy 4.561106 -272.845832) (xy 4.537549 -272.913152)
			(xy 4.506604 -272.977411) (xy 4.468658 -273.037802) (xy 4.424189 -273.093564) (xy 4.373756 -273.143997)
			(xy 4.317994 -273.188466) (xy 4.257603 -273.226412) (xy 4.193344 -273.257357) (xy 4.126024 -273.280914)
			(xy 4.056489 -273.296784) (xy 3.985615 -273.30477) (xy 3.914293 -273.30477) (xy 3.843419 -273.296784)
			(xy 3.773884 -273.280914) (xy 3.706564 -273.257357) (xy 3.642305 -273.226412) (xy 3.581914 -273.188466)
			(xy 3.526152 -273.143997) (xy 3.475719 -273.093564) (xy 3.43125 -273.037802) (xy 3.393304 -272.977411)
			(xy 3.362359 -272.913152) (xy 3.338802 -272.845832) (xy 3.322932 -272.776297) (xy 3.314946 -272.705423)
			(xy 0.509016 -272.705423) (xy 0.509016 -273.705421) (xy 1.31495 -273.705421) (xy 1.31495 -273.634099)
			(xy 1.322936 -273.563225) (xy 1.338806 -273.49369) (xy 1.362363 -273.42637) (xy 1.393308 -273.362111)
			(xy 1.431254 -273.30172) (xy 1.475723 -273.245958) (xy 1.526156 -273.195525) (xy 1.581918 -273.151056)
			(xy 1.642309 -273.11311) (xy 1.706568 -273.082165) (xy 1.773888 -273.058608) (xy 1.843423 -273.042738)
			(xy 1.914297 -273.034752) (xy 1.949958 -273.034252) (xy 1.985619 -273.034752) (xy 2.056493 -273.042738)
			(xy 2.126028 -273.058608) (xy 2.193348 -273.082165) (xy 2.257607 -273.11311) (xy 2.317998 -273.151056)
			(xy 2.37376 -273.195525) (xy 2.424193 -273.245958) (xy 2.468662 -273.30172) (xy 2.506608 -273.362111)
			(xy 2.537553 -273.42637) (xy 2.56111 -273.49369) (xy 2.57698 -273.563225) (xy 2.584966 -273.634099)
			(xy 2.584966 -273.705421) (xy 7.81481 -273.705421) (xy 7.81481 -273.634099) (xy 7.822796 -273.563225)
			(xy 7.838666 -273.49369) (xy 7.862223 -273.42637) (xy 7.893168 -273.362111) (xy 7.931114 -273.30172)
			(xy 7.975583 -273.245958) (xy 8.026016 -273.195525) (xy 8.081778 -273.151056) (xy 8.142169 -273.11311)
			(xy 8.206428 -273.082165) (xy 8.273748 -273.058608) (xy 8.343283 -273.042738) (xy 8.414157 -273.034752)
			(xy 8.449818 -273.034252) (xy 8.485479 -273.034752) (xy 8.556353 -273.042738) (xy 8.625888 -273.058608)
			(xy 8.693208 -273.082165) (xy 8.757467 -273.11311) (xy 8.817858 -273.151056) (xy 8.87362 -273.195525)
			(xy 8.924053 -273.245958) (xy 8.968522 -273.30172) (xy 9.006468 -273.362111) (xy 9.037413 -273.42637)
			(xy 9.06097 -273.49369) (xy 9.07684 -273.563225) (xy 9.084826 -273.634099) (xy 9.084826 -273.705421)
			(xy 9.07684 -273.776295) (xy 9.06097 -273.84583) (xy 9.037413 -273.91315) (xy 9.006468 -273.977409)
			(xy 8.968522 -274.0378) (xy 8.924053 -274.093562) (xy 8.87362 -274.143995) (xy 8.817858 -274.188464)
			(xy 8.757467 -274.22641) (xy 8.693208 -274.257355) (xy 8.625888 -274.280912) (xy 8.556353 -274.296782)
			(xy 8.485479 -274.304768) (xy 8.414157 -274.304768) (xy 8.343283 -274.296782) (xy 8.273748 -274.280912)
			(xy 8.206428 -274.257355) (xy 8.142169 -274.22641) (xy 8.081778 -274.188464) (xy 8.026016 -274.143995)
			(xy 7.975583 -274.093562) (xy 7.931114 -274.0378) (xy 7.893168 -273.977409) (xy 7.862223 -273.91315)
			(xy 7.838666 -273.84583) (xy 7.822796 -273.776295) (xy 7.81481 -273.705421) (xy 2.584966 -273.705421)
			(xy 2.57698 -273.776295) (xy 2.56111 -273.84583) (xy 2.537553 -273.91315) (xy 2.506608 -273.977409)
			(xy 2.468662 -274.0378) (xy 2.424193 -274.093562) (xy 2.37376 -274.143995) (xy 2.317998 -274.188464)
			(xy 2.257607 -274.22641) (xy 2.193348 -274.257355) (xy 2.126028 -274.280912) (xy 2.056493 -274.296782)
			(xy 1.985619 -274.304768) (xy 1.914297 -274.304768) (xy 1.843423 -274.296782) (xy 1.773888 -274.280912)
			(xy 1.706568 -274.257355) (xy 1.642309 -274.22641) (xy 1.581918 -274.188464) (xy 1.526156 -274.143995)
			(xy 1.475723 -274.093562) (xy 1.431254 -274.0378) (xy 1.393308 -273.977409) (xy 1.362363 -273.91315)
			(xy 1.338806 -273.84583) (xy 1.322936 -273.776295) (xy 1.31495 -273.705421) (xy 0.509016 -273.705421)
			(xy 0.509016 -274.705419) (xy 3.314946 -274.705419) (xy 3.314946 -274.634097) (xy 3.322932 -274.563223)
			(xy 3.338802 -274.493688) (xy 3.362359 -274.426368) (xy 3.393304 -274.362109) (xy 3.43125 -274.301718)
			(xy 3.475719 -274.245956) (xy 3.526152 -274.195523) (xy 3.581914 -274.151054) (xy 3.642305 -274.113108)
			(xy 3.706564 -274.082163) (xy 3.773884 -274.058606) (xy 3.843419 -274.042736) (xy 3.914293 -274.03475)
			(xy 3.949954 -274.03425) (xy 3.985615 -274.03475) (xy 4.056489 -274.042736) (xy 4.126024 -274.058606)
			(xy 4.193344 -274.082163) (xy 4.257603 -274.113108) (xy 4.317994 -274.151054) (xy 4.373756 -274.195523)
			(xy 4.424189 -274.245956) (xy 4.468658 -274.301718) (xy 4.506604 -274.362109) (xy 4.537549 -274.426368)
			(xy 4.561106 -274.493688) (xy 4.576976 -274.563223) (xy 4.584962 -274.634097) (xy 4.584962 -274.705419)
			(xy 5.814814 -274.705419) (xy 5.814814 -274.634097) (xy 5.8228 -274.563223) (xy 5.83867 -274.493688)
			(xy 5.862227 -274.426368) (xy 5.893172 -274.362109) (xy 5.931118 -274.301718) (xy 5.975587 -274.245956)
			(xy 6.02602 -274.195523) (xy 6.081782 -274.151054) (xy 6.142173 -274.113108) (xy 6.206432 -274.082163)
			(xy 6.273752 -274.058606) (xy 6.343287 -274.042736) (xy 6.414161 -274.03475) (xy 6.449822 -274.03425)
			(xy 6.485483 -274.03475) (xy 6.556357 -274.042736) (xy 6.625892 -274.058606) (xy 6.693212 -274.082163)
			(xy 6.757471 -274.113108) (xy 6.817862 -274.151054) (xy 6.873624 -274.195523) (xy 6.924057 -274.245956)
			(xy 6.968526 -274.301718) (xy 7.006472 -274.362109) (xy 7.037417 -274.426368) (xy 7.060974 -274.493688)
			(xy 7.076844 -274.563223) (xy 7.08483 -274.634097) (xy 7.08483 -274.705419) (xy 7.076844 -274.776293)
			(xy 7.060974 -274.845828) (xy 7.037417 -274.913148) (xy 7.006472 -274.977407) (xy 6.968526 -275.037798)
			(xy 6.924057 -275.09356) (xy 6.873624 -275.143993) (xy 6.817862 -275.188462) (xy 6.757471 -275.226408)
			(xy 6.693212 -275.257353) (xy 6.625892 -275.28091) (xy 6.556357 -275.29678) (xy 6.485483 -275.304766)
			(xy 6.414161 -275.304766) (xy 6.343287 -275.29678) (xy 6.273752 -275.28091) (xy 6.206432 -275.257353)
			(xy 6.142173 -275.226408) (xy 6.081782 -275.188462) (xy 6.02602 -275.143993) (xy 5.975587 -275.09356)
			(xy 5.931118 -275.037798) (xy 5.893172 -274.977407) (xy 5.862227 -274.913148) (xy 5.83867 -274.845828)
			(xy 5.8228 -274.776293) (xy 5.814814 -274.705419) (xy 4.584962 -274.705419) (xy 4.576976 -274.776293)
			(xy 4.561106 -274.845828) (xy 4.537549 -274.913148) (xy 4.506604 -274.977407) (xy 4.468658 -275.037798)
			(xy 4.424189 -275.09356) (xy 4.373756 -275.143993) (xy 4.317994 -275.188462) (xy 4.257603 -275.226408)
			(xy 4.193344 -275.257353) (xy 4.126024 -275.28091) (xy 4.056489 -275.29678) (xy 3.985615 -275.304766)
			(xy 3.914293 -275.304766) (xy 3.843419 -275.29678) (xy 3.773884 -275.28091) (xy 3.706564 -275.257353)
			(xy 3.642305 -275.226408) (xy 3.581914 -275.188462) (xy 3.526152 -275.143993) (xy 3.475719 -275.09356)
			(xy 3.43125 -275.037798) (xy 3.393304 -274.977407) (xy 3.362359 -274.913148) (xy 3.338802 -274.845828)
			(xy 3.322932 -274.776293) (xy 3.314946 -274.705419) (xy 0.509016 -274.705419) (xy 0.509016 -275.705417)
			(xy 1.31495 -275.705417) (xy 1.31495 -275.634095) (xy 1.322936 -275.563221) (xy 1.338806 -275.493686)
			(xy 1.362363 -275.426366) (xy 1.393308 -275.362107) (xy 1.431254 -275.301716) (xy 1.475723 -275.245954)
			(xy 1.526156 -275.195521) (xy 1.581918 -275.151052) (xy 1.642309 -275.113106) (xy 1.706568 -275.082161)
			(xy 1.773888 -275.058604) (xy 1.843423 -275.042734) (xy 1.914297 -275.034748) (xy 1.949958 -275.034248)
			(xy 1.985619 -275.034748) (xy 2.056493 -275.042734) (xy 2.126028 -275.058604) (xy 2.193348 -275.082161)
			(xy 2.257607 -275.113106) (xy 2.317998 -275.151052) (xy 2.37376 -275.195521) (xy 2.424193 -275.245954)
			(xy 2.468662 -275.301716) (xy 2.506608 -275.362107) (xy 2.537553 -275.426366) (xy 2.56111 -275.493686)
			(xy 2.57698 -275.563221) (xy 2.584966 -275.634095) (xy 2.584966 -275.705417) (xy 7.81481 -275.705417)
			(xy 7.81481 -275.634095) (xy 7.822796 -275.563221) (xy 7.838666 -275.493686) (xy 7.862223 -275.426366)
			(xy 7.893168 -275.362107) (xy 7.931114 -275.301716) (xy 7.975583 -275.245954) (xy 8.026016 -275.195521)
			(xy 8.081778 -275.151052) (xy 8.142169 -275.113106) (xy 8.206428 -275.082161) (xy 8.273748 -275.058604)
			(xy 8.343283 -275.042734) (xy 8.414157 -275.034748) (xy 8.449818 -275.034248) (xy 8.485479 -275.034748)
			(xy 8.556353 -275.042734) (xy 8.625888 -275.058604) (xy 8.693208 -275.082161) (xy 8.757467 -275.113106)
			(xy 8.817858 -275.151052) (xy 8.87362 -275.195521) (xy 8.924053 -275.245954) (xy 8.968522 -275.301716)
			(xy 9.006468 -275.362107) (xy 9.037413 -275.426366) (xy 9.06097 -275.493686) (xy 9.07684 -275.563221)
			(xy 9.084826 -275.634095) (xy 9.084826 -275.705417) (xy 9.07684 -275.776291) (xy 9.06097 -275.845826)
			(xy 9.037413 -275.913146) (xy 9.006468 -275.977405) (xy 8.968522 -276.037796) (xy 8.924053 -276.093558)
			(xy 8.87362 -276.143991) (xy 8.817858 -276.18846) (xy 8.757467 -276.226406) (xy 8.693208 -276.257351)
			(xy 8.625888 -276.280908) (xy 8.556353 -276.296778) (xy 8.485479 -276.304764) (xy 8.414157 -276.304764)
			(xy 8.343283 -276.296778) (xy 8.273748 -276.280908) (xy 8.206428 -276.257351) (xy 8.142169 -276.226406)
			(xy 8.081778 -276.18846) (xy 8.026016 -276.143991) (xy 7.975583 -276.093558) (xy 7.931114 -276.037796)
			(xy 7.893168 -275.977405) (xy 7.862223 -275.913146) (xy 7.838666 -275.845826) (xy 7.822796 -275.776291)
			(xy 7.81481 -275.705417) (xy 2.584966 -275.705417) (xy 2.57698 -275.776291) (xy 2.56111 -275.845826)
			(xy 2.537553 -275.913146) (xy 2.506608 -275.977405) (xy 2.468662 -276.037796) (xy 2.424193 -276.093558)
			(xy 2.37376 -276.143991) (xy 2.317998 -276.18846) (xy 2.257607 -276.226406) (xy 2.193348 -276.257351)
			(xy 2.126028 -276.280908) (xy 2.056493 -276.296778) (xy 1.985619 -276.304764) (xy 1.914297 -276.304764)
			(xy 1.843423 -276.296778) (xy 1.773888 -276.280908) (xy 1.706568 -276.257351) (xy 1.642309 -276.226406)
			(xy 1.581918 -276.18846) (xy 1.526156 -276.143991) (xy 1.475723 -276.093558) (xy 1.431254 -276.037796)
			(xy 1.393308 -275.977405) (xy 1.362363 -275.913146) (xy 1.338806 -275.845826) (xy 1.322936 -275.776291)
			(xy 1.31495 -275.705417) (xy 0.509016 -275.705417) (xy 0.509016 -276.705415) (xy 5.814814 -276.705415)
			(xy 5.814814 -276.634093) (xy 5.8228 -276.563219) (xy 5.83867 -276.493684) (xy 5.862227 -276.426364)
			(xy 5.893172 -276.362105) (xy 5.931118 -276.301714) (xy 5.975587 -276.245952) (xy 6.02602 -276.195519)
			(xy 6.081782 -276.15105) (xy 6.142173 -276.113104) (xy 6.206432 -276.082159) (xy 6.273752 -276.058602)
			(xy 6.343287 -276.042732) (xy 6.414161 -276.034746) (xy 6.449822 -276.034246) (xy 6.485483 -276.034746)
			(xy 6.556357 -276.042732) (xy 6.625892 -276.058602) (xy 6.693212 -276.082159) (xy 6.757471 -276.113104)
			(xy 6.817862 -276.15105) (xy 6.873624 -276.195519) (xy 6.924057 -276.245952) (xy 6.968526 -276.301714)
			(xy 7.006472 -276.362105) (xy 7.037417 -276.426364) (xy 7.060974 -276.493684) (xy 7.076844 -276.563219)
			(xy 7.08483 -276.634093) (xy 7.08483 -276.705415) (xy 7.076844 -276.776289) (xy 7.060974 -276.845824)
			(xy 7.037417 -276.913144) (xy 7.006472 -276.977403) (xy 6.968526 -277.037794) (xy 6.924057 -277.093556)
			(xy 6.873624 -277.143989) (xy 6.817862 -277.188458) (xy 6.757471 -277.226404) (xy 6.693212 -277.257349)
			(xy 6.625892 -277.280906) (xy 6.556357 -277.296776) (xy 6.485483 -277.304762) (xy 6.414161 -277.304762)
			(xy 6.343287 -277.296776) (xy 6.273752 -277.280906) (xy 6.206432 -277.257349) (xy 6.142173 -277.226404)
			(xy 6.081782 -277.188458) (xy 6.02602 -277.143989) (xy 5.975587 -277.093556) (xy 5.931118 -277.037794)
			(xy 5.893172 -276.977403) (xy 5.862227 -276.913144) (xy 5.83867 -276.845824) (xy 5.8228 -276.776289)
			(xy 5.814814 -276.705415) (xy 0.509016 -276.705415) (xy 0.509016 -277.705413) (xy 1.31495 -277.705413)
			(xy 1.31495 -277.634091) (xy 1.322936 -277.563217) (xy 1.338806 -277.493682) (xy 1.362363 -277.426362)
			(xy 1.393308 -277.362103) (xy 1.431254 -277.301712) (xy 1.475723 -277.24595) (xy 1.526156 -277.195517)
			(xy 1.581918 -277.151048) (xy 1.642309 -277.113102) (xy 1.706568 -277.082157) (xy 1.773888 -277.0586)
			(xy 1.843423 -277.04273) (xy 1.914297 -277.034744) (xy 1.949958 -277.034244) (xy 1.985619 -277.034744)
			(xy 2.056493 -277.04273) (xy 2.126028 -277.0586) (xy 2.193348 -277.082157) (xy 2.257607 -277.113102)
			(xy 2.317998 -277.151048) (xy 2.37376 -277.195517) (xy 2.424193 -277.24595) (xy 2.468662 -277.301712)
			(xy 2.506608 -277.362103) (xy 2.537553 -277.426362) (xy 2.56111 -277.493682) (xy 2.57698 -277.563217)
			(xy 2.584966 -277.634091) (xy 2.584966 -277.705413) (xy 2.57698 -277.776287) (xy 2.56111 -277.845822)
			(xy 2.537553 -277.913142) (xy 2.506608 -277.977401) (xy 2.468662 -278.037792) (xy 2.424193 -278.093554)
			(xy 2.37376 -278.143987) (xy 2.317998 -278.188456) (xy 2.257607 -278.226402) (xy 2.193348 -278.257347)
			(xy 2.126028 -278.280904) (xy 2.056493 -278.296774) (xy 1.985619 -278.30476) (xy 1.914297 -278.30476)
			(xy 1.843423 -278.296774) (xy 1.773888 -278.280904) (xy 1.706568 -278.257347) (xy 1.642309 -278.226402)
			(xy 1.581918 -278.188456) (xy 1.526156 -278.143987) (xy 1.475723 -278.093554) (xy 1.431254 -278.037792)
			(xy 1.393308 -277.977401) (xy 1.362363 -277.913142) (xy 1.338806 -277.845822) (xy 1.322936 -277.776287)
			(xy 1.31495 -277.705413) (xy 0.509016 -277.705413) (xy 0.509016 -278.705411) (xy 3.314946 -278.705411)
			(xy 3.314946 -278.634089) (xy 3.322932 -278.563215) (xy 3.338802 -278.49368) (xy 3.362359 -278.42636)
			(xy 3.393304 -278.362101) (xy 3.43125 -278.30171) (xy 3.475719 -278.245948) (xy 3.526152 -278.195515)
			(xy 3.581914 -278.151046) (xy 3.642305 -278.1131) (xy 3.706564 -278.082155) (xy 3.773884 -278.058598)
			(xy 3.843419 -278.042728) (xy 3.914293 -278.034742) (xy 3.949954 -278.034242) (xy 3.985615 -278.034742)
			(xy 4.056489 -278.042728) (xy 4.126024 -278.058598) (xy 4.193344 -278.082155) (xy 4.257603 -278.1131)
			(xy 4.317994 -278.151046) (xy 4.373756 -278.195515) (xy 4.424189 -278.245948) (xy 4.468658 -278.30171)
			(xy 4.506604 -278.362101) (xy 4.537549 -278.42636) (xy 4.561106 -278.49368) (xy 4.576976 -278.563215)
			(xy 4.584962 -278.634089) (xy 4.584962 -278.705411) (xy 5.814814 -278.705411) (xy 5.814814 -278.634089)
			(xy 5.8228 -278.563215) (xy 5.83867 -278.49368) (xy 5.862227 -278.42636) (xy 5.893172 -278.362101)
			(xy 5.931118 -278.30171) (xy 5.975587 -278.245948) (xy 6.02602 -278.195515) (xy 6.081782 -278.151046)
			(xy 6.142173 -278.1131) (xy 6.206432 -278.082155) (xy 6.273752 -278.058598) (xy 6.343287 -278.042728)
			(xy 6.414161 -278.034742) (xy 6.449822 -278.034242) (xy 6.485483 -278.034742) (xy 6.556357 -278.042728)
			(xy 6.625892 -278.058598) (xy 6.693212 -278.082155) (xy 6.757471 -278.1131) (xy 6.817862 -278.151046)
			(xy 6.873624 -278.195515) (xy 6.924057 -278.245948) (xy 6.968526 -278.30171) (xy 7.006472 -278.362101)
			(xy 7.037417 -278.42636) (xy 7.060974 -278.49368) (xy 7.076844 -278.563215) (xy 7.08483 -278.634089)
			(xy 7.08483 -278.705411) (xy 7.076844 -278.776285) (xy 7.060974 -278.84582) (xy 7.037417 -278.91314)
			(xy 7.006472 -278.977399) (xy 6.968526 -279.03779) (xy 6.924057 -279.093552) (xy 6.873624 -279.143985)
			(xy 6.817862 -279.188454) (xy 6.757471 -279.2264) (xy 6.693212 -279.257345) (xy 6.625892 -279.280902)
			(xy 6.556357 -279.296772) (xy 6.485483 -279.304758) (xy 6.414161 -279.304758) (xy 6.343287 -279.296772)
			(xy 6.273752 -279.280902) (xy 6.206432 -279.257345) (xy 6.142173 -279.2264) (xy 6.081782 -279.188454)
			(xy 6.02602 -279.143985) (xy 5.975587 -279.093552) (xy 5.931118 -279.03779) (xy 5.893172 -278.977399)
			(xy 5.862227 -278.91314) (xy 5.83867 -278.84582) (xy 5.8228 -278.776285) (xy 5.814814 -278.705411)
			(xy 4.584962 -278.705411) (xy 4.576976 -278.776285) (xy 4.561106 -278.84582) (xy 4.537549 -278.91314)
			(xy 4.506604 -278.977399) (xy 4.468658 -279.03779) (xy 4.424189 -279.093552) (xy 4.373756 -279.143985)
			(xy 4.317994 -279.188454) (xy 4.257603 -279.2264) (xy 4.193344 -279.257345) (xy 4.126024 -279.280902)
			(xy 4.056489 -279.296772) (xy 3.985615 -279.304758) (xy 3.914293 -279.304758) (xy 3.843419 -279.296772)
			(xy 3.773884 -279.280902) (xy 3.706564 -279.257345) (xy 3.642305 -279.2264) (xy 3.581914 -279.188454)
			(xy 3.526152 -279.143985) (xy 3.475719 -279.093552) (xy 3.43125 -279.03779) (xy 3.393304 -278.977399)
			(xy 3.362359 -278.91314) (xy 3.338802 -278.84582) (xy 3.322932 -278.776285) (xy 3.314946 -278.705411)
			(xy 0.509016 -278.705411) (xy 0.509016 -279.705409) (xy 1.31495 -279.705409) (xy 1.31495 -279.634087)
			(xy 1.322936 -279.563213) (xy 1.338806 -279.493678) (xy 1.362363 -279.426358) (xy 1.393308 -279.362099)
			(xy 1.431254 -279.301708) (xy 1.475723 -279.245946) (xy 1.526156 -279.195513) (xy 1.581918 -279.151044)
			(xy 1.642309 -279.113098) (xy 1.706568 -279.082153) (xy 1.773888 -279.058596) (xy 1.843423 -279.042726)
			(xy 1.914297 -279.03474) (xy 1.949958 -279.03424) (xy 1.985619 -279.03474) (xy 2.056493 -279.042726)
			(xy 2.126028 -279.058596) (xy 2.193348 -279.082153) (xy 2.257607 -279.113098) (xy 2.317998 -279.151044)
			(xy 2.37376 -279.195513) (xy 2.424193 -279.245946) (xy 2.468662 -279.301708) (xy 2.506608 -279.362099)
			(xy 2.537553 -279.426358) (xy 2.56111 -279.493678) (xy 2.57698 -279.563213) (xy 2.584966 -279.634087)
			(xy 2.584966 -279.705409) (xy 7.81481 -279.705409) (xy 7.81481 -279.634087) (xy 7.822796 -279.563213)
			(xy 7.838666 -279.493678) (xy 7.862223 -279.426358) (xy 7.893168 -279.362099) (xy 7.931114 -279.301708)
			(xy 7.975583 -279.245946) (xy 8.026016 -279.195513) (xy 8.081778 -279.151044) (xy 8.142169 -279.113098)
			(xy 8.206428 -279.082153) (xy 8.273748 -279.058596) (xy 8.343283 -279.042726) (xy 8.414157 -279.03474)
			(xy 8.449818 -279.03424) (xy 8.485479 -279.03474) (xy 8.556353 -279.042726) (xy 8.625888 -279.058596)
			(xy 8.693208 -279.082153) (xy 8.757467 -279.113098) (xy 8.817858 -279.151044) (xy 8.87362 -279.195513)
			(xy 8.924053 -279.245946) (xy 8.968522 -279.301708) (xy 9.006468 -279.362099) (xy 9.037413 -279.426358)
			(xy 9.06097 -279.493678) (xy 9.07684 -279.563213) (xy 9.084826 -279.634087) (xy 9.084826 -279.705409)
			(xy 9.07684 -279.776283) (xy 9.06097 -279.845818) (xy 9.037413 -279.913138) (xy 9.006468 -279.977397)
			(xy 8.968522 -280.037788) (xy 8.924053 -280.09355) (xy 8.87362 -280.143983) (xy 8.817858 -280.188452)
			(xy 8.757467 -280.226398) (xy 8.693208 -280.257343) (xy 8.625888 -280.2809) (xy 8.556353 -280.29677)
			(xy 8.485479 -280.304756) (xy 8.414157 -280.304756) (xy 8.343283 -280.29677) (xy 8.273748 -280.2809)
			(xy 8.206428 -280.257343) (xy 8.142169 -280.226398) (xy 8.081778 -280.188452) (xy 8.026016 -280.143983)
			(xy 7.975583 -280.09355) (xy 7.931114 -280.037788) (xy 7.893168 -279.977397) (xy 7.862223 -279.913138)
			(xy 7.838666 -279.845818) (xy 7.822796 -279.776283) (xy 7.81481 -279.705409) (xy 2.584966 -279.705409)
			(xy 2.57698 -279.776283) (xy 2.56111 -279.845818) (xy 2.537553 -279.913138) (xy 2.506608 -279.977397)
			(xy 2.468662 -280.037788) (xy 2.424193 -280.09355) (xy 2.37376 -280.143983) (xy 2.317998 -280.188452)
			(xy 2.257607 -280.226398) (xy 2.193348 -280.257343) (xy 2.126028 -280.2809) (xy 2.056493 -280.29677)
			(xy 1.985619 -280.304756) (xy 1.914297 -280.304756) (xy 1.843423 -280.29677) (xy 1.773888 -280.2809)
			(xy 1.706568 -280.257343) (xy 1.642309 -280.226398) (xy 1.581918 -280.188452) (xy 1.526156 -280.143983)
			(xy 1.475723 -280.09355) (xy 1.431254 -280.037788) (xy 1.393308 -279.977397) (xy 1.362363 -279.913138)
			(xy 1.338806 -279.845818) (xy 1.322936 -279.776283) (xy 1.31495 -279.705409) (xy 0.509016 -279.705409)
			(xy 0.509016 -280.705407) (xy 3.314946 -280.705407) (xy 3.314946 -280.634085) (xy 3.322932 -280.563211)
			(xy 3.338802 -280.493676) (xy 3.362359 -280.426356) (xy 3.393304 -280.362097) (xy 3.43125 -280.301706)
			(xy 3.475719 -280.245944) (xy 3.526152 -280.195511) (xy 3.581914 -280.151042) (xy 3.642305 -280.113096)
			(xy 3.706564 -280.082151) (xy 3.773884 -280.058594) (xy 3.843419 -280.042724) (xy 3.914293 -280.034738)
			(xy 3.949954 -280.034238) (xy 3.985615 -280.034738) (xy 4.056489 -280.042724) (xy 4.126024 -280.058594)
			(xy 4.193344 -280.082151) (xy 4.257603 -280.113096) (xy 4.317994 -280.151042) (xy 4.373756 -280.195511)
			(xy 4.424189 -280.245944) (xy 4.468658 -280.301706) (xy 4.506604 -280.362097) (xy 4.537549 -280.426356)
			(xy 4.561106 -280.493676) (xy 4.576976 -280.563211) (xy 4.584962 -280.634085) (xy 4.584962 -280.705407)
			(xy 5.814814 -280.705407) (xy 5.814814 -280.634085) (xy 5.8228 -280.563211) (xy 5.83867 -280.493676)
			(xy 5.862227 -280.426356) (xy 5.893172 -280.362097) (xy 5.931118 -280.301706) (xy 5.975587 -280.245944)
			(xy 6.02602 -280.195511) (xy 6.081782 -280.151042) (xy 6.142173 -280.113096) (xy 6.206432 -280.082151)
			(xy 6.273752 -280.058594) (xy 6.343287 -280.042724) (xy 6.414161 -280.034738) (xy 6.449822 -280.034238)
			(xy 6.485483 -280.034738) (xy 6.556357 -280.042724) (xy 6.625892 -280.058594) (xy 6.693212 -280.082151)
			(xy 6.757471 -280.113096) (xy 6.817862 -280.151042) (xy 6.873624 -280.195511) (xy 6.924057 -280.245944)
			(xy 6.968526 -280.301706) (xy 7.006472 -280.362097) (xy 7.037417 -280.426356) (xy 7.060974 -280.493676)
			(xy 7.076844 -280.563211) (xy 7.08483 -280.634085) (xy 7.08483 -280.705407) (xy 7.076844 -280.776281)
			(xy 7.060974 -280.845816) (xy 7.037417 -280.913136) (xy 7.006472 -280.977395) (xy 6.968526 -281.037786)
			(xy 6.924057 -281.093548) (xy 6.873624 -281.143981) (xy 6.817862 -281.18845) (xy 6.757471 -281.226396)
			(xy 6.693212 -281.257341) (xy 6.625892 -281.280898) (xy 6.556357 -281.296768) (xy 6.485483 -281.304754)
			(xy 6.414161 -281.304754) (xy 6.343287 -281.296768) (xy 6.273752 -281.280898) (xy 6.206432 -281.257341)
			(xy 6.142173 -281.226396) (xy 6.081782 -281.18845) (xy 6.02602 -281.143981) (xy 5.975587 -281.093548)
			(xy 5.931118 -281.037786) (xy 5.893172 -280.977395) (xy 5.862227 -280.913136) (xy 5.83867 -280.845816)
			(xy 5.8228 -280.776281) (xy 5.814814 -280.705407) (xy 4.584962 -280.705407) (xy 4.576976 -280.776281)
			(xy 4.561106 -280.845816) (xy 4.537549 -280.913136) (xy 4.506604 -280.977395) (xy 4.468658 -281.037786)
			(xy 4.424189 -281.093548) (xy 4.373756 -281.143981) (xy 4.317994 -281.18845) (xy 4.257603 -281.226396)
			(xy 4.193344 -281.257341) (xy 4.126024 -281.280898) (xy 4.056489 -281.296768) (xy 3.985615 -281.304754)
			(xy 3.914293 -281.304754) (xy 3.843419 -281.296768) (xy 3.773884 -281.280898) (xy 3.706564 -281.257341)
			(xy 3.642305 -281.226396) (xy 3.581914 -281.18845) (xy 3.526152 -281.143981) (xy 3.475719 -281.093548)
			(xy 3.43125 -281.037786) (xy 3.393304 -280.977395) (xy 3.362359 -280.913136) (xy 3.338802 -280.845816)
			(xy 3.322932 -280.776281) (xy 3.314946 -280.705407) (xy 0.509016 -280.705407) (xy 0.509016 -281.705405)
			(xy 7.81481 -281.705405) (xy 7.81481 -281.634083) (xy 7.822796 -281.563209) (xy 7.838666 -281.493674)
			(xy 7.862223 -281.426354) (xy 7.893168 -281.362095) (xy 7.931114 -281.301704) (xy 7.975583 -281.245942)
			(xy 8.026016 -281.195509) (xy 8.081778 -281.15104) (xy 8.142169 -281.113094) (xy 8.206428 -281.082149)
			(xy 8.273748 -281.058592) (xy 8.343283 -281.042722) (xy 8.414157 -281.034736) (xy 8.449818 -281.034236)
			(xy 8.485479 -281.034736) (xy 8.556353 -281.042722) (xy 8.625888 -281.058592) (xy 8.693208 -281.082149)
			(xy 8.757467 -281.113094) (xy 8.817858 -281.15104) (xy 8.87362 -281.195509) (xy 8.924053 -281.245942)
			(xy 8.968522 -281.301704) (xy 9.006468 -281.362095) (xy 9.037413 -281.426354) (xy 9.06097 -281.493674)
			(xy 9.07684 -281.563209) (xy 9.084826 -281.634083) (xy 9.084826 -281.705405) (xy 9.07684 -281.776279)
			(xy 9.06097 -281.845814) (xy 9.037413 -281.913134) (xy 9.006468 -281.977393) (xy 8.968522 -282.037784)
			(xy 8.924053 -282.093546) (xy 8.87362 -282.143979) (xy 8.817858 -282.188448) (xy 8.757467 -282.226394)
			(xy 8.693208 -282.257339) (xy 8.625888 -282.280896) (xy 8.556353 -282.296766) (xy 8.485479 -282.304752)
			(xy 8.414157 -282.304752) (xy 8.343283 -282.296766) (xy 8.273748 -282.280896) (xy 8.206428 -282.257339)
			(xy 8.142169 -282.226394) (xy 8.081778 -282.188448) (xy 8.026016 -282.143979) (xy 7.975583 -282.093546)
			(xy 7.931114 -282.037784) (xy 7.893168 -281.977393) (xy 7.862223 -281.913134) (xy 7.838666 -281.845814)
			(xy 7.822796 -281.776279) (xy 7.81481 -281.705405) (xy 0.509016 -281.705405) (xy 0.509016 -282.705403)
			(xy 3.314946 -282.705403) (xy 3.314946 -282.634081) (xy 3.322932 -282.563207) (xy 3.338802 -282.493672)
			(xy 3.362359 -282.426352) (xy 3.393304 -282.362093) (xy 3.43125 -282.301702) (xy 3.475719 -282.24594)
			(xy 3.526152 -282.195507) (xy 3.581914 -282.151038) (xy 3.642305 -282.113092) (xy 3.706564 -282.082147)
			(xy 3.773884 -282.05859) (xy 3.843419 -282.04272) (xy 3.914293 -282.034734) (xy 3.949954 -282.034234)
			(xy 3.985615 -282.034734) (xy 4.056489 -282.04272) (xy 4.126024 -282.05859) (xy 4.193344 -282.082147)
			(xy 4.257603 -282.113092) (xy 4.317994 -282.151038) (xy 4.373756 -282.195507) (xy 4.424189 -282.24594)
			(xy 4.468658 -282.301702) (xy 4.506604 -282.362093) (xy 4.537549 -282.426352) (xy 4.561106 -282.493672)
			(xy 4.576976 -282.563207) (xy 4.584962 -282.634081) (xy 4.584962 -282.705403) (xy 4.576976 -282.776277)
			(xy 4.561106 -282.845812) (xy 4.537549 -282.913132) (xy 4.506604 -282.977391) (xy 4.468658 -283.037782)
			(xy 4.424189 -283.093544) (xy 4.373756 -283.143977) (xy 4.317994 -283.188446) (xy 4.257603 -283.226392)
			(xy 4.193344 -283.257337) (xy 4.126024 -283.280894) (xy 4.056489 -283.296764) (xy 3.985615 -283.30475)
			(xy 3.914293 -283.30475) (xy 3.843419 -283.296764) (xy 3.773884 -283.280894) (xy 3.706564 -283.257337)
			(xy 3.642305 -283.226392) (xy 3.581914 -283.188446) (xy 3.526152 -283.143977) (xy 3.475719 -283.093544)
			(xy 3.43125 -283.037782) (xy 3.393304 -282.977391) (xy 3.362359 -282.913132) (xy 3.338802 -282.845812)
			(xy 3.322932 -282.776277) (xy 3.314946 -282.705403) (xy 0.509016 -282.705403) (xy 0.509016 -283.705401)
			(xy 1.31495 -283.705401) (xy 1.31495 -283.634079) (xy 1.322936 -283.563205) (xy 1.338806 -283.49367)
			(xy 1.362363 -283.42635) (xy 1.393308 -283.362091) (xy 1.431254 -283.3017) (xy 1.475723 -283.245938)
			(xy 1.526156 -283.195505) (xy 1.581918 -283.151036) (xy 1.642309 -283.11309) (xy 1.706568 -283.082145)
			(xy 1.773888 -283.058588) (xy 1.843423 -283.042718) (xy 1.914297 -283.034732) (xy 1.949958 -283.034232)
			(xy 1.985619 -283.034732) (xy 2.056493 -283.042718) (xy 2.126028 -283.058588) (xy 2.193348 -283.082145)
			(xy 2.257607 -283.11309) (xy 2.317998 -283.151036) (xy 2.37376 -283.195505) (xy 2.424193 -283.245938)
			(xy 2.468662 -283.3017) (xy 2.506608 -283.362091) (xy 2.537553 -283.42635) (xy 2.56111 -283.49367)
			(xy 2.57698 -283.563205) (xy 2.584966 -283.634079) (xy 2.584966 -283.705401) (xy 7.81481 -283.705401)
			(xy 7.81481 -283.634079) (xy 7.822796 -283.563205) (xy 7.838666 -283.49367) (xy 7.862223 -283.42635)
			(xy 7.893168 -283.362091) (xy 7.931114 -283.3017) (xy 7.975583 -283.245938) (xy 8.026016 -283.195505)
			(xy 8.081778 -283.151036) (xy 8.142169 -283.11309) (xy 8.206428 -283.082145) (xy 8.273748 -283.058588)
			(xy 8.343283 -283.042718) (xy 8.414157 -283.034732) (xy 8.449818 -283.034232) (xy 8.485479 -283.034732)
			(xy 8.556353 -283.042718) (xy 8.625888 -283.058588) (xy 8.693208 -283.082145) (xy 8.757467 -283.11309)
			(xy 8.817858 -283.151036) (xy 8.87362 -283.195505) (xy 8.924053 -283.245938) (xy 8.968522 -283.3017)
			(xy 9.006468 -283.362091) (xy 9.037413 -283.42635) (xy 9.06097 -283.49367) (xy 9.07684 -283.563205)
			(xy 9.084826 -283.634079) (xy 9.084826 -283.705401) (xy 9.07684 -283.776275) (xy 9.06097 -283.84581)
			(xy 9.037413 -283.91313) (xy 9.006468 -283.977389) (xy 8.968522 -284.03778) (xy 8.924053 -284.093542)
			(xy 8.87362 -284.143975) (xy 8.817858 -284.188444) (xy 8.757467 -284.22639) (xy 8.693208 -284.257335)
			(xy 8.625888 -284.280892) (xy 8.556353 -284.296762) (xy 8.485479 -284.304748) (xy 8.414157 -284.304748)
			(xy 8.343283 -284.296762) (xy 8.273748 -284.280892) (xy 8.206428 -284.257335) (xy 8.142169 -284.22639)
			(xy 8.081778 -284.188444) (xy 8.026016 -284.143975) (xy 7.975583 -284.093542) (xy 7.931114 -284.03778)
			(xy 7.893168 -283.977389) (xy 7.862223 -283.91313) (xy 7.838666 -283.84581) (xy 7.822796 -283.776275)
			(xy 7.81481 -283.705401) (xy 2.584966 -283.705401) (xy 2.57698 -283.776275) (xy 2.56111 -283.84581)
			(xy 2.537553 -283.91313) (xy 2.506608 -283.977389) (xy 2.468662 -284.03778) (xy 2.424193 -284.093542)
			(xy 2.37376 -284.143975) (xy 2.317998 -284.188444) (xy 2.257607 -284.22639) (xy 2.193348 -284.257335)
			(xy 2.126028 -284.280892) (xy 2.056493 -284.296762) (xy 1.985619 -284.304748) (xy 1.914297 -284.304748)
			(xy 1.843423 -284.296762) (xy 1.773888 -284.280892) (xy 1.706568 -284.257335) (xy 1.642309 -284.22639)
			(xy 1.581918 -284.188444) (xy 1.526156 -284.143975) (xy 1.475723 -284.093542) (xy 1.431254 -284.03778)
			(xy 1.393308 -283.977389) (xy 1.362363 -283.91313) (xy 1.338806 -283.84581) (xy 1.322936 -283.776275)
			(xy 1.31495 -283.705401) (xy 0.509016 -283.705401) (xy 0.509016 -284.705653) (xy 3.314946 -284.705653)
			(xy 3.314946 -284.634331) (xy 3.322932 -284.563457) (xy 3.338802 -284.493922) (xy 3.362359 -284.426602)
			(xy 3.393304 -284.362343) (xy 3.43125 -284.301952) (xy 3.475719 -284.24619) (xy 3.526152 -284.195757)
			(xy 3.581914 -284.151288) (xy 3.642305 -284.113342) (xy 3.706564 -284.082397) (xy 3.773884 -284.05884)
			(xy 3.843419 -284.04297) (xy 3.914293 -284.034984) (xy 3.949954 -284.034484) (xy 3.985615 -284.034984)
			(xy 4.056489 -284.04297) (xy 4.126024 -284.05884) (xy 4.193344 -284.082397) (xy 4.257603 -284.113342)
			(xy 4.317994 -284.151288) (xy 4.373756 -284.195757) (xy 4.424189 -284.24619) (xy 4.468658 -284.301952)
			(xy 4.506604 -284.362343) (xy 4.537549 -284.426602) (xy 4.561106 -284.493922) (xy 4.576976 -284.563457)
			(xy 4.584962 -284.634331) (xy 4.584962 -284.705653) (xy 5.814814 -284.705653) (xy 5.814814 -284.634331)
			(xy 5.8228 -284.563457) (xy 5.83867 -284.493922) (xy 5.862227 -284.426602) (xy 5.893172 -284.362343)
			(xy 5.931118 -284.301952) (xy 5.975587 -284.24619) (xy 6.02602 -284.195757) (xy 6.081782 -284.151288)
			(xy 6.142173 -284.113342) (xy 6.206432 -284.082397) (xy 6.273752 -284.05884) (xy 6.343287 -284.04297)
			(xy 6.414161 -284.034984) (xy 6.449822 -284.034484) (xy 6.485483 -284.034984) (xy 6.556357 -284.04297)
			(xy 6.625892 -284.05884) (xy 6.693212 -284.082397) (xy 6.757471 -284.113342) (xy 6.817862 -284.151288)
			(xy 6.873624 -284.195757) (xy 6.924057 -284.24619) (xy 6.968526 -284.301952) (xy 7.006472 -284.362343)
			(xy 7.037417 -284.426602) (xy 7.060974 -284.493922) (xy 7.076844 -284.563457) (xy 7.08483 -284.634331)
			(xy 7.08483 -284.705653) (xy 7.076844 -284.776527) (xy 7.060974 -284.846062) (xy 7.037417 -284.913382)
			(xy 7.006472 -284.977641) (xy 6.968526 -285.038032) (xy 6.924057 -285.093794) (xy 6.873624 -285.144227)
			(xy 6.817862 -285.188696) (xy 6.757471 -285.226642) (xy 6.693212 -285.257587) (xy 6.625892 -285.281144)
			(xy 6.556357 -285.297014) (xy 6.485483 -285.305) (xy 6.414161 -285.305) (xy 6.343287 -285.297014)
			(xy 6.273752 -285.281144) (xy 6.206432 -285.257587) (xy 6.142173 -285.226642) (xy 6.081782 -285.188696)
			(xy 6.02602 -285.144227) (xy 5.975587 -285.093794) (xy 5.931118 -285.038032) (xy 5.893172 -284.977641)
			(xy 5.862227 -284.913382) (xy 5.83867 -284.846062) (xy 5.8228 -284.776527) (xy 5.814814 -284.705653)
			(xy 4.584962 -284.705653) (xy 4.576976 -284.776527) (xy 4.561106 -284.846062) (xy 4.537549 -284.913382)
			(xy 4.506604 -284.977641) (xy 4.468658 -285.038032) (xy 4.424189 -285.093794) (xy 4.373756 -285.144227)
			(xy 4.317994 -285.188696) (xy 4.257603 -285.226642) (xy 4.193344 -285.257587) (xy 4.126024 -285.281144)
			(xy 4.056489 -285.297014) (xy 3.985615 -285.305) (xy 3.914293 -285.305) (xy 3.843419 -285.297014)
			(xy 3.773884 -285.281144) (xy 3.706564 -285.257587) (xy 3.642305 -285.226642) (xy 3.581914 -285.188696)
			(xy 3.526152 -285.144227) (xy 3.475719 -285.093794) (xy 3.43125 -285.038032) (xy 3.393304 -284.977641)
			(xy 3.362359 -284.913382) (xy 3.338802 -284.846062) (xy 3.322932 -284.776527) (xy 3.314946 -284.705653)
			(xy 0.509016 -284.705653) (xy 0.509016 -285.705397) (xy 1.31495 -285.705397) (xy 1.31495 -285.634075)
			(xy 1.322936 -285.563201) (xy 1.338806 -285.493666) (xy 1.362363 -285.426346) (xy 1.393308 -285.362087)
			(xy 1.431254 -285.301696) (xy 1.475723 -285.245934) (xy 1.526156 -285.195501) (xy 1.581918 -285.151032)
			(xy 1.642309 -285.113086) (xy 1.706568 -285.082141) (xy 1.773888 -285.058584) (xy 1.843423 -285.042714)
			(xy 1.914297 -285.034728) (xy 1.949958 -285.034228) (xy 1.985619 -285.034728) (xy 2.056493 -285.042714)
			(xy 2.126028 -285.058584) (xy 2.193348 -285.082141) (xy 2.257607 -285.113086) (xy 2.317998 -285.151032)
			(xy 2.37376 -285.195501) (xy 2.424193 -285.245934) (xy 2.468662 -285.301696) (xy 2.506608 -285.362087)
			(xy 2.537553 -285.426346) (xy 2.56111 -285.493666) (xy 2.57698 -285.563201) (xy 2.584966 -285.634075)
			(xy 2.584966 -285.705397) (xy 7.81481 -285.705397) (xy 7.81481 -285.634075) (xy 7.822796 -285.563201)
			(xy 7.838666 -285.493666) (xy 7.862223 -285.426346) (xy 7.893168 -285.362087) (xy 7.931114 -285.301696)
			(xy 7.975583 -285.245934) (xy 8.026016 -285.195501) (xy 8.081778 -285.151032) (xy 8.142169 -285.113086)
			(xy 8.206428 -285.082141) (xy 8.273748 -285.058584) (xy 8.343283 -285.042714) (xy 8.414157 -285.034728)
			(xy 8.449818 -285.034228) (xy 8.485479 -285.034728) (xy 8.556353 -285.042714) (xy 8.625888 -285.058584)
			(xy 8.693208 -285.082141) (xy 8.757467 -285.113086) (xy 8.817858 -285.151032) (xy 8.87362 -285.195501)
			(xy 8.924053 -285.245934) (xy 8.968522 -285.301696) (xy 9.006468 -285.362087) (xy 9.037413 -285.426346)
			(xy 9.06097 -285.493666) (xy 9.07684 -285.563201) (xy 9.084826 -285.634075) (xy 9.084826 -285.705397)
			(xy 9.07684 -285.776271) (xy 9.06097 -285.845806) (xy 9.037413 -285.913126) (xy 9.006468 -285.977385)
			(xy 8.968522 -286.037776) (xy 8.924053 -286.093538) (xy 8.87362 -286.143971) (xy 8.817858 -286.18844)
			(xy 8.757467 -286.226386) (xy 8.693208 -286.257331) (xy 8.625888 -286.280888) (xy 8.556353 -286.296758)
			(xy 8.485479 -286.304744) (xy 8.414157 -286.304744) (xy 8.343283 -286.296758) (xy 8.273748 -286.280888)
			(xy 8.206428 -286.257331) (xy 8.142169 -286.226386) (xy 8.081778 -286.18844) (xy 8.026016 -286.143971)
			(xy 7.975583 -286.093538) (xy 7.931114 -286.037776) (xy 7.893168 -285.977385) (xy 7.862223 -285.913126)
			(xy 7.838666 -285.845806) (xy 7.822796 -285.776271) (xy 7.81481 -285.705397) (xy 2.584966 -285.705397)
			(xy 2.57698 -285.776271) (xy 2.56111 -285.845806) (xy 2.537553 -285.913126) (xy 2.506608 -285.977385)
			(xy 2.468662 -286.037776) (xy 2.424193 -286.093538) (xy 2.37376 -286.143971) (xy 2.317998 -286.18844)
			(xy 2.257607 -286.226386) (xy 2.193348 -286.257331) (xy 2.126028 -286.280888) (xy 2.056493 -286.296758)
			(xy 1.985619 -286.304744) (xy 1.914297 -286.304744) (xy 1.843423 -286.296758) (xy 1.773888 -286.280888)
			(xy 1.706568 -286.257331) (xy 1.642309 -286.226386) (xy 1.581918 -286.18844) (xy 1.526156 -286.143971)
			(xy 1.475723 -286.093538) (xy 1.431254 -286.037776) (xy 1.393308 -285.977385) (xy 1.362363 -285.913126)
			(xy 1.338806 -285.845806) (xy 1.322936 -285.776271) (xy 1.31495 -285.705397) (xy 0.509016 -285.705397)
			(xy 0.509016 -286.705649) (xy 5.814814 -286.705649) (xy 5.814814 -286.634327) (xy 5.8228 -286.563453)
			(xy 5.83867 -286.493918) (xy 5.862227 -286.426598) (xy 5.893172 -286.362339) (xy 5.931118 -286.301948)
			(xy 5.975587 -286.246186) (xy 6.02602 -286.195753) (xy 6.081782 -286.151284) (xy 6.142173 -286.113338)
			(xy 6.206432 -286.082393) (xy 6.273752 -286.058836) (xy 6.343287 -286.042966) (xy 6.414161 -286.03498)
			(xy 6.449822 -286.03448) (xy 6.485483 -286.03498) (xy 6.556357 -286.042966) (xy 6.625892 -286.058836)
			(xy 6.693212 -286.082393) (xy 6.757471 -286.113338) (xy 6.817862 -286.151284) (xy 6.873624 -286.195753)
			(xy 6.924057 -286.246186) (xy 6.968526 -286.301948) (xy 7.006472 -286.362339) (xy 7.037417 -286.426598)
			(xy 7.060974 -286.493918) (xy 7.076844 -286.563453) (xy 7.08483 -286.634327) (xy 7.08483 -286.705649)
			(xy 7.076844 -286.776523) (xy 7.060974 -286.846058) (xy 7.037417 -286.913378) (xy 7.006472 -286.977637)
			(xy 6.968526 -287.038028) (xy 6.924057 -287.09379) (xy 6.873624 -287.144223) (xy 6.817862 -287.188692)
			(xy 6.757471 -287.226638) (xy 6.693212 -287.257583) (xy 6.625892 -287.28114) (xy 6.556357 -287.29701)
			(xy 6.485483 -287.304996) (xy 6.414161 -287.304996) (xy 6.343287 -287.29701) (xy 6.273752 -287.28114)
			(xy 6.206432 -287.257583) (xy 6.142173 -287.226638) (xy 6.081782 -287.188692) (xy 6.02602 -287.144223)
			(xy 5.975587 -287.09379) (xy 5.931118 -287.038028) (xy 5.893172 -286.977637) (xy 5.862227 -286.913378)
			(xy 5.83867 -286.846058) (xy 5.8228 -286.776523) (xy 5.814814 -286.705649) (xy 0.509016 -286.705649)
			(xy 0.509016 -287.705393) (xy 1.31495 -287.705393) (xy 1.31495 -287.634071) (xy 1.322936 -287.563197)
			(xy 1.338806 -287.493662) (xy 1.362363 -287.426342) (xy 1.393308 -287.362083) (xy 1.431254 -287.301692)
			(xy 1.475723 -287.24593) (xy 1.526156 -287.195497) (xy 1.581918 -287.151028) (xy 1.642309 -287.113082)
			(xy 1.706568 -287.082137) (xy 1.773888 -287.05858) (xy 1.843423 -287.04271) (xy 1.914297 -287.034724)
			(xy 1.949958 -287.034224) (xy 1.985619 -287.034724) (xy 2.056493 -287.04271) (xy 2.126028 -287.05858)
			(xy 2.193348 -287.082137) (xy 2.257607 -287.113082) (xy 2.317998 -287.151028) (xy 2.37376 -287.195497)
			(xy 2.424193 -287.24593) (xy 2.468662 -287.301692) (xy 2.506608 -287.362083) (xy 2.537553 -287.426342)
			(xy 2.56111 -287.493662) (xy 2.57698 -287.563197) (xy 2.584966 -287.634071) (xy 2.584966 -287.705393)
			(xy 2.57698 -287.776267) (xy 2.56111 -287.845802) (xy 2.537553 -287.913122) (xy 2.506608 -287.977381)
			(xy 2.468662 -288.037772) (xy 2.424193 -288.093534) (xy 2.37376 -288.143967) (xy 2.317998 -288.188436)
			(xy 2.257607 -288.226382) (xy 2.193348 -288.257327) (xy 2.126028 -288.280884) (xy 2.056493 -288.296754)
			(xy 1.985619 -288.30474) (xy 1.914297 -288.30474) (xy 1.843423 -288.296754) (xy 1.773888 -288.280884)
			(xy 1.706568 -288.257327) (xy 1.642309 -288.226382) (xy 1.581918 -288.188436) (xy 1.526156 -288.143967)
			(xy 1.475723 -288.093534) (xy 1.431254 -288.037772) (xy 1.393308 -287.977381) (xy 1.362363 -287.913122)
			(xy 1.338806 -287.845802) (xy 1.322936 -287.776267) (xy 1.31495 -287.705393) (xy 0.509016 -287.705393)
			(xy 0.509016 -288.705645) (xy 3.314946 -288.705645) (xy 3.314946 -288.634323) (xy 3.322932 -288.563449)
			(xy 3.338802 -288.493914) (xy 3.362359 -288.426594) (xy 3.393304 -288.362335) (xy 3.43125 -288.301944)
			(xy 3.475719 -288.246182) (xy 3.526152 -288.195749) (xy 3.581914 -288.15128) (xy 3.642305 -288.113334)
			(xy 3.706564 -288.082389) (xy 3.773884 -288.058832) (xy 3.843419 -288.042962) (xy 3.914293 -288.034976)
			(xy 3.949954 -288.034476) (xy 3.985615 -288.034976) (xy 4.056489 -288.042962) (xy 4.126024 -288.058832)
			(xy 4.193344 -288.082389) (xy 4.257603 -288.113334) (xy 4.317994 -288.15128) (xy 4.373756 -288.195749)
			(xy 4.424189 -288.246182) (xy 4.468658 -288.301944) (xy 4.506604 -288.362335) (xy 4.537549 -288.426594)
			(xy 4.561106 -288.493914) (xy 4.576976 -288.563449) (xy 4.584962 -288.634323) (xy 4.584962 -288.705645)
			(xy 5.814814 -288.705645) (xy 5.814814 -288.634323) (xy 5.8228 -288.563449) (xy 5.83867 -288.493914)
			(xy 5.862227 -288.426594) (xy 5.893172 -288.362335) (xy 5.931118 -288.301944) (xy 5.975587 -288.246182)
			(xy 6.02602 -288.195749) (xy 6.081782 -288.15128) (xy 6.142173 -288.113334) (xy 6.206432 -288.082389)
			(xy 6.273752 -288.058832) (xy 6.343287 -288.042962) (xy 6.414161 -288.034976) (xy 6.449822 -288.034476)
			(xy 6.485483 -288.034976) (xy 6.556357 -288.042962) (xy 6.625892 -288.058832) (xy 6.693212 -288.082389)
			(xy 6.757471 -288.113334) (xy 6.817862 -288.15128) (xy 6.873624 -288.195749) (xy 6.924057 -288.246182)
			(xy 6.968526 -288.301944) (xy 7.006472 -288.362335) (xy 7.037417 -288.426594) (xy 7.060974 -288.493914)
			(xy 7.076844 -288.563449) (xy 7.08483 -288.634323) (xy 7.08483 -288.705645) (xy 7.076844 -288.776519)
			(xy 7.060974 -288.846054) (xy 7.037417 -288.913374) (xy 7.006472 -288.977633) (xy 6.968526 -289.038024)
			(xy 6.924057 -289.093786) (xy 6.873624 -289.144219) (xy 6.817862 -289.188688) (xy 6.757471 -289.226634)
			(xy 6.693212 -289.257579) (xy 6.625892 -289.281136) (xy 6.556357 -289.297006) (xy 6.485483 -289.304992)
			(xy 6.414161 -289.304992) (xy 6.343287 -289.297006) (xy 6.273752 -289.281136) (xy 6.206432 -289.257579)
			(xy 6.142173 -289.226634) (xy 6.081782 -289.188688) (xy 6.02602 -289.144219) (xy 5.975587 -289.093786)
			(xy 5.931118 -289.038024) (xy 5.893172 -288.977633) (xy 5.862227 -288.913374) (xy 5.83867 -288.846054)
			(xy 5.8228 -288.776519) (xy 5.814814 -288.705645) (xy 4.584962 -288.705645) (xy 4.576976 -288.776519)
			(xy 4.561106 -288.846054) (xy 4.537549 -288.913374) (xy 4.506604 -288.977633) (xy 4.468658 -289.038024)
			(xy 4.424189 -289.093786) (xy 4.373756 -289.144219) (xy 4.317994 -289.188688) (xy 4.257603 -289.226634)
			(xy 4.193344 -289.257579) (xy 4.126024 -289.281136) (xy 4.056489 -289.297006) (xy 3.985615 -289.304992)
			(xy 3.914293 -289.304992) (xy 3.843419 -289.297006) (xy 3.773884 -289.281136) (xy 3.706564 -289.257579)
			(xy 3.642305 -289.226634) (xy 3.581914 -289.188688) (xy 3.526152 -289.144219) (xy 3.475719 -289.093786)
			(xy 3.43125 -289.038024) (xy 3.393304 -288.977633) (xy 3.362359 -288.913374) (xy 3.338802 -288.846054)
			(xy 3.322932 -288.776519) (xy 3.314946 -288.705645) (xy 0.509016 -288.705645) (xy 0.509016 -289.705389)
			(xy 1.31495 -289.705389) (xy 1.31495 -289.634067) (xy 1.322936 -289.563193) (xy 1.338806 -289.493658)
			(xy 1.362363 -289.426338) (xy 1.393308 -289.362079) (xy 1.431254 -289.301688) (xy 1.475723 -289.245926)
			(xy 1.526156 -289.195493) (xy 1.581918 -289.151024) (xy 1.642309 -289.113078) (xy 1.706568 -289.082133)
			(xy 1.773888 -289.058576) (xy 1.843423 -289.042706) (xy 1.914297 -289.03472) (xy 1.949958 -289.03422)
			(xy 1.985619 -289.03472) (xy 2.056493 -289.042706) (xy 2.126028 -289.058576) (xy 2.193348 -289.082133)
			(xy 2.257607 -289.113078) (xy 2.317998 -289.151024) (xy 2.37376 -289.195493) (xy 2.424193 -289.245926)
			(xy 2.468662 -289.301688) (xy 2.506608 -289.362079) (xy 2.537553 -289.426338) (xy 2.56111 -289.493658)
			(xy 2.57698 -289.563193) (xy 2.584966 -289.634067) (xy 2.584966 -289.705389) (xy 7.81481 -289.705389)
			(xy 7.81481 -289.634067) (xy 7.822796 -289.563193) (xy 7.838666 -289.493658) (xy 7.862223 -289.426338)
			(xy 7.893168 -289.362079) (xy 7.931114 -289.301688) (xy 7.975583 -289.245926) (xy 8.026016 -289.195493)
			(xy 8.081778 -289.151024) (xy 8.142169 -289.113078) (xy 8.206428 -289.082133) (xy 8.273748 -289.058576)
			(xy 8.343283 -289.042706) (xy 8.414157 -289.03472) (xy 8.449818 -289.03422) (xy 8.485479 -289.03472)
			(xy 8.556353 -289.042706) (xy 8.625888 -289.058576) (xy 8.693208 -289.082133) (xy 8.757467 -289.113078)
			(xy 8.817858 -289.151024) (xy 8.87362 -289.195493) (xy 8.924053 -289.245926) (xy 8.968522 -289.301688)
			(xy 9.006468 -289.362079) (xy 9.037413 -289.426338) (xy 9.06097 -289.493658) (xy 9.07684 -289.563193)
			(xy 9.084826 -289.634067) (xy 9.084826 -289.705389) (xy 9.07684 -289.776263) (xy 9.06097 -289.845798)
			(xy 9.037413 -289.913118) (xy 9.006468 -289.977377) (xy 8.968522 -290.037768) (xy 8.924053 -290.09353)
			(xy 8.87362 -290.143963) (xy 8.817858 -290.188432) (xy 8.757467 -290.226378) (xy 8.693208 -290.257323)
			(xy 8.625888 -290.28088) (xy 8.556353 -290.29675) (xy 8.485479 -290.304736) (xy 8.414157 -290.304736)
			(xy 8.343283 -290.29675) (xy 8.273748 -290.28088) (xy 8.206428 -290.257323) (xy 8.142169 -290.226378)
			(xy 8.081778 -290.188432) (xy 8.026016 -290.143963) (xy 7.975583 -290.09353) (xy 7.931114 -290.037768)
			(xy 7.893168 -289.977377) (xy 7.862223 -289.913118) (xy 7.838666 -289.845798) (xy 7.822796 -289.776263)
			(xy 7.81481 -289.705389) (xy 2.584966 -289.705389) (xy 2.57698 -289.776263) (xy 2.56111 -289.845798)
			(xy 2.537553 -289.913118) (xy 2.506608 -289.977377) (xy 2.468662 -290.037768) (xy 2.424193 -290.09353)
			(xy 2.37376 -290.143963) (xy 2.317998 -290.188432) (xy 2.257607 -290.226378) (xy 2.193348 -290.257323)
			(xy 2.126028 -290.28088) (xy 2.056493 -290.29675) (xy 1.985619 -290.304736) (xy 1.914297 -290.304736)
			(xy 1.843423 -290.29675) (xy 1.773888 -290.28088) (xy 1.706568 -290.257323) (xy 1.642309 -290.226378)
			(xy 1.581918 -290.188432) (xy 1.526156 -290.143963) (xy 1.475723 -290.09353) (xy 1.431254 -290.037768)
			(xy 1.393308 -289.977377) (xy 1.362363 -289.913118) (xy 1.338806 -289.845798) (xy 1.322936 -289.776263)
			(xy 1.31495 -289.705389) (xy 0.509016 -289.705389) (xy 0.509016 -290.705641) (xy 3.314946 -290.705641)
			(xy 3.314946 -290.634319) (xy 3.322932 -290.563445) (xy 3.338802 -290.49391) (xy 3.362359 -290.42659)
			(xy 3.393304 -290.362331) (xy 3.43125 -290.30194) (xy 3.475719 -290.246178) (xy 3.526152 -290.195745)
			(xy 3.581914 -290.151276) (xy 3.642305 -290.11333) (xy 3.706564 -290.082385) (xy 3.773884 -290.058828)
			(xy 3.843419 -290.042958) (xy 3.914293 -290.034972) (xy 3.949954 -290.034472) (xy 3.985615 -290.034972)
			(xy 4.056489 -290.042958) (xy 4.126024 -290.058828) (xy 4.193344 -290.082385) (xy 4.257603 -290.11333)
			(xy 4.317994 -290.151276) (xy 4.373756 -290.195745) (xy 4.424189 -290.246178) (xy 4.468658 -290.30194)
			(xy 4.506604 -290.362331) (xy 4.537549 -290.42659) (xy 4.561106 -290.49391) (xy 4.576976 -290.563445)
			(xy 4.584962 -290.634319) (xy 4.584962 -290.705641) (xy 5.814814 -290.705641) (xy 5.814814 -290.634319)
			(xy 5.8228 -290.563445) (xy 5.83867 -290.49391) (xy 5.862227 -290.42659) (xy 5.893172 -290.362331)
			(xy 5.931118 -290.30194) (xy 5.975587 -290.246178) (xy 6.02602 -290.195745) (xy 6.081782 -290.151276)
			(xy 6.142173 -290.11333) (xy 6.206432 -290.082385) (xy 6.273752 -290.058828) (xy 6.343287 -290.042958)
			(xy 6.414161 -290.034972) (xy 6.449822 -290.034472) (xy 6.485483 -290.034972) (xy 6.556357 -290.042958)
			(xy 6.625892 -290.058828) (xy 6.693212 -290.082385) (xy 6.757471 -290.11333) (xy 6.817862 -290.151276)
			(xy 6.873624 -290.195745) (xy 6.924057 -290.246178) (xy 6.968526 -290.30194) (xy 7.006472 -290.362331)
			(xy 7.037417 -290.42659) (xy 7.060974 -290.49391) (xy 7.076844 -290.563445) (xy 7.08483 -290.634319)
			(xy 7.08483 -290.705641) (xy 7.076844 -290.776515) (xy 7.060974 -290.84605) (xy 7.037417 -290.91337)
			(xy 7.006472 -290.977629) (xy 6.968526 -291.03802) (xy 6.924057 -291.093782) (xy 6.873624 -291.144215)
			(xy 6.817862 -291.188684) (xy 6.757471 -291.22663) (xy 6.693212 -291.257575) (xy 6.625892 -291.281132)
			(xy 6.556357 -291.297002) (xy 6.485483 -291.304988) (xy 6.414161 -291.304988) (xy 6.343287 -291.297002)
			(xy 6.273752 -291.281132) (xy 6.206432 -291.257575) (xy 6.142173 -291.22663) (xy 6.081782 -291.188684)
			(xy 6.02602 -291.144215) (xy 5.975587 -291.093782) (xy 5.931118 -291.03802) (xy 5.893172 -290.977629)
			(xy 5.862227 -290.91337) (xy 5.83867 -290.84605) (xy 5.8228 -290.776515) (xy 5.814814 -290.705641)
			(xy 4.584962 -290.705641) (xy 4.576976 -290.776515) (xy 4.561106 -290.84605) (xy 4.537549 -290.91337)
			(xy 4.506604 -290.977629) (xy 4.468658 -291.03802) (xy 4.424189 -291.093782) (xy 4.373756 -291.144215)
			(xy 4.317994 -291.188684) (xy 4.257603 -291.22663) (xy 4.193344 -291.257575) (xy 4.126024 -291.281132)
			(xy 4.056489 -291.297002) (xy 3.985615 -291.304988) (xy 3.914293 -291.304988) (xy 3.843419 -291.297002)
			(xy 3.773884 -291.281132) (xy 3.706564 -291.257575) (xy 3.642305 -291.22663) (xy 3.581914 -291.188684)
			(xy 3.526152 -291.144215) (xy 3.475719 -291.093782) (xy 3.43125 -291.03802) (xy 3.393304 -290.977629)
			(xy 3.362359 -290.91337) (xy 3.338802 -290.84605) (xy 3.322932 -290.776515) (xy 3.314946 -290.705641)
			(xy 0.509016 -290.705641) (xy 0.509016 -291.705385) (xy 7.81481 -291.705385) (xy 7.81481 -291.634063)
			(xy 7.822796 -291.563189) (xy 7.838666 -291.493654) (xy 7.862223 -291.426334) (xy 7.893168 -291.362075)
			(xy 7.931114 -291.301684) (xy 7.975583 -291.245922) (xy 8.026016 -291.195489) (xy 8.081778 -291.15102)
			(xy 8.142169 -291.113074) (xy 8.206428 -291.082129) (xy 8.273748 -291.058572) (xy 8.343283 -291.042702)
			(xy 8.414157 -291.034716) (xy 8.449818 -291.034216) (xy 8.485479 -291.034716) (xy 8.556353 -291.042702)
			(xy 8.625888 -291.058572) (xy 8.693208 -291.082129) (xy 8.757467 -291.113074) (xy 8.817858 -291.15102)
			(xy 8.87362 -291.195489) (xy 8.924053 -291.245922) (xy 8.968522 -291.301684) (xy 9.006468 -291.362075)
			(xy 9.037413 -291.426334) (xy 9.06097 -291.493654) (xy 9.07684 -291.563189) (xy 9.084826 -291.634063)
			(xy 9.084826 -291.705385) (xy 9.07684 -291.776259) (xy 9.06097 -291.845794) (xy 9.037413 -291.913114)
			(xy 9.006468 -291.977373) (xy 8.968522 -292.037764) (xy 8.924053 -292.093526) (xy 8.87362 -292.143959)
			(xy 8.817858 -292.188428) (xy 8.757467 -292.226374) (xy 8.693208 -292.257319) (xy 8.625888 -292.280876)
			(xy 8.556353 -292.296746) (xy 8.485479 -292.304732) (xy 8.414157 -292.304732) (xy 8.343283 -292.296746)
			(xy 8.273748 -292.280876) (xy 8.206428 -292.257319) (xy 8.142169 -292.226374) (xy 8.081778 -292.188428)
			(xy 8.026016 -292.143959) (xy 7.975583 -292.093526) (xy 7.931114 -292.037764) (xy 7.893168 -291.977373)
			(xy 7.862223 -291.913114) (xy 7.838666 -291.845794) (xy 7.822796 -291.776259) (xy 7.81481 -291.705385)
			(xy 0.509016 -291.705385) (xy 0.509016 -292.705637) (xy 3.314946 -292.705637) (xy 3.314946 -292.634315)
			(xy 3.322932 -292.563441) (xy 3.338802 -292.493906) (xy 3.362359 -292.426586) (xy 3.393304 -292.362327)
			(xy 3.43125 -292.301936) (xy 3.475719 -292.246174) (xy 3.526152 -292.195741) (xy 3.581914 -292.151272)
			(xy 3.642305 -292.113326) (xy 3.706564 -292.082381) (xy 3.773884 -292.058824) (xy 3.843419 -292.042954)
			(xy 3.914293 -292.034968) (xy 3.949954 -292.034468) (xy 3.985615 -292.034968) (xy 4.056489 -292.042954)
			(xy 4.126024 -292.058824) (xy 4.193344 -292.082381) (xy 4.257603 -292.113326) (xy 4.317994 -292.151272)
			(xy 4.373756 -292.195741) (xy 4.424189 -292.246174) (xy 4.468658 -292.301936) (xy 4.506604 -292.362327)
			(xy 4.537549 -292.426586) (xy 4.561106 -292.493906) (xy 4.576976 -292.563441) (xy 4.584962 -292.634315)
			(xy 4.584962 -292.705637) (xy 4.576976 -292.776511) (xy 4.561106 -292.846046) (xy 4.537549 -292.913366)
			(xy 4.506604 -292.977625) (xy 4.468658 -293.038016) (xy 4.424189 -293.093778) (xy 4.373756 -293.144211)
			(xy 4.317994 -293.18868) (xy 4.257603 -293.226626) (xy 4.193344 -293.257571) (xy 4.126024 -293.281128)
			(xy 4.056489 -293.296998) (xy 3.985615 -293.304984) (xy 3.914293 -293.304984) (xy 3.843419 -293.296998)
			(xy 3.773884 -293.281128) (xy 3.706564 -293.257571) (xy 3.642305 -293.226626) (xy 3.581914 -293.18868)
			(xy 3.526152 -293.144211) (xy 3.475719 -293.093778) (xy 3.43125 -293.038016) (xy 3.393304 -292.977625)
			(xy 3.362359 -292.913366) (xy 3.338802 -292.846046) (xy 3.322932 -292.776511) (xy 3.314946 -292.705637)
			(xy 0.509016 -292.705637) (xy 0.509016 -293.705381) (xy 1.31495 -293.705381) (xy 1.31495 -293.634059)
			(xy 1.322936 -293.563185) (xy 1.338806 -293.49365) (xy 1.362363 -293.42633) (xy 1.393308 -293.362071)
			(xy 1.431254 -293.30168) (xy 1.475723 -293.245918) (xy 1.526156 -293.195485) (xy 1.581918 -293.151016)
			(xy 1.642309 -293.11307) (xy 1.706568 -293.082125) (xy 1.773888 -293.058568) (xy 1.843423 -293.042698)
			(xy 1.914297 -293.034712) (xy 1.949958 -293.034212) (xy 1.985619 -293.034712) (xy 2.056493 -293.042698)
			(xy 2.126028 -293.058568) (xy 2.193348 -293.082125) (xy 2.257607 -293.11307) (xy 2.317998 -293.151016)
			(xy 2.37376 -293.195485) (xy 2.424193 -293.245918) (xy 2.468662 -293.30168) (xy 2.506608 -293.362071)
			(xy 2.537553 -293.42633) (xy 2.56111 -293.49365) (xy 2.57698 -293.563185) (xy 2.584966 -293.634059)
			(xy 2.584966 -293.705381) (xy 7.81481 -293.705381) (xy 7.81481 -293.634059) (xy 7.822796 -293.563185)
			(xy 7.838666 -293.49365) (xy 7.862223 -293.42633) (xy 7.893168 -293.362071) (xy 7.931114 -293.30168)
			(xy 7.975583 -293.245918) (xy 8.026016 -293.195485) (xy 8.081778 -293.151016) (xy 8.142169 -293.11307)
			(xy 8.206428 -293.082125) (xy 8.273748 -293.058568) (xy 8.343283 -293.042698) (xy 8.414157 -293.034712)
			(xy 8.449818 -293.034212) (xy 8.485479 -293.034712) (xy 8.556353 -293.042698) (xy 8.625888 -293.058568)
			(xy 8.693208 -293.082125) (xy 8.757467 -293.11307) (xy 8.817858 -293.151016) (xy 8.87362 -293.195485)
			(xy 8.924053 -293.245918) (xy 8.968522 -293.30168) (xy 9.006468 -293.362071) (xy 9.037413 -293.42633)
			(xy 9.06097 -293.49365) (xy 9.07684 -293.563185) (xy 9.084826 -293.634059) (xy 9.084826 -293.705381)
			(xy 9.07684 -293.776255) (xy 9.06097 -293.84579) (xy 9.037413 -293.91311) (xy 9.006468 -293.977369)
			(xy 8.968522 -294.03776) (xy 8.924053 -294.093522) (xy 8.87362 -294.143955) (xy 8.817858 -294.188424)
			(xy 8.757467 -294.22637) (xy 8.693208 -294.257315) (xy 8.625888 -294.280872) (xy 8.556353 -294.296742)
			(xy 8.485479 -294.304728) (xy 8.414157 -294.304728) (xy 8.343283 -294.296742) (xy 8.273748 -294.280872)
			(xy 8.206428 -294.257315) (xy 8.142169 -294.22637) (xy 8.081778 -294.188424) (xy 8.026016 -294.143955)
			(xy 7.975583 -294.093522) (xy 7.931114 -294.03776) (xy 7.893168 -293.977369) (xy 7.862223 -293.91311)
			(xy 7.838666 -293.84579) (xy 7.822796 -293.776255) (xy 7.81481 -293.705381) (xy 2.584966 -293.705381)
			(xy 2.57698 -293.776255) (xy 2.56111 -293.84579) (xy 2.537553 -293.91311) (xy 2.506608 -293.977369)
			(xy 2.468662 -294.03776) (xy 2.424193 -294.093522) (xy 2.37376 -294.143955) (xy 2.317998 -294.188424)
			(xy 2.257607 -294.22637) (xy 2.193348 -294.257315) (xy 2.126028 -294.280872) (xy 2.056493 -294.296742)
			(xy 1.985619 -294.304728) (xy 1.914297 -294.304728) (xy 1.843423 -294.296742) (xy 1.773888 -294.280872)
			(xy 1.706568 -294.257315) (xy 1.642309 -294.22637) (xy 1.581918 -294.188424) (xy 1.526156 -294.143955)
			(xy 1.475723 -294.093522) (xy 1.431254 -294.03776) (xy 1.393308 -293.977369) (xy 1.362363 -293.91311)
			(xy 1.338806 -293.84579) (xy 1.322936 -293.776255) (xy 1.31495 -293.705381) (xy 0.509016 -293.705381)
			(xy 0.509016 -294.705633) (xy 3.314946 -294.705633) (xy 3.314946 -294.634311) (xy 3.322932 -294.563437)
			(xy 3.338802 -294.493902) (xy 3.362359 -294.426582) (xy 3.393304 -294.362323) (xy 3.43125 -294.301932)
			(xy 3.475719 -294.24617) (xy 3.526152 -294.195737) (xy 3.581914 -294.151268) (xy 3.642305 -294.113322)
			(xy 3.706564 -294.082377) (xy 3.773884 -294.05882) (xy 3.843419 -294.04295) (xy 3.914293 -294.034964)
			(xy 3.949954 -294.034464) (xy 3.985615 -294.034964) (xy 4.056489 -294.04295) (xy 4.126024 -294.05882)
			(xy 4.193344 -294.082377) (xy 4.257603 -294.113322) (xy 4.317994 -294.151268) (xy 4.373756 -294.195737)
			(xy 4.424189 -294.24617) (xy 4.468658 -294.301932) (xy 4.506604 -294.362323) (xy 4.537549 -294.426582)
			(xy 4.561106 -294.493902) (xy 4.576976 -294.563437) (xy 4.584962 -294.634311) (xy 4.584962 -294.705633)
			(xy 5.814814 -294.705633) (xy 5.814814 -294.634311) (xy 5.8228 -294.563437) (xy 5.83867 -294.493902)
			(xy 5.862227 -294.426582) (xy 5.893172 -294.362323) (xy 5.931118 -294.301932) (xy 5.975587 -294.24617)
			(xy 6.02602 -294.195737) (xy 6.081782 -294.151268) (xy 6.142173 -294.113322) (xy 6.206432 -294.082377)
			(xy 6.273752 -294.05882) (xy 6.343287 -294.04295) (xy 6.414161 -294.034964) (xy 6.449822 -294.034464)
			(xy 6.485483 -294.034964) (xy 6.556357 -294.04295) (xy 6.625892 -294.05882) (xy 6.693212 -294.082377)
			(xy 6.757471 -294.113322) (xy 6.817862 -294.151268) (xy 6.873624 -294.195737) (xy 6.924057 -294.24617)
			(xy 6.968526 -294.301932) (xy 7.006472 -294.362323) (xy 7.037417 -294.426582) (xy 7.060974 -294.493902)
			(xy 7.076844 -294.563437) (xy 7.08483 -294.634311) (xy 7.08483 -294.705633) (xy 7.076844 -294.776507)
			(xy 7.060974 -294.846042) (xy 7.037417 -294.913362) (xy 7.006472 -294.977621) (xy 6.968526 -295.038012)
			(xy 6.924057 -295.093774) (xy 6.873624 -295.144207) (xy 6.817862 -295.188676) (xy 6.757471 -295.226622)
			(xy 6.693212 -295.257567) (xy 6.625892 -295.281124) (xy 6.556357 -295.296994) (xy 6.485483 -295.30498)
			(xy 6.414161 -295.30498) (xy 6.343287 -295.296994) (xy 6.273752 -295.281124) (xy 6.206432 -295.257567)
			(xy 6.142173 -295.226622) (xy 6.081782 -295.188676) (xy 6.02602 -295.144207) (xy 5.975587 -295.093774)
			(xy 5.931118 -295.038012) (xy 5.893172 -294.977621) (xy 5.862227 -294.913362) (xy 5.83867 -294.846042)
			(xy 5.8228 -294.776507) (xy 5.814814 -294.705633) (xy 4.584962 -294.705633) (xy 4.576976 -294.776507)
			(xy 4.561106 -294.846042) (xy 4.537549 -294.913362) (xy 4.506604 -294.977621) (xy 4.468658 -295.038012)
			(xy 4.424189 -295.093774) (xy 4.373756 -295.144207) (xy 4.317994 -295.188676) (xy 4.257603 -295.226622)
			(xy 4.193344 -295.257567) (xy 4.126024 -295.281124) (xy 4.056489 -295.296994) (xy 3.985615 -295.30498)
			(xy 3.914293 -295.30498) (xy 3.843419 -295.296994) (xy 3.773884 -295.281124) (xy 3.706564 -295.257567)
			(xy 3.642305 -295.226622) (xy 3.581914 -295.188676) (xy 3.526152 -295.144207) (xy 3.475719 -295.093774)
			(xy 3.43125 -295.038012) (xy 3.393304 -294.977621) (xy 3.362359 -294.913362) (xy 3.338802 -294.846042)
			(xy 3.322932 -294.776507) (xy 3.314946 -294.705633) (xy 0.509016 -294.705633) (xy 0.509016 -295.705631)
			(xy 1.31495 -295.705631) (xy 1.31495 -295.634309) (xy 1.322936 -295.563435) (xy 1.338806 -295.4939)
			(xy 1.362363 -295.42658) (xy 1.393308 -295.362321) (xy 1.431254 -295.30193) (xy 1.475723 -295.246168)
			(xy 1.526156 -295.195735) (xy 1.581918 -295.151266) (xy 1.642309 -295.11332) (xy 1.706568 -295.082375)
			(xy 1.773888 -295.058818) (xy 1.843423 -295.042948) (xy 1.914297 -295.034962) (xy 1.949958 -295.034462)
			(xy 1.985619 -295.034962) (xy 2.056493 -295.042948) (xy 2.126028 -295.058818) (xy 2.193348 -295.082375)
			(xy 2.257607 -295.11332) (xy 2.317998 -295.151266) (xy 2.37376 -295.195735) (xy 2.424193 -295.246168)
			(xy 2.468662 -295.30193) (xy 2.506608 -295.362321) (xy 2.537553 -295.42658) (xy 2.56111 -295.4939)
			(xy 2.57698 -295.563435) (xy 2.584966 -295.634309) (xy 2.584966 -295.705631) (xy 7.81481 -295.705631)
			(xy 7.81481 -295.634309) (xy 7.822796 -295.563435) (xy 7.838666 -295.4939) (xy 7.862223 -295.42658)
			(xy 7.893168 -295.362321) (xy 7.931114 -295.30193) (xy 7.975583 -295.246168) (xy 8.026016 -295.195735)
			(xy 8.081778 -295.151266) (xy 8.142169 -295.11332) (xy 8.206428 -295.082375) (xy 8.273748 -295.058818)
			(xy 8.343283 -295.042948) (xy 8.414157 -295.034962) (xy 8.449818 -295.034462) (xy 8.485479 -295.034962)
			(xy 8.556353 -295.042948) (xy 8.625888 -295.058818) (xy 8.693208 -295.082375) (xy 8.757467 -295.11332)
			(xy 8.817858 -295.151266) (xy 8.87362 -295.195735) (xy 8.924053 -295.246168) (xy 8.968522 -295.30193)
			(xy 9.006468 -295.362321) (xy 9.037413 -295.42658) (xy 9.06097 -295.4939) (xy 9.07684 -295.563435)
			(xy 9.084826 -295.634309) (xy 9.084826 -295.705631) (xy 9.07684 -295.776505) (xy 9.06097 -295.84604)
			(xy 9.042055 -295.900094) (xy 11.599164 -295.900094) (xy 11.599658 -295.800658) (xy 11.607565 -295.601944)
			(xy 11.623365 -295.403701) (xy 11.647034 -295.206243) (xy 11.678535 -295.009883) (xy 11.717818 -294.814929)
			(xy 11.76482 -294.621692) (xy 11.819467 -294.430476) (xy 11.881674 -294.241584) (xy 11.95134 -294.055315)
			(xy 12.028358 -293.871962) (xy 12.112603 -293.691816) (xy 12.203944 -293.515162) (xy 12.302236 -293.342279)
			(xy 12.407324 -293.173441) (xy 12.519041 -293.008913) (xy 12.637211 -292.848958) (xy 12.761646 -292.693827)
			(xy 12.892151 -292.543765) (xy 13.028518 -292.399011) (xy 13.170532 -292.259793) (xy 13.317969 -292.12633)
			(xy 13.470596 -291.998835) (xy 13.62817 -291.877509) (xy 13.790444 -291.762543) (xy 13.957159 -291.654119)
			(xy 14.128054 -291.552409) (xy 14.302857 -291.457574) (xy 14.481292 -291.369763) (xy 14.663077 -291.289115)
			(xy 14.847925 -291.215759) (xy 15.035543 -291.149809) (xy 15.225635 -291.091371) (xy 15.417899 -291.040536)
			(xy 15.612033 -290.997385) (xy 15.807728 -290.961987) (xy 16.004677 -290.934396) (xy 16.202566 -290.914657)
			(xy 16.401084 -290.902801) (xy 16.599916 -290.898848) (xy 16.798748 -290.902801) (xy 16.997266 -290.914657)
			(xy 17.195155 -290.934396) (xy 17.392104 -290.961987) (xy 17.587799 -290.997385) (xy 17.781933 -291.040536)
			(xy 17.974197 -291.091371) (xy 18.164289 -291.149809) (xy 18.351907 -291.215759) (xy 18.536755 -291.289115)
			(xy 18.71854 -291.369763) (xy 18.896975 -291.457574) (xy 19.071778 -291.552409) (xy 19.242673 -291.654119)
			(xy 19.409388 -291.762543) (xy 19.571662 -291.877509) (xy 19.729236 -291.998835) (xy 19.881863 -292.12633)
			(xy 20.0293 -292.259793) (xy 20.171314 -292.399011) (xy 20.307681 -292.543765) (xy 20.438186 -292.693827)
			(xy 20.562621 -292.848958) (xy 20.680791 -293.008913) (xy 20.792508 -293.173441) (xy 20.897596 -293.342279)
			(xy 20.995888 -293.515162) (xy 21.087229 -293.691816) (xy 21.171474 -293.871962) (xy 21.248492 -294.055315)
			(xy 21.318158 -294.241584) (xy 21.380365 -294.430476) (xy 21.435012 -294.621692) (xy 21.482014 -294.814929)
			(xy 21.521297 -295.009883) (xy 21.552798 -295.206243) (xy 21.576467 -295.403701) (xy 21.592267 -295.601944)
			(xy 21.600174 -295.800658) (xy 21.600668 -295.900094) (xy 21.600174 -295.99953) (xy 21.592267 -296.198244)
			(xy 21.576467 -296.396487) (xy 21.552798 -296.593945) (xy 21.521297 -296.790305) (xy 21.482014 -296.985259)
			(xy 21.435012 -297.178496) (xy 21.380365 -297.369712) (xy 21.318158 -297.558604) (xy 21.248492 -297.744873)
			(xy 21.171474 -297.928226) (xy 21.087229 -298.108372) (xy 20.995888 -298.285026) (xy 20.897596 -298.457909)
			(xy 20.792508 -298.626747) (xy 20.680791 -298.791275) (xy 20.562621 -298.95123) (xy 20.438186 -299.106361)
			(xy 20.307681 -299.256423) (xy 20.171314 -299.401177) (xy 20.0293 -299.540395) (xy 19.881863 -299.673858)
			(xy 19.729236 -299.801353) (xy 19.571662 -299.922679) (xy 19.409388 -300.037645) (xy 19.242673 -300.146069)
			(xy 19.071778 -300.247779) (xy 18.896975 -300.342614) (xy 18.71854 -300.430425) (xy 18.536755 -300.511073)
			(xy 18.351907 -300.584429) (xy 18.164289 -300.650379) (xy 17.974197 -300.708817) (xy 17.781933 -300.759652)
			(xy 17.587799 -300.802803) (xy 17.392104 -300.838201) (xy 17.195155 -300.865792) (xy 16.997266 -300.885531)
			(xy 16.798748 -300.897387) (xy 16.599916 -300.901341) (xy 16.401084 -300.897387) (xy 16.202566 -300.885531)
			(xy 16.004677 -300.865792) (xy 15.807728 -300.838201) (xy 15.612033 -300.802803) (xy 15.417899 -300.759652)
			(xy 15.225635 -300.708817) (xy 15.035543 -300.650379) (xy 14.847925 -300.584429) (xy 14.663077 -300.511073)
			(xy 14.481292 -300.430425) (xy 14.302857 -300.342614) (xy 14.128054 -300.247779) (xy 13.957159 -300.146069)
			(xy 13.790444 -300.037645) (xy 13.62817 -299.922679) (xy 13.470596 -299.801353) (xy 13.317969 -299.673858)
			(xy 13.170532 -299.540395) (xy 13.028518 -299.401177) (xy 12.892151 -299.256423) (xy 12.761646 -299.106361)
			(xy 12.637211 -298.95123) (xy 12.519041 -298.791275) (xy 12.407324 -298.626747) (xy 12.302236 -298.457909)
			(xy 12.203944 -298.285026) (xy 12.112603 -298.108372) (xy 12.028358 -297.928226) (xy 11.95134 -297.744873)
			(xy 11.881674 -297.558604) (xy 11.819467 -297.369712) (xy 11.76482 -297.178496) (xy 11.717818 -296.985259)
			(xy 11.678535 -296.790305) (xy 11.647034 -296.593945) (xy 11.623365 -296.396487) (xy 11.607565 -296.198244)
			(xy 11.599658 -295.99953) (xy 11.599164 -295.900094) (xy 9.042055 -295.900094) (xy 9.037413 -295.91336)
			(xy 9.006468 -295.977619) (xy 8.968522 -296.03801) (xy 8.924053 -296.093772) (xy 8.87362 -296.144205)
			(xy 8.817858 -296.188674) (xy 8.757467 -296.22662) (xy 8.693208 -296.257565) (xy 8.625888 -296.281122)
			(xy 8.556353 -296.296992) (xy 8.485479 -296.304978) (xy 8.414157 -296.304978) (xy 8.343283 -296.296992)
			(xy 8.273748 -296.281122) (xy 8.206428 -296.257565) (xy 8.142169 -296.22662) (xy 8.081778 -296.188674)
			(xy 8.026016 -296.144205) (xy 7.975583 -296.093772) (xy 7.931114 -296.03801) (xy 7.893168 -295.977619)
			(xy 7.862223 -295.91336) (xy 7.838666 -295.84604) (xy 7.822796 -295.776505) (xy 7.81481 -295.705631)
			(xy 2.584966 -295.705631) (xy 2.57698 -295.776505) (xy 2.56111 -295.84604) (xy 2.537553 -295.91336)
			(xy 2.506608 -295.977619) (xy 2.468662 -296.03801) (xy 2.424193 -296.093772) (xy 2.37376 -296.144205)
			(xy 2.317998 -296.188674) (xy 2.257607 -296.22662) (xy 2.193348 -296.257565) (xy 2.126028 -296.281122)
			(xy 2.056493 -296.296992) (xy 1.985619 -296.304978) (xy 1.914297 -296.304978) (xy 1.843423 -296.296992)
			(xy 1.773888 -296.281122) (xy 1.706568 -296.257565) (xy 1.642309 -296.22662) (xy 1.581918 -296.188674)
			(xy 1.526156 -296.144205) (xy 1.475723 -296.093772) (xy 1.431254 -296.03801) (xy 1.393308 -295.977619)
			(xy 1.362363 -295.91336) (xy 1.338806 -295.84604) (xy 1.322936 -295.776505) (xy 1.31495 -295.705631)
			(xy 0.509016 -295.705631) (xy 0.509016 -296.705629) (xy 5.814814 -296.705629) (xy 5.814814 -296.634307)
			(xy 5.8228 -296.563433) (xy 5.83867 -296.493898) (xy 5.862227 -296.426578) (xy 5.893172 -296.362319)
			(xy 5.931118 -296.301928) (xy 5.975587 -296.246166) (xy 6.02602 -296.195733) (xy 6.081782 -296.151264)
			(xy 6.142173 -296.113318) (xy 6.206432 -296.082373) (xy 6.273752 -296.058816) (xy 6.343287 -296.042946)
			(xy 6.414161 -296.03496) (xy 6.449822 -296.03446) (xy 6.485483 -296.03496) (xy 6.556357 -296.042946)
			(xy 6.625892 -296.058816) (xy 6.693212 -296.082373) (xy 6.757471 -296.113318) (xy 6.817862 -296.151264)
			(xy 6.873624 -296.195733) (xy 6.924057 -296.246166) (xy 6.968526 -296.301928) (xy 7.006472 -296.362319)
			(xy 7.037417 -296.426578) (xy 7.060974 -296.493898) (xy 7.076844 -296.563433) (xy 7.08483 -296.634307)
			(xy 7.08483 -296.705629) (xy 7.076844 -296.776503) (xy 7.060974 -296.846038) (xy 7.037417 -296.913358)
			(xy 7.006472 -296.977617) (xy 6.968526 -297.038008) (xy 6.924057 -297.09377) (xy 6.873624 -297.144203)
			(xy 6.817862 -297.188672) (xy 6.757471 -297.226618) (xy 6.693212 -297.257563) (xy 6.625892 -297.28112)
			(xy 6.556357 -297.29699) (xy 6.485483 -297.304976) (xy 6.414161 -297.304976) (xy 6.343287 -297.29699)
			(xy 6.273752 -297.28112) (xy 6.206432 -297.257563) (xy 6.142173 -297.226618) (xy 6.081782 -297.188672)
			(xy 6.02602 -297.144203) (xy 5.975587 -297.09377) (xy 5.931118 -297.038008) (xy 5.893172 -296.977617)
			(xy 5.862227 -296.913358) (xy 5.83867 -296.846038) (xy 5.8228 -296.776503) (xy 5.814814 -296.705629)
			(xy 0.509016 -296.705629) (xy 0.509016 -297.705627) (xy 1.31495 -297.705627) (xy 1.31495 -297.634305)
			(xy 1.322936 -297.563431) (xy 1.338806 -297.493896) (xy 1.362363 -297.426576) (xy 1.393308 -297.362317)
			(xy 1.431254 -297.301926) (xy 1.475723 -297.246164) (xy 1.526156 -297.195731) (xy 1.581918 -297.151262)
			(xy 1.642309 -297.113316) (xy 1.706568 -297.082371) (xy 1.773888 -297.058814) (xy 1.843423 -297.042944)
			(xy 1.914297 -297.034958) (xy 1.949958 -297.034458) (xy 1.985619 -297.034958) (xy 2.056493 -297.042944)
			(xy 2.126028 -297.058814) (xy 2.193348 -297.082371) (xy 2.257607 -297.113316) (xy 2.317998 -297.151262)
			(xy 2.37376 -297.195731) (xy 2.424193 -297.246164) (xy 2.468662 -297.301926) (xy 2.506608 -297.362317)
			(xy 2.537553 -297.426576) (xy 2.56111 -297.493896) (xy 2.57698 -297.563431) (xy 2.584966 -297.634305)
			(xy 2.584966 -297.705627) (xy 2.57698 -297.776501) (xy 2.56111 -297.846036) (xy 2.537553 -297.913356)
			(xy 2.506608 -297.977615) (xy 2.468662 -298.038006) (xy 2.424193 -298.093768) (xy 2.37376 -298.144201)
			(xy 2.317998 -298.18867) (xy 2.257607 -298.226616) (xy 2.193348 -298.257561) (xy 2.126028 -298.281118)
			(xy 2.056493 -298.296988) (xy 1.985619 -298.304974) (xy 1.914297 -298.304974) (xy 1.843423 -298.296988)
			(xy 1.773888 -298.281118) (xy 1.706568 -298.257561) (xy 1.642309 -298.226616) (xy 1.581918 -298.18867)
			(xy 1.526156 -298.144201) (xy 1.475723 -298.093768) (xy 1.431254 -298.038006) (xy 1.393308 -297.977615)
			(xy 1.362363 -297.913356) (xy 1.338806 -297.846036) (xy 1.322936 -297.776501) (xy 1.31495 -297.705627)
			(xy 0.509016 -297.705627) (xy 0.509016 -298.705625) (xy 3.314946 -298.705625) (xy 3.314946 -298.634303)
			(xy 3.322932 -298.563429) (xy 3.338802 -298.493894) (xy 3.362359 -298.426574) (xy 3.393304 -298.362315)
			(xy 3.43125 -298.301924) (xy 3.475719 -298.246162) (xy 3.526152 -298.195729) (xy 3.581914 -298.15126)
			(xy 3.642305 -298.113314) (xy 3.706564 -298.082369) (xy 3.773884 -298.058812) (xy 3.843419 -298.042942)
			(xy 3.914293 -298.034956) (xy 3.949954 -298.034456) (xy 3.985615 -298.034956) (xy 4.056489 -298.042942)
			(xy 4.126024 -298.058812) (xy 4.193344 -298.082369) (xy 4.257603 -298.113314) (xy 4.317994 -298.15126)
			(xy 4.373756 -298.195729) (xy 4.424189 -298.246162) (xy 4.468658 -298.301924) (xy 4.506604 -298.362315)
			(xy 4.537549 -298.426574) (xy 4.561106 -298.493894) (xy 4.576976 -298.563429) (xy 4.584962 -298.634303)
			(xy 4.584962 -298.705625) (xy 5.814814 -298.705625) (xy 5.814814 -298.634303) (xy 5.8228 -298.563429)
			(xy 5.83867 -298.493894) (xy 5.862227 -298.426574) (xy 5.893172 -298.362315) (xy 5.931118 -298.301924)
			(xy 5.975587 -298.246162) (xy 6.02602 -298.195729) (xy 6.081782 -298.15126) (xy 6.142173 -298.113314)
			(xy 6.206432 -298.082369) (xy 6.273752 -298.058812) (xy 6.343287 -298.042942) (xy 6.414161 -298.034956)
			(xy 6.449822 -298.034456) (xy 6.485483 -298.034956) (xy 6.556357 -298.042942) (xy 6.625892 -298.058812)
			(xy 6.693212 -298.082369) (xy 6.757471 -298.113314) (xy 6.817862 -298.15126) (xy 6.873624 -298.195729)
			(xy 6.924057 -298.246162) (xy 6.968526 -298.301924) (xy 7.006472 -298.362315) (xy 7.037417 -298.426574)
			(xy 7.060974 -298.493894) (xy 7.076844 -298.563429) (xy 7.08483 -298.634303) (xy 7.08483 -298.705625)
			(xy 7.076844 -298.776499) (xy 7.060974 -298.846034) (xy 7.037417 -298.913354) (xy 7.006472 -298.977613)
			(xy 6.968526 -299.038004) (xy 6.924057 -299.093766) (xy 6.873624 -299.144199) (xy 6.817862 -299.188668)
			(xy 6.757471 -299.226614) (xy 6.693212 -299.257559) (xy 6.625892 -299.281116) (xy 6.556357 -299.296986)
			(xy 6.485483 -299.304972) (xy 6.414161 -299.304972) (xy 6.343287 -299.296986) (xy 6.273752 -299.281116)
			(xy 6.206432 -299.257559) (xy 6.142173 -299.226614) (xy 6.081782 -299.188668) (xy 6.02602 -299.144199)
			(xy 5.975587 -299.093766) (xy 5.931118 -299.038004) (xy 5.893172 -298.977613) (xy 5.862227 -298.913354)
			(xy 5.83867 -298.846034) (xy 5.8228 -298.776499) (xy 5.814814 -298.705625) (xy 4.584962 -298.705625)
			(xy 4.576976 -298.776499) (xy 4.561106 -298.846034) (xy 4.537549 -298.913354) (xy 4.506604 -298.977613)
			(xy 4.468658 -299.038004) (xy 4.424189 -299.093766) (xy 4.373756 -299.144199) (xy 4.317994 -299.188668)
			(xy 4.257603 -299.226614) (xy 4.193344 -299.257559) (xy 4.126024 -299.281116) (xy 4.056489 -299.296986)
			(xy 3.985615 -299.304972) (xy 3.914293 -299.304972) (xy 3.843419 -299.296986) (xy 3.773884 -299.281116)
			(xy 3.706564 -299.257559) (xy 3.642305 -299.226614) (xy 3.581914 -299.188668) (xy 3.526152 -299.144199)
			(xy 3.475719 -299.093766) (xy 3.43125 -299.038004) (xy 3.393304 -298.977613) (xy 3.362359 -298.913354)
			(xy 3.338802 -298.846034) (xy 3.322932 -298.776499) (xy 3.314946 -298.705625) (xy 0.509016 -298.705625)
			(xy 0.509016 -299.705623) (xy 1.31495 -299.705623) (xy 1.31495 -299.634301) (xy 1.322936 -299.563427)
			(xy 1.338806 -299.493892) (xy 1.362363 -299.426572) (xy 1.393308 -299.362313) (xy 1.431254 -299.301922)
			(xy 1.475723 -299.24616) (xy 1.526156 -299.195727) (xy 1.581918 -299.151258) (xy 1.642309 -299.113312)
			(xy 1.706568 -299.082367) (xy 1.773888 -299.05881) (xy 1.843423 -299.04294) (xy 1.914297 -299.034954)
			(xy 1.949958 -299.034454) (xy 1.985619 -299.034954) (xy 2.056493 -299.04294) (xy 2.126028 -299.05881)
			(xy 2.193348 -299.082367) (xy 2.257607 -299.113312) (xy 2.317998 -299.151258) (xy 2.37376 -299.195727)
			(xy 2.424193 -299.24616) (xy 2.468662 -299.301922) (xy 2.506608 -299.362313) (xy 2.537553 -299.426572)
			(xy 2.56111 -299.493892) (xy 2.57698 -299.563427) (xy 2.584966 -299.634301) (xy 2.584966 -299.705623)
			(xy 7.81481 -299.705623) (xy 7.81481 -299.634301) (xy 7.822796 -299.563427) (xy 7.838666 -299.493892)
			(xy 7.862223 -299.426572) (xy 7.893168 -299.362313) (xy 7.931114 -299.301922) (xy 7.975583 -299.24616)
			(xy 8.026016 -299.195727) (xy 8.081778 -299.151258) (xy 8.142169 -299.113312) (xy 8.206428 -299.082367)
			(xy 8.273748 -299.05881) (xy 8.343283 -299.04294) (xy 8.414157 -299.034954) (xy 8.449818 -299.034454)
			(xy 8.485479 -299.034954) (xy 8.556353 -299.04294) (xy 8.625888 -299.05881) (xy 8.693208 -299.082367)
			(xy 8.757467 -299.113312) (xy 8.817858 -299.151258) (xy 8.87362 -299.195727) (xy 8.924053 -299.24616)
			(xy 8.968522 -299.301922) (xy 9.006468 -299.362313) (xy 9.037413 -299.426572) (xy 9.06097 -299.493892)
			(xy 9.07684 -299.563427) (xy 9.084826 -299.634301) (xy 9.084826 -299.705623) (xy 9.07684 -299.776497)
			(xy 9.06097 -299.846032) (xy 9.037413 -299.913352) (xy 9.006468 -299.977611) (xy 8.968522 -300.038002)
			(xy 8.924053 -300.093764) (xy 8.87362 -300.144197) (xy 8.817858 -300.188666) (xy 8.757467 -300.226612)
			(xy 8.693208 -300.257557) (xy 8.625888 -300.281114) (xy 8.556353 -300.296984) (xy 8.485479 -300.30497)
			(xy 8.414157 -300.30497) (xy 8.343283 -300.296984) (xy 8.273748 -300.281114) (xy 8.206428 -300.257557)
			(xy 8.142169 -300.226612) (xy 8.081778 -300.188666) (xy 8.026016 -300.144197) (xy 7.975583 -300.093764)
			(xy 7.931114 -300.038002) (xy 7.893168 -299.977611) (xy 7.862223 -299.913352) (xy 7.838666 -299.846032)
			(xy 7.822796 -299.776497) (xy 7.81481 -299.705623) (xy 2.584966 -299.705623) (xy 2.57698 -299.776497)
			(xy 2.56111 -299.846032) (xy 2.537553 -299.913352) (xy 2.506608 -299.977611) (xy 2.468662 -300.038002)
			(xy 2.424193 -300.093764) (xy 2.37376 -300.144197) (xy 2.317998 -300.188666) (xy 2.257607 -300.226612)
			(xy 2.193348 -300.257557) (xy 2.126028 -300.281114) (xy 2.056493 -300.296984) (xy 1.985619 -300.30497)
			(xy 1.914297 -300.30497) (xy 1.843423 -300.296984) (xy 1.773888 -300.281114) (xy 1.706568 -300.257557)
			(xy 1.642309 -300.226612) (xy 1.581918 -300.188666) (xy 1.526156 -300.144197) (xy 1.475723 -300.093764)
			(xy 1.431254 -300.038002) (xy 1.393308 -299.977611) (xy 1.362363 -299.913352) (xy 1.338806 -299.846032)
			(xy 1.322936 -299.776497) (xy 1.31495 -299.705623) (xy 0.509016 -299.705623) (xy 0.509016 -300.705621)
			(xy 3.314946 -300.705621) (xy 3.314946 -300.634299) (xy 3.322932 -300.563425) (xy 3.338802 -300.49389)
			(xy 3.362359 -300.42657) (xy 3.393304 -300.362311) (xy 3.43125 -300.30192) (xy 3.475719 -300.246158)
			(xy 3.526152 -300.195725) (xy 3.581914 -300.151256) (xy 3.642305 -300.11331) (xy 3.706564 -300.082365)
			(xy 3.773884 -300.058808) (xy 3.843419 -300.042938) (xy 3.914293 -300.034952) (xy 3.949954 -300.034452)
			(xy 3.985615 -300.034952) (xy 4.056489 -300.042938) (xy 4.126024 -300.058808) (xy 4.193344 -300.082365)
			(xy 4.257603 -300.11331) (xy 4.317994 -300.151256) (xy 4.373756 -300.195725) (xy 4.424189 -300.246158)
			(xy 4.468658 -300.30192) (xy 4.506604 -300.362311) (xy 4.537549 -300.42657) (xy 4.561106 -300.49389)
			(xy 4.576976 -300.563425) (xy 4.584962 -300.634299) (xy 4.584962 -300.705621) (xy 5.814814 -300.705621)
			(xy 5.814814 -300.634299) (xy 5.8228 -300.563425) (xy 5.83867 -300.49389) (xy 5.862227 -300.42657)
			(xy 5.893172 -300.362311) (xy 5.931118 -300.30192) (xy 5.975587 -300.246158) (xy 6.02602 -300.195725)
			(xy 6.081782 -300.151256) (xy 6.142173 -300.11331) (xy 6.206432 -300.082365) (xy 6.273752 -300.058808)
			(xy 6.343287 -300.042938) (xy 6.414161 -300.034952) (xy 6.449822 -300.034452) (xy 6.485483 -300.034952)
			(xy 6.556357 -300.042938) (xy 6.625892 -300.058808) (xy 6.693212 -300.082365) (xy 6.757471 -300.11331)
			(xy 6.817862 -300.151256) (xy 6.873624 -300.195725) (xy 6.924057 -300.246158) (xy 6.968526 -300.30192)
			(xy 7.006472 -300.362311) (xy 7.037417 -300.42657) (xy 7.060974 -300.49389) (xy 7.076844 -300.563425)
			(xy 7.08483 -300.634299) (xy 7.08483 -300.705621) (xy 7.076844 -300.776495) (xy 7.060974 -300.84603)
			(xy 7.037417 -300.91335) (xy 7.006472 -300.977609) (xy 6.968526 -301.038) (xy 6.924057 -301.093762)
			(xy 6.873624 -301.144195) (xy 6.817862 -301.188664) (xy 6.757471 -301.22661) (xy 6.693212 -301.257555)
			(xy 6.625892 -301.281112) (xy 6.556357 -301.296982) (xy 6.485483 -301.304968) (xy 6.414161 -301.304968)
			(xy 6.343287 -301.296982) (xy 6.273752 -301.281112) (xy 6.206432 -301.257555) (xy 6.142173 -301.22661)
			(xy 6.081782 -301.188664) (xy 6.02602 -301.144195) (xy 5.975587 -301.093762) (xy 5.931118 -301.038)
			(xy 5.893172 -300.977609) (xy 5.862227 -300.91335) (xy 5.83867 -300.84603) (xy 5.8228 -300.776495)
			(xy 5.814814 -300.705621) (xy 4.584962 -300.705621) (xy 4.576976 -300.776495) (xy 4.561106 -300.84603)
			(xy 4.537549 -300.91335) (xy 4.506604 -300.977609) (xy 4.468658 -301.038) (xy 4.424189 -301.093762)
			(xy 4.373756 -301.144195) (xy 4.317994 -301.188664) (xy 4.257603 -301.22661) (xy 4.193344 -301.257555)
			(xy 4.126024 -301.281112) (xy 4.056489 -301.296982) (xy 3.985615 -301.304968) (xy 3.914293 -301.304968)
			(xy 3.843419 -301.296982) (xy 3.773884 -301.281112) (xy 3.706564 -301.257555) (xy 3.642305 -301.22661)
			(xy 3.581914 -301.188664) (xy 3.526152 -301.144195) (xy 3.475719 -301.093762) (xy 3.43125 -301.038)
			(xy 3.393304 -300.977609) (xy 3.362359 -300.91335) (xy 3.338802 -300.84603) (xy 3.322932 -300.776495)
			(xy 3.314946 -300.705621) (xy 0.509016 -300.705621) (xy 0.509016 -301.705619) (xy 7.81481 -301.705619)
			(xy 7.81481 -301.634297) (xy 7.822796 -301.563423) (xy 7.838666 -301.493888) (xy 7.862223 -301.426568)
			(xy 7.893168 -301.362309) (xy 7.931114 -301.301918) (xy 7.975583 -301.246156) (xy 8.026016 -301.195723)
			(xy 8.081778 -301.151254) (xy 8.142169 -301.113308) (xy 8.206428 -301.082363) (xy 8.273748 -301.058806)
			(xy 8.343283 -301.042936) (xy 8.414157 -301.03495) (xy 8.449818 -301.03445) (xy 8.485479 -301.03495)
			(xy 8.556353 -301.042936) (xy 8.625888 -301.058806) (xy 8.693208 -301.082363) (xy 8.757467 -301.113308)
			(xy 8.817858 -301.151254) (xy 8.87362 -301.195723) (xy 8.924053 -301.246156) (xy 8.968522 -301.301918)
			(xy 9.006468 -301.362309) (xy 9.037413 -301.426568) (xy 9.06097 -301.493888) (xy 9.07684 -301.563423)
			(xy 9.084826 -301.634297) (xy 9.084826 -301.705619) (xy 9.07684 -301.776493) (xy 9.06097 -301.846028)
			(xy 9.037413 -301.913348) (xy 9.006468 -301.977607) (xy 8.968522 -302.037998) (xy 8.924053 -302.09376)
			(xy 8.87362 -302.144193) (xy 8.817858 -302.188662) (xy 8.757467 -302.226608) (xy 8.693208 -302.257553)
			(xy 8.625888 -302.28111) (xy 8.556353 -302.29698) (xy 8.485479 -302.304966) (xy 8.414157 -302.304966)
			(xy 8.343283 -302.29698) (xy 8.273748 -302.28111) (xy 8.206428 -302.257553) (xy 8.142169 -302.226608)
			(xy 8.081778 -302.188662) (xy 8.026016 -302.144193) (xy 7.975583 -302.09376) (xy 7.931114 -302.037998)
			(xy 7.893168 -301.977607) (xy 7.862223 -301.913348) (xy 7.838666 -301.846028) (xy 7.822796 -301.776493)
			(xy 7.81481 -301.705619) (xy 0.509016 -301.705619) (xy 0.509016 -302.705617) (xy 3.314946 -302.705617)
			(xy 3.314946 -302.634295) (xy 3.322932 -302.563421) (xy 3.338802 -302.493886) (xy 3.362359 -302.426566)
			(xy 3.393304 -302.362307) (xy 3.43125 -302.301916) (xy 3.475719 -302.246154) (xy 3.526152 -302.195721)
			(xy 3.581914 -302.151252) (xy 3.642305 -302.113306) (xy 3.706564 -302.082361) (xy 3.773884 -302.058804)
			(xy 3.843419 -302.042934) (xy 3.914293 -302.034948) (xy 3.949954 -302.034448) (xy 3.985615 -302.034948)
			(xy 4.056489 -302.042934) (xy 4.126024 -302.058804) (xy 4.193344 -302.082361) (xy 4.257603 -302.113306)
			(xy 4.317994 -302.151252) (xy 4.373756 -302.195721) (xy 4.424189 -302.246154) (xy 4.468658 -302.301916)
			(xy 4.506604 -302.362307) (xy 4.537549 -302.426566) (xy 4.561106 -302.493886) (xy 4.576976 -302.563421)
			(xy 4.584962 -302.634295) (xy 4.584962 -302.705617) (xy 4.576976 -302.776491) (xy 4.561106 -302.846026)
			(xy 4.537549 -302.913346) (xy 4.506604 -302.977605) (xy 4.468658 -303.037996) (xy 4.424189 -303.093758)
			(xy 4.373756 -303.144191) (xy 4.317994 -303.18866) (xy 4.257603 -303.226606) (xy 4.193344 -303.257551)
			(xy 4.126024 -303.281108) (xy 4.056489 -303.296978) (xy 3.985615 -303.304964) (xy 3.914293 -303.304964)
			(xy 3.843419 -303.296978) (xy 3.773884 -303.281108) (xy 3.706564 -303.257551) (xy 3.642305 -303.226606)
			(xy 3.581914 -303.18866) (xy 3.526152 -303.144191) (xy 3.475719 -303.093758) (xy 3.43125 -303.037996)
			(xy 3.393304 -302.977605) (xy 3.362359 -302.913346) (xy 3.338802 -302.846026) (xy 3.322932 -302.776491)
			(xy 3.314946 -302.705617) (xy 0.509016 -302.705617) (xy 0.509016 -303.705615) (xy 1.31495 -303.705615)
			(xy 1.31495 -303.634293) (xy 1.322936 -303.563419) (xy 1.338806 -303.493884) (xy 1.362363 -303.426564)
			(xy 1.393308 -303.362305) (xy 1.431254 -303.301914) (xy 1.475723 -303.246152) (xy 1.526156 -303.195719)
			(xy 1.581918 -303.15125) (xy 1.642309 -303.113304) (xy 1.706568 -303.082359) (xy 1.773888 -303.058802)
			(xy 1.843423 -303.042932) (xy 1.914297 -303.034946) (xy 1.949958 -303.034446) (xy 1.985619 -303.034946)
			(xy 2.056493 -303.042932) (xy 2.126028 -303.058802) (xy 2.193348 -303.082359) (xy 2.257607 -303.113304)
			(xy 2.317998 -303.15125) (xy 2.37376 -303.195719) (xy 2.424193 -303.246152) (xy 2.468662 -303.301914)
			(xy 2.506608 -303.362305) (xy 2.537553 -303.426564) (xy 2.56111 -303.493884) (xy 2.57698 -303.563419)
			(xy 2.584966 -303.634293) (xy 2.584966 -303.705615) (xy 7.81481 -303.705615) (xy 7.81481 -303.634293)
			(xy 7.822796 -303.563419) (xy 7.838666 -303.493884) (xy 7.862223 -303.426564) (xy 7.893168 -303.362305)
			(xy 7.931114 -303.301914) (xy 7.975583 -303.246152) (xy 8.026016 -303.195719) (xy 8.081778 -303.15125)
			(xy 8.142169 -303.113304) (xy 8.206428 -303.082359) (xy 8.273748 -303.058802) (xy 8.343283 -303.042932)
			(xy 8.414157 -303.034946) (xy 8.449818 -303.034446) (xy 8.485479 -303.034946) (xy 8.556353 -303.042932)
			(xy 8.625888 -303.058802) (xy 8.693208 -303.082359) (xy 8.757467 -303.113304) (xy 8.817858 -303.15125)
			(xy 8.87362 -303.195719) (xy 8.924053 -303.246152) (xy 8.968522 -303.301914) (xy 9.006468 -303.362305)
			(xy 9.037413 -303.426564) (xy 9.06097 -303.493884) (xy 9.07684 -303.563419) (xy 9.084826 -303.634293)
			(xy 9.084826 -303.705615) (xy 9.07684 -303.776489) (xy 9.06097 -303.846024) (xy 9.037413 -303.913344)
			(xy 9.006468 -303.977603) (xy 8.968522 -304.037994) (xy 8.924053 -304.093756) (xy 8.87362 -304.144189)
			(xy 8.817858 -304.188658) (xy 8.757467 -304.226604) (xy 8.693208 -304.257549) (xy 8.625888 -304.281106)
			(xy 8.556353 -304.296976) (xy 8.485479 -304.304962) (xy 8.414157 -304.304962) (xy 8.343283 -304.296976)
			(xy 8.273748 -304.281106) (xy 8.206428 -304.257549) (xy 8.142169 -304.226604) (xy 8.081778 -304.188658)
			(xy 8.026016 -304.144189) (xy 7.975583 -304.093756) (xy 7.931114 -304.037994) (xy 7.893168 -303.977603)
			(xy 7.862223 -303.913344) (xy 7.838666 -303.846024) (xy 7.822796 -303.776489) (xy 7.81481 -303.705615)
			(xy 2.584966 -303.705615) (xy 2.57698 -303.776489) (xy 2.56111 -303.846024) (xy 2.537553 -303.913344)
			(xy 2.506608 -303.977603) (xy 2.468662 -304.037994) (xy 2.424193 -304.093756) (xy 2.37376 -304.144189)
			(xy 2.317998 -304.188658) (xy 2.257607 -304.226604) (xy 2.193348 -304.257549) (xy 2.126028 -304.281106)
			(xy 2.056493 -304.296976) (xy 1.985619 -304.304962) (xy 1.914297 -304.304962) (xy 1.843423 -304.296976)
			(xy 1.773888 -304.281106) (xy 1.706568 -304.257549) (xy 1.642309 -304.226604) (xy 1.581918 -304.188658)
			(xy 1.526156 -304.144189) (xy 1.475723 -304.093756) (xy 1.431254 -304.037994) (xy 1.393308 -303.977603)
			(xy 1.362363 -303.913344) (xy 1.338806 -303.846024) (xy 1.322936 -303.776489) (xy 1.31495 -303.705615)
			(xy 0.509016 -303.705615) (xy 0.509016 -304.705613) (xy 3.314946 -304.705613) (xy 3.314946 -304.634291)
			(xy 3.322932 -304.563417) (xy 3.338802 -304.493882) (xy 3.362359 -304.426562) (xy 3.393304 -304.362303)
			(xy 3.43125 -304.301912) (xy 3.475719 -304.24615) (xy 3.526152 -304.195717) (xy 3.581914 -304.151248)
			(xy 3.642305 -304.113302) (xy 3.706564 -304.082357) (xy 3.773884 -304.0588) (xy 3.843419 -304.04293)
			(xy 3.914293 -304.034944) (xy 3.949954 -304.034444) (xy 3.985615 -304.034944) (xy 4.056489 -304.04293)
			(xy 4.126024 -304.0588) (xy 4.193344 -304.082357) (xy 4.257603 -304.113302) (xy 4.317994 -304.151248)
			(xy 4.373756 -304.195717) (xy 4.424189 -304.24615) (xy 4.468658 -304.301912) (xy 4.506604 -304.362303)
			(xy 4.537549 -304.426562) (xy 4.561106 -304.493882) (xy 4.576976 -304.563417) (xy 4.584962 -304.634291)
			(xy 4.584962 -304.705613) (xy 5.814814 -304.705613) (xy 5.814814 -304.634291) (xy 5.8228 -304.563417)
			(xy 5.83867 -304.493882) (xy 5.862227 -304.426562) (xy 5.893172 -304.362303) (xy 5.931118 -304.301912)
			(xy 5.975587 -304.24615) (xy 6.02602 -304.195717) (xy 6.081782 -304.151248) (xy 6.142173 -304.113302)
			(xy 6.206432 -304.082357) (xy 6.273752 -304.0588) (xy 6.343287 -304.04293) (xy 6.414161 -304.034944)
			(xy 6.449822 -304.034444) (xy 6.485483 -304.034944) (xy 6.556357 -304.04293) (xy 6.625892 -304.0588)
			(xy 6.693212 -304.082357) (xy 6.757471 -304.113302) (xy 6.817862 -304.151248) (xy 6.873624 -304.195717)
			(xy 6.924057 -304.24615) (xy 6.968526 -304.301912) (xy 7.006472 -304.362303) (xy 7.037417 -304.426562)
			(xy 7.060974 -304.493882) (xy 7.076844 -304.563417) (xy 7.08483 -304.634291) (xy 7.08483 -304.705613)
			(xy 7.076844 -304.776487) (xy 7.060974 -304.846022) (xy 7.037417 -304.913342) (xy 7.006472 -304.977601)
			(xy 6.968526 -305.037992) (xy 6.924057 -305.093754) (xy 6.873624 -305.144187) (xy 6.817862 -305.188656)
			(xy 6.757471 -305.226602) (xy 6.693212 -305.257547) (xy 6.625892 -305.281104) (xy 6.556357 -305.296974)
			(xy 6.485483 -305.30496) (xy 6.414161 -305.30496) (xy 6.343287 -305.296974) (xy 6.273752 -305.281104)
			(xy 6.206432 -305.257547) (xy 6.142173 -305.226602) (xy 6.081782 -305.188656) (xy 6.02602 -305.144187)
			(xy 5.975587 -305.093754) (xy 5.931118 -305.037992) (xy 5.893172 -304.977601) (xy 5.862227 -304.913342)
			(xy 5.83867 -304.846022) (xy 5.8228 -304.776487) (xy 5.814814 -304.705613) (xy 4.584962 -304.705613)
			(xy 4.576976 -304.776487) (xy 4.561106 -304.846022) (xy 4.537549 -304.913342) (xy 4.506604 -304.977601)
			(xy 4.468658 -305.037992) (xy 4.424189 -305.093754) (xy 4.373756 -305.144187) (xy 4.317994 -305.188656)
			(xy 4.257603 -305.226602) (xy 4.193344 -305.257547) (xy 4.126024 -305.281104) (xy 4.056489 -305.296974)
			(xy 3.985615 -305.30496) (xy 3.914293 -305.30496) (xy 3.843419 -305.296974) (xy 3.773884 -305.281104)
			(xy 3.706564 -305.257547) (xy 3.642305 -305.226602) (xy 3.581914 -305.188656) (xy 3.526152 -305.144187)
			(xy 3.475719 -305.093754) (xy 3.43125 -305.037992) (xy 3.393304 -304.977601) (xy 3.362359 -304.913342)
			(xy 3.338802 -304.846022) (xy 3.322932 -304.776487) (xy 3.314946 -304.705613) (xy 0.509016 -304.705613)
			(xy 0.509016 -305.705611) (xy 1.31495 -305.705611) (xy 1.31495 -305.634289) (xy 1.322936 -305.563415)
			(xy 1.338806 -305.49388) (xy 1.362363 -305.42656) (xy 1.393308 -305.362301) (xy 1.431254 -305.30191)
			(xy 1.475723 -305.246148) (xy 1.526156 -305.195715) (xy 1.581918 -305.151246) (xy 1.642309 -305.1133)
			(xy 1.706568 -305.082355) (xy 1.773888 -305.058798) (xy 1.843423 -305.042928) (xy 1.914297 -305.034942)
			(xy 1.949958 -305.034442) (xy 1.985619 -305.034942) (xy 2.056493 -305.042928) (xy 2.126028 -305.058798)
			(xy 2.193348 -305.082355) (xy 2.257607 -305.1133) (xy 2.317998 -305.151246) (xy 2.37376 -305.195715)
			(xy 2.424193 -305.246148) (xy 2.468662 -305.30191) (xy 2.506608 -305.362301) (xy 2.537553 -305.42656)
			(xy 2.56111 -305.49388) (xy 2.57698 -305.563415) (xy 2.584966 -305.634289) (xy 2.584966 -305.705611)
			(xy 7.81481 -305.705611) (xy 7.81481 -305.634289) (xy 7.822796 -305.563415) (xy 7.838666 -305.49388)
			(xy 7.862223 -305.42656) (xy 7.893168 -305.362301) (xy 7.931114 -305.30191) (xy 7.975583 -305.246148)
			(xy 8.026016 -305.195715) (xy 8.081778 -305.151246) (xy 8.142169 -305.1133) (xy 8.206428 -305.082355)
			(xy 8.273748 -305.058798) (xy 8.343283 -305.042928) (xy 8.414157 -305.034942) (xy 8.449818 -305.034442)
			(xy 8.485479 -305.034942) (xy 8.556353 -305.042928) (xy 8.625888 -305.058798) (xy 8.693208 -305.082355)
			(xy 8.757467 -305.1133) (xy 8.817858 -305.151246) (xy 8.87362 -305.195715) (xy 8.924053 -305.246148)
			(xy 8.968522 -305.30191) (xy 9.006468 -305.362301) (xy 9.037413 -305.42656) (xy 9.06097 -305.49388)
			(xy 9.07684 -305.563415) (xy 9.084826 -305.634289) (xy 9.084826 -305.705611) (xy 9.07684 -305.776485)
			(xy 9.06097 -305.84602) (xy 9.037413 -305.91334) (xy 9.006468 -305.977599) (xy 8.968522 -306.03799)
			(xy 8.924053 -306.093752) (xy 8.87362 -306.144185) (xy 8.817858 -306.188654) (xy 8.757467 -306.2266)
			(xy 8.693208 -306.257545) (xy 8.625888 -306.281102) (xy 8.556353 -306.296972) (xy 8.485479 -306.304958)
			(xy 8.414157 -306.304958) (xy 8.343283 -306.296972) (xy 8.273748 -306.281102) (xy 8.206428 -306.257545)
			(xy 8.142169 -306.2266) (xy 8.081778 -306.188654) (xy 8.026016 -306.144185) (xy 7.975583 -306.093752)
			(xy 7.931114 -306.03799) (xy 7.893168 -305.977599) (xy 7.862223 -305.91334) (xy 7.838666 -305.84602)
			(xy 7.822796 -305.776485) (xy 7.81481 -305.705611) (xy 2.584966 -305.705611) (xy 2.57698 -305.776485)
			(xy 2.56111 -305.84602) (xy 2.537553 -305.91334) (xy 2.506608 -305.977599) (xy 2.468662 -306.03799)
			(xy 2.424193 -306.093752) (xy 2.37376 -306.144185) (xy 2.317998 -306.188654) (xy 2.257607 -306.2266)
			(xy 2.193348 -306.257545) (xy 2.126028 -306.281102) (xy 2.056493 -306.296972) (xy 1.985619 -306.304958)
			(xy 1.914297 -306.304958) (xy 1.843423 -306.296972) (xy 1.773888 -306.281102) (xy 1.706568 -306.257545)
			(xy 1.642309 -306.2266) (xy 1.581918 -306.188654) (xy 1.526156 -306.144185) (xy 1.475723 -306.093752)
			(xy 1.431254 -306.03799) (xy 1.393308 -305.977599) (xy 1.362363 -305.91334) (xy 1.338806 -305.84602)
			(xy 1.322936 -305.776485) (xy 1.31495 -305.705611) (xy 0.509016 -305.705611) (xy 0.509016 -306.705609)
			(xy 5.814814 -306.705609) (xy 5.814814 -306.634287) (xy 5.8228 -306.563413) (xy 5.83867 -306.493878)
			(xy 5.862227 -306.426558) (xy 5.893172 -306.362299) (xy 5.931118 -306.301908) (xy 5.975587 -306.246146)
			(xy 6.02602 -306.195713) (xy 6.081782 -306.151244) (xy 6.142173 -306.113298) (xy 6.206432 -306.082353)
			(xy 6.273752 -306.058796) (xy 6.343287 -306.042926) (xy 6.414161 -306.03494) (xy 6.449822 -306.03444)
			(xy 6.485483 -306.03494) (xy 6.556357 -306.042926) (xy 6.625892 -306.058796) (xy 6.693212 -306.082353)
			(xy 6.757471 -306.113298) (xy 6.817862 -306.151244) (xy 6.873624 -306.195713) (xy 6.924057 -306.246146)
			(xy 6.968526 -306.301908) (xy 7.006472 -306.362299) (xy 7.037417 -306.426558) (xy 7.060974 -306.493878)
			(xy 7.076844 -306.563413) (xy 7.08483 -306.634287) (xy 7.08483 -306.705609) (xy 7.076844 -306.776483)
			(xy 7.060974 -306.846018) (xy 7.037417 -306.913338) (xy 7.006472 -306.977597) (xy 6.968526 -307.037988)
			(xy 6.924057 -307.09375) (xy 6.873624 -307.144183) (xy 6.817862 -307.188652) (xy 6.757471 -307.226598)
			(xy 6.693212 -307.257543) (xy 6.625892 -307.2811) (xy 6.556357 -307.29697) (xy 6.485483 -307.304956)
			(xy 6.414161 -307.304956) (xy 6.343287 -307.29697) (xy 6.273752 -307.2811) (xy 6.206432 -307.257543)
			(xy 6.142173 -307.226598) (xy 6.081782 -307.188652) (xy 6.02602 -307.144183) (xy 5.975587 -307.09375)
			(xy 5.931118 -307.037988) (xy 5.893172 -306.977597) (xy 5.862227 -306.913338) (xy 5.83867 -306.846018)
			(xy 5.8228 -306.776483) (xy 5.814814 -306.705609) (xy 0.509016 -306.705609) (xy 0.509016 -307.705607)
			(xy 1.31495 -307.705607) (xy 1.31495 -307.634285) (xy 1.322936 -307.563411) (xy 1.338806 -307.493876)
			(xy 1.362363 -307.426556) (xy 1.393308 -307.362297) (xy 1.431254 -307.301906) (xy 1.475723 -307.246144)
			(xy 1.526156 -307.195711) (xy 1.581918 -307.151242) (xy 1.642309 -307.113296) (xy 1.706568 -307.082351)
			(xy 1.773888 -307.058794) (xy 1.843423 -307.042924) (xy 1.914297 -307.034938) (xy 1.949958 -307.034438)
			(xy 1.985619 -307.034938) (xy 2.056493 -307.042924) (xy 2.126028 -307.058794) (xy 2.193348 -307.082351)
			(xy 2.257607 -307.113296) (xy 2.317998 -307.151242) (xy 2.37376 -307.195711) (xy 2.424193 -307.246144)
			(xy 2.468662 -307.301906) (xy 2.506608 -307.362297) (xy 2.537553 -307.426556) (xy 2.56111 -307.493876)
			(xy 2.57698 -307.563411) (xy 2.584966 -307.634285) (xy 2.584966 -307.705607) (xy 2.57698 -307.776481)
			(xy 2.56111 -307.846016) (xy 2.537553 -307.913336) (xy 2.506608 -307.977595) (xy 2.468662 -308.037986)
			(xy 2.424193 -308.093748) (xy 2.37376 -308.144181) (xy 2.317998 -308.18865) (xy 2.257607 -308.226596)
			(xy 2.193348 -308.257541) (xy 2.126028 -308.281098) (xy 2.056493 -308.296968) (xy 1.985619 -308.304954)
			(xy 1.914297 -308.304954) (xy 1.843423 -308.296968) (xy 1.773888 -308.281098) (xy 1.706568 -308.257541)
			(xy 1.642309 -308.226596) (xy 1.581918 -308.18865) (xy 1.526156 -308.144181) (xy 1.475723 -308.093748)
			(xy 1.431254 -308.037986) (xy 1.393308 -307.977595) (xy 1.362363 -307.913336) (xy 1.338806 -307.846016)
			(xy 1.322936 -307.776481) (xy 1.31495 -307.705607) (xy 0.509016 -307.705607) (xy 0.509016 -308.705605)
			(xy 3.314946 -308.705605) (xy 3.314946 -308.634283) (xy 3.322932 -308.563409) (xy 3.338802 -308.493874)
			(xy 3.362359 -308.426554) (xy 3.393304 -308.362295) (xy 3.43125 -308.301904) (xy 3.475719 -308.246142)
			(xy 3.526152 -308.195709) (xy 3.581914 -308.15124) (xy 3.642305 -308.113294) (xy 3.706564 -308.082349)
			(xy 3.773884 -308.058792) (xy 3.843419 -308.042922) (xy 3.914293 -308.034936) (xy 3.949954 -308.034436)
			(xy 3.985615 -308.034936) (xy 4.056489 -308.042922) (xy 4.126024 -308.058792) (xy 4.193344 -308.082349)
			(xy 4.257603 -308.113294) (xy 4.317994 -308.15124) (xy 4.373756 -308.195709) (xy 4.424189 -308.246142)
			(xy 4.468658 -308.301904) (xy 4.506604 -308.362295) (xy 4.537549 -308.426554) (xy 4.561106 -308.493874)
			(xy 4.576976 -308.563409) (xy 4.584962 -308.634283) (xy 4.584962 -308.705605) (xy 5.814814 -308.705605)
			(xy 5.814814 -308.634283) (xy 5.8228 -308.563409) (xy 5.83867 -308.493874) (xy 5.862227 -308.426554)
			(xy 5.893172 -308.362295) (xy 5.931118 -308.301904) (xy 5.975587 -308.246142) (xy 6.02602 -308.195709)
			(xy 6.081782 -308.15124) (xy 6.142173 -308.113294) (xy 6.206432 -308.082349) (xy 6.273752 -308.058792)
			(xy 6.343287 -308.042922) (xy 6.414161 -308.034936) (xy 6.449822 -308.034436) (xy 6.485483 -308.034936)
			(xy 6.556357 -308.042922) (xy 6.625892 -308.058792) (xy 6.693212 -308.082349) (xy 6.757471 -308.113294)
			(xy 6.817862 -308.15124) (xy 6.873624 -308.195709) (xy 6.924057 -308.246142) (xy 6.968526 -308.301904)
			(xy 7.006472 -308.362295) (xy 7.037417 -308.426554) (xy 7.060974 -308.493874) (xy 7.076844 -308.563409)
			(xy 7.08483 -308.634283) (xy 7.08483 -308.705605) (xy 7.076844 -308.776479) (xy 7.060974 -308.846014)
			(xy 7.037417 -308.913334) (xy 7.006472 -308.977593) (xy 6.968526 -309.037984) (xy 6.924057 -309.093746)
			(xy 6.873624 -309.144179) (xy 6.817862 -309.188648) (xy 6.757471 -309.226594) (xy 6.693212 -309.257539)
			(xy 6.625892 -309.281096) (xy 6.556357 -309.296966) (xy 6.485483 -309.304952) (xy 6.414161 -309.304952)
			(xy 6.343287 -309.296966) (xy 6.273752 -309.281096) (xy 6.206432 -309.257539) (xy 6.142173 -309.226594)
			(xy 6.081782 -309.188648) (xy 6.02602 -309.144179) (xy 5.975587 -309.093746) (xy 5.931118 -309.037984)
			(xy 5.893172 -308.977593) (xy 5.862227 -308.913334) (xy 5.83867 -308.846014) (xy 5.8228 -308.776479)
			(xy 5.814814 -308.705605) (xy 4.584962 -308.705605) (xy 4.576976 -308.776479) (xy 4.561106 -308.846014)
			(xy 4.537549 -308.913334) (xy 4.506604 -308.977593) (xy 4.468658 -309.037984) (xy 4.424189 -309.093746)
			(xy 4.373756 -309.144179) (xy 4.317994 -309.188648) (xy 4.257603 -309.226594) (xy 4.193344 -309.257539)
			(xy 4.126024 -309.281096) (xy 4.056489 -309.296966) (xy 3.985615 -309.304952) (xy 3.914293 -309.304952)
			(xy 3.843419 -309.296966) (xy 3.773884 -309.281096) (xy 3.706564 -309.257539) (xy 3.642305 -309.226594)
			(xy 3.581914 -309.188648) (xy 3.526152 -309.144179) (xy 3.475719 -309.093746) (xy 3.43125 -309.037984)
			(xy 3.393304 -308.977593) (xy 3.362359 -308.913334) (xy 3.338802 -308.846014) (xy 3.322932 -308.776479)
			(xy 3.314946 -308.705605) (xy 0.509016 -308.705605) (xy 0.509016 -309.705603) (xy 1.31495 -309.705603)
			(xy 1.31495 -309.634281) (xy 1.322936 -309.563407) (xy 1.338806 -309.493872) (xy 1.362363 -309.426552)
			(xy 1.393308 -309.362293) (xy 1.431254 -309.301902) (xy 1.475723 -309.24614) (xy 1.526156 -309.195707)
			(xy 1.581918 -309.151238) (xy 1.642309 -309.113292) (xy 1.706568 -309.082347) (xy 1.773888 -309.05879)
			(xy 1.843423 -309.04292) (xy 1.914297 -309.034934) (xy 1.949958 -309.034434) (xy 1.985619 -309.034934)
			(xy 2.056493 -309.04292) (xy 2.126028 -309.05879) (xy 2.193348 -309.082347) (xy 2.257607 -309.113292)
			(xy 2.317998 -309.151238) (xy 2.37376 -309.195707) (xy 2.424193 -309.24614) (xy 2.468662 -309.301902)
			(xy 2.506608 -309.362293) (xy 2.537553 -309.426552) (xy 2.56111 -309.493872) (xy 2.57698 -309.563407)
			(xy 2.584966 -309.634281) (xy 2.584966 -309.705603) (xy 7.81481 -309.705603) (xy 7.81481 -309.634281)
			(xy 7.822796 -309.563407) (xy 7.838666 -309.493872) (xy 7.862223 -309.426552) (xy 7.893168 -309.362293)
			(xy 7.931114 -309.301902) (xy 7.975583 -309.24614) (xy 8.026016 -309.195707) (xy 8.081778 -309.151238)
			(xy 8.142169 -309.113292) (xy 8.206428 -309.082347) (xy 8.273748 -309.05879) (xy 8.343283 -309.04292)
			(xy 8.414157 -309.034934) (xy 8.449818 -309.034434) (xy 8.485479 -309.034934) (xy 8.556353 -309.04292)
			(xy 8.625888 -309.05879) (xy 8.693208 -309.082347) (xy 8.757467 -309.113292) (xy 8.817858 -309.151238)
			(xy 8.87362 -309.195707) (xy 8.924053 -309.24614) (xy 8.968522 -309.301902) (xy 9.006468 -309.362293)
			(xy 9.037413 -309.426552) (xy 9.06097 -309.493872) (xy 9.07684 -309.563407) (xy 9.084826 -309.634281)
			(xy 9.084826 -309.705603) (xy 9.07684 -309.776477) (xy 9.06097 -309.846012) (xy 9.037413 -309.913332)
			(xy 9.006468 -309.977591) (xy 8.968522 -310.037982) (xy 8.924053 -310.093744) (xy 8.87362 -310.144177)
			(xy 8.817858 -310.188646) (xy 8.757467 -310.226592) (xy 8.693208 -310.257537) (xy 8.625888 -310.281094)
			(xy 8.556353 -310.296964) (xy 8.485479 -310.30495) (xy 8.414157 -310.30495) (xy 8.343283 -310.296964)
			(xy 8.273748 -310.281094) (xy 8.206428 -310.257537) (xy 8.142169 -310.226592) (xy 8.081778 -310.188646)
			(xy 8.026016 -310.144177) (xy 7.975583 -310.093744) (xy 7.931114 -310.037982) (xy 7.893168 -309.977591)
			(xy 7.862223 -309.913332) (xy 7.838666 -309.846012) (xy 7.822796 -309.776477) (xy 7.81481 -309.705603)
			(xy 2.584966 -309.705603) (xy 2.57698 -309.776477) (xy 2.56111 -309.846012) (xy 2.537553 -309.913332)
			(xy 2.506608 -309.977591) (xy 2.468662 -310.037982) (xy 2.424193 -310.093744) (xy 2.37376 -310.144177)
			(xy 2.317998 -310.188646) (xy 2.257607 -310.226592) (xy 2.193348 -310.257537) (xy 2.126028 -310.281094)
			(xy 2.056493 -310.296964) (xy 1.985619 -310.30495) (xy 1.914297 -310.30495) (xy 1.843423 -310.296964)
			(xy 1.773888 -310.281094) (xy 1.706568 -310.257537) (xy 1.642309 -310.226592) (xy 1.581918 -310.188646)
			(xy 1.526156 -310.144177) (xy 1.475723 -310.093744) (xy 1.431254 -310.037982) (xy 1.393308 -309.977591)
			(xy 1.362363 -309.913332) (xy 1.338806 -309.846012) (xy 1.322936 -309.776477) (xy 1.31495 -309.705603)
			(xy 0.509016 -309.705603) (xy 0.509016 -310.705601) (xy 3.314946 -310.705601) (xy 3.314946 -310.634279)
			(xy 3.322932 -310.563405) (xy 3.338802 -310.49387) (xy 3.362359 -310.42655) (xy 3.393304 -310.362291)
			(xy 3.43125 -310.3019) (xy 3.475719 -310.246138) (xy 3.526152 -310.195705) (xy 3.581914 -310.151236)
			(xy 3.642305 -310.11329) (xy 3.706564 -310.082345) (xy 3.773884 -310.058788) (xy 3.843419 -310.042918)
			(xy 3.914293 -310.034932) (xy 3.949954 -310.034432) (xy 3.985615 -310.034932) (xy 4.056489 -310.042918)
			(xy 4.126024 -310.058788) (xy 4.193344 -310.082345) (xy 4.257603 -310.11329) (xy 4.317994 -310.151236)
			(xy 4.373756 -310.195705) (xy 4.424189 -310.246138) (xy 4.468658 -310.3019) (xy 4.506604 -310.362291)
			(xy 4.537549 -310.42655) (xy 4.561106 -310.49387) (xy 4.576976 -310.563405) (xy 4.584962 -310.634279)
			(xy 4.584962 -310.705601) (xy 5.814814 -310.705601) (xy 5.814814 -310.634279) (xy 5.8228 -310.563405)
			(xy 5.83867 -310.49387) (xy 5.862227 -310.42655) (xy 5.893172 -310.362291) (xy 5.931118 -310.3019)
			(xy 5.975587 -310.246138) (xy 6.02602 -310.195705) (xy 6.081782 -310.151236) (xy 6.142173 -310.11329)
			(xy 6.206432 -310.082345) (xy 6.273752 -310.058788) (xy 6.343287 -310.042918) (xy 6.414161 -310.034932)
			(xy 6.449822 -310.034432) (xy 6.485483 -310.034932) (xy 6.556357 -310.042918) (xy 6.625892 -310.058788)
			(xy 6.693212 -310.082345) (xy 6.757471 -310.11329) (xy 6.817862 -310.151236) (xy 6.873624 -310.195705)
			(xy 6.924057 -310.246138) (xy 6.968526 -310.3019) (xy 7.006472 -310.362291) (xy 7.037417 -310.42655)
			(xy 7.060974 -310.49387) (xy 7.076844 -310.563405) (xy 7.08483 -310.634279) (xy 7.08483 -310.705601)
			(xy 7.076844 -310.776475) (xy 7.060974 -310.84601) (xy 7.037417 -310.91333) (xy 7.006472 -310.977589)
			(xy 6.968526 -311.03798) (xy 6.924057 -311.093742) (xy 6.873624 -311.144175) (xy 6.817862 -311.188644)
			(xy 6.757471 -311.22659) (xy 6.693212 -311.257535) (xy 6.625892 -311.281092) (xy 6.556357 -311.296962)
			(xy 6.485483 -311.304948) (xy 6.414161 -311.304948) (xy 6.343287 -311.296962) (xy 6.273752 -311.281092)
			(xy 6.206432 -311.257535) (xy 6.142173 -311.22659) (xy 6.081782 -311.188644) (xy 6.02602 -311.144175)
			(xy 5.975587 -311.093742) (xy 5.931118 -311.03798) (xy 5.893172 -310.977589) (xy 5.862227 -310.91333)
			(xy 5.83867 -310.84601) (xy 5.8228 -310.776475) (xy 5.814814 -310.705601) (xy 4.584962 -310.705601)
			(xy 4.576976 -310.776475) (xy 4.561106 -310.84601) (xy 4.537549 -310.91333) (xy 4.506604 -310.977589)
			(xy 4.468658 -311.03798) (xy 4.424189 -311.093742) (xy 4.373756 -311.144175) (xy 4.317994 -311.188644)
			(xy 4.257603 -311.22659) (xy 4.193344 -311.257535) (xy 4.126024 -311.281092) (xy 4.056489 -311.296962)
			(xy 3.985615 -311.304948) (xy 3.914293 -311.304948) (xy 3.843419 -311.296962) (xy 3.773884 -311.281092)
			(xy 3.706564 -311.257535) (xy 3.642305 -311.22659) (xy 3.581914 -311.188644) (xy 3.526152 -311.144175)
			(xy 3.475719 -311.093742) (xy 3.43125 -311.03798) (xy 3.393304 -310.977589) (xy 3.362359 -310.91333)
			(xy 3.338802 -310.84601) (xy 3.322932 -310.776475) (xy 3.314946 -310.705601) (xy 0.509016 -310.705601)
			(xy 0.509016 -311.705599) (xy 7.81481 -311.705599) (xy 7.81481 -311.634277) (xy 7.822796 -311.563403)
			(xy 7.838666 -311.493868) (xy 7.862223 -311.426548) (xy 7.893168 -311.362289) (xy 7.931114 -311.301898)
			(xy 7.975583 -311.246136) (xy 8.026016 -311.195703) (xy 8.081778 -311.151234) (xy 8.142169 -311.113288)
			(xy 8.206428 -311.082343) (xy 8.273748 -311.058786) (xy 8.343283 -311.042916) (xy 8.414157 -311.03493)
			(xy 8.449818 -311.03443) (xy 8.485479 -311.03493) (xy 8.556353 -311.042916) (xy 8.625888 -311.058786)
			(xy 8.693208 -311.082343) (xy 8.757467 -311.113288) (xy 8.817858 -311.151234) (xy 8.87362 -311.195703)
			(xy 8.924053 -311.246136) (xy 8.968522 -311.301898) (xy 9.006468 -311.362289) (xy 9.037413 -311.426548)
			(xy 9.06097 -311.493868) (xy 9.07684 -311.563403) (xy 9.084826 -311.634277) (xy 9.084826 -311.705599)
			(xy 9.07684 -311.776473) (xy 9.06097 -311.846008) (xy 9.037413 -311.913328) (xy 9.006468 -311.977587)
			(xy 8.968522 -312.037978) (xy 8.924053 -312.09374) (xy 8.87362 -312.144173) (xy 8.817858 -312.188642)
			(xy 8.757467 -312.226588) (xy 8.693208 -312.257533) (xy 8.625888 -312.28109) (xy 8.556353 -312.29696)
			(xy 8.485479 -312.304946) (xy 8.414157 -312.304946) (xy 8.343283 -312.29696) (xy 8.273748 -312.28109)
			(xy 8.206428 -312.257533) (xy 8.142169 -312.226588) (xy 8.081778 -312.188642) (xy 8.026016 -312.144173)
			(xy 7.975583 -312.09374) (xy 7.931114 -312.037978) (xy 7.893168 -311.977587) (xy 7.862223 -311.913328)
			(xy 7.838666 -311.846008) (xy 7.822796 -311.776473) (xy 7.81481 -311.705599) (xy 0.509016 -311.705599)
			(xy 0.509016 -312.705597) (xy 3.314946 -312.705597) (xy 3.314946 -312.634275) (xy 3.322932 -312.563401)
			(xy 3.338802 -312.493866) (xy 3.362359 -312.426546) (xy 3.393304 -312.362287) (xy 3.43125 -312.301896)
			(xy 3.475719 -312.246134) (xy 3.526152 -312.195701) (xy 3.581914 -312.151232) (xy 3.642305 -312.113286)
			(xy 3.706564 -312.082341) (xy 3.773884 -312.058784) (xy 3.843419 -312.042914) (xy 3.914293 -312.034928)
			(xy 3.949954 -312.034428) (xy 3.985615 -312.034928) (xy 4.056489 -312.042914) (xy 4.126024 -312.058784)
			(xy 4.193344 -312.082341) (xy 4.257603 -312.113286) (xy 4.317994 -312.151232) (xy 4.373756 -312.195701)
			(xy 4.424189 -312.246134) (xy 4.468658 -312.301896) (xy 4.506604 -312.362287) (xy 4.537549 -312.426546)
			(xy 4.561106 -312.493866) (xy 4.576976 -312.563401) (xy 4.584962 -312.634275) (xy 4.584962 -312.705597)
			(xy 4.576976 -312.776471) (xy 4.561106 -312.846006) (xy 4.537549 -312.913326) (xy 4.506604 -312.977585)
			(xy 4.468658 -313.037976) (xy 4.424189 -313.093738) (xy 4.373756 -313.144171) (xy 4.317994 -313.18864)
			(xy 4.257603 -313.226586) (xy 4.193344 -313.257531) (xy 4.126024 -313.281088) (xy 4.056489 -313.296958)
			(xy 3.985615 -313.304944) (xy 3.914293 -313.304944) (xy 3.843419 -313.296958) (xy 3.773884 -313.281088)
			(xy 3.706564 -313.257531) (xy 3.642305 -313.226586) (xy 3.581914 -313.18864) (xy 3.526152 -313.144171)
			(xy 3.475719 -313.093738) (xy 3.43125 -313.037976) (xy 3.393304 -312.977585) (xy 3.362359 -312.913326)
			(xy 3.338802 -312.846006) (xy 3.322932 -312.776471) (xy 3.314946 -312.705597) (xy 0.509016 -312.705597)
			(xy 0.509016 -313.705595) (xy 1.31495 -313.705595) (xy 1.31495 -313.634273) (xy 1.322936 -313.563399)
			(xy 1.338806 -313.493864) (xy 1.362363 -313.426544) (xy 1.393308 -313.362285) (xy 1.431254 -313.301894)
			(xy 1.475723 -313.246132) (xy 1.526156 -313.195699) (xy 1.581918 -313.15123) (xy 1.642309 -313.113284)
			(xy 1.706568 -313.082339) (xy 1.773888 -313.058782) (xy 1.843423 -313.042912) (xy 1.914297 -313.034926)
			(xy 1.949958 -313.034426) (xy 1.985619 -313.034926) (xy 2.056493 -313.042912) (xy 2.126028 -313.058782)
			(xy 2.193348 -313.082339) (xy 2.257607 -313.113284) (xy 2.317998 -313.15123) (xy 2.37376 -313.195699)
			(xy 2.424193 -313.246132) (xy 2.468662 -313.301894) (xy 2.506608 -313.362285) (xy 2.537553 -313.426544)
			(xy 2.56111 -313.493864) (xy 2.57698 -313.563399) (xy 2.584966 -313.634273) (xy 2.584966 -313.705595)
			(xy 7.81481 -313.705595) (xy 7.81481 -313.634273) (xy 7.822796 -313.563399) (xy 7.838666 -313.493864)
			(xy 7.862223 -313.426544) (xy 7.893168 -313.362285) (xy 7.931114 -313.301894) (xy 7.975583 -313.246132)
			(xy 8.026016 -313.195699) (xy 8.081778 -313.15123) (xy 8.142169 -313.113284) (xy 8.206428 -313.082339)
			(xy 8.273748 -313.058782) (xy 8.343283 -313.042912) (xy 8.414157 -313.034926) (xy 8.449818 -313.034426)
			(xy 8.485479 -313.034926) (xy 8.556353 -313.042912) (xy 8.625888 -313.058782) (xy 8.693208 -313.082339)
			(xy 8.757467 -313.113284) (xy 8.817858 -313.15123) (xy 8.87362 -313.195699) (xy 8.924053 -313.246132)
			(xy 8.968522 -313.301894) (xy 9.006468 -313.362285) (xy 9.037413 -313.426544) (xy 9.06097 -313.493864)
			(xy 9.07684 -313.563399) (xy 9.084826 -313.634273) (xy 9.084826 -313.705595) (xy 9.07684 -313.776469)
			(xy 9.06097 -313.846004) (xy 9.037413 -313.913324) (xy 9.006468 -313.977583) (xy 8.968522 -314.037974)
			(xy 8.924053 -314.093736) (xy 8.87362 -314.144169) (xy 8.817858 -314.188638) (xy 8.757467 -314.226584)
			(xy 8.693208 -314.257529) (xy 8.625888 -314.281086) (xy 8.556353 -314.296956) (xy 8.485479 -314.304942)
			(xy 8.414157 -314.304942) (xy 8.343283 -314.296956) (xy 8.273748 -314.281086) (xy 8.206428 -314.257529)
			(xy 8.142169 -314.226584) (xy 8.081778 -314.188638) (xy 8.026016 -314.144169) (xy 7.975583 -314.093736)
			(xy 7.931114 -314.037974) (xy 7.893168 -313.977583) (xy 7.862223 -313.913324) (xy 7.838666 -313.846004)
			(xy 7.822796 -313.776469) (xy 7.81481 -313.705595) (xy 2.584966 -313.705595) (xy 2.57698 -313.776469)
			(xy 2.56111 -313.846004) (xy 2.537553 -313.913324) (xy 2.506608 -313.977583) (xy 2.468662 -314.037974)
			(xy 2.424193 -314.093736) (xy 2.37376 -314.144169) (xy 2.317998 -314.188638) (xy 2.257607 -314.226584)
			(xy 2.193348 -314.257529) (xy 2.126028 -314.281086) (xy 2.056493 -314.296956) (xy 1.985619 -314.304942)
			(xy 1.914297 -314.304942) (xy 1.843423 -314.296956) (xy 1.773888 -314.281086) (xy 1.706568 -314.257529)
			(xy 1.642309 -314.226584) (xy 1.581918 -314.188638) (xy 1.526156 -314.144169) (xy 1.475723 -314.093736)
			(xy 1.431254 -314.037974) (xy 1.393308 -313.977583) (xy 1.362363 -313.913324) (xy 1.338806 -313.846004)
			(xy 1.322936 -313.776469) (xy 1.31495 -313.705595) (xy 0.509016 -313.705595) (xy 0.509016 -314.705593)
			(xy 3.314946 -314.705593) (xy 3.314946 -314.634271) (xy 3.322932 -314.563397) (xy 3.338802 -314.493862)
			(xy 3.362359 -314.426542) (xy 3.393304 -314.362283) (xy 3.43125 -314.301892) (xy 3.475719 -314.24613)
			(xy 3.526152 -314.195697) (xy 3.581914 -314.151228) (xy 3.642305 -314.113282) (xy 3.706564 -314.082337)
			(xy 3.773884 -314.05878) (xy 3.843419 -314.04291) (xy 3.914293 -314.034924) (xy 3.949954 -314.034424)
			(xy 3.985615 -314.034924) (xy 4.056489 -314.04291) (xy 4.126024 -314.05878) (xy 4.193344 -314.082337)
			(xy 4.257603 -314.113282) (xy 4.317994 -314.151228) (xy 4.373756 -314.195697) (xy 4.424189 -314.24613)
			(xy 4.468658 -314.301892) (xy 4.506604 -314.362283) (xy 4.537549 -314.426542) (xy 4.561106 -314.493862)
			(xy 4.576976 -314.563397) (xy 4.584962 -314.634271) (xy 4.584962 -314.705593) (xy 5.814814 -314.705593)
			(xy 5.814814 -314.634271) (xy 5.8228 -314.563397) (xy 5.83867 -314.493862) (xy 5.862227 -314.426542)
			(xy 5.893172 -314.362283) (xy 5.931118 -314.301892) (xy 5.975587 -314.24613) (xy 6.02602 -314.195697)
			(xy 6.081782 -314.151228) (xy 6.142173 -314.113282) (xy 6.206432 -314.082337) (xy 6.273752 -314.05878)
			(xy 6.343287 -314.04291) (xy 6.414161 -314.034924) (xy 6.449822 -314.034424) (xy 6.485483 -314.034924)
			(xy 6.556357 -314.04291) (xy 6.625892 -314.05878) (xy 6.693212 -314.082337) (xy 6.757471 -314.113282)
			(xy 6.817862 -314.151228) (xy 6.873624 -314.195697) (xy 6.924057 -314.24613) (xy 6.968526 -314.301892)
			(xy 7.006472 -314.362283) (xy 7.037417 -314.426542) (xy 7.060974 -314.493862) (xy 7.076844 -314.563397)
			(xy 7.08483 -314.634271) (xy 7.08483 -314.705593) (xy 7.082495 -314.726316) (xy 12.100796 -314.726316)
			(xy 12.100796 -314.66638) (xy 12.108619 -314.606958) (xy 12.124132 -314.549065) (xy 12.147068 -314.493692)
			(xy 12.177035 -314.441786) (xy 12.213522 -314.394236) (xy 12.255902 -314.351856) (xy 12.303452 -314.315369)
			(xy 12.355358 -314.285402) (xy 12.410731 -314.262466) (xy 12.468624 -314.246953) (xy 12.528046 -314.23913)
			(xy 12.558014 -314.23864) (xy 12.587982 -314.23913) (xy 12.647404 -314.246953) (xy 12.705297 -314.262466)
			(xy 12.76067 -314.285402) (xy 12.812576 -314.315369) (xy 12.860126 -314.351856) (xy 12.902506 -314.394236)
			(xy 12.938993 -314.441786) (xy 12.96896 -314.493692) (xy 12.991896 -314.549065) (xy 13.007409 -314.606958)
			(xy 13.015232 -314.66638) (xy 13.015232 -314.726316) (xy 13.007409 -314.785738) (xy 12.991896 -314.843631)
			(xy 12.96896 -314.899004) (xy 12.938993 -314.95091) (xy 12.902506 -314.99846) (xy 12.860126 -315.04084)
			(xy 12.812576 -315.077327) (xy 12.76067 -315.107294) (xy 12.705297 -315.13023) (xy 12.647404 -315.145743)
			(xy 12.587982 -315.153566) (xy 12.528046 -315.153566) (xy 12.468624 -315.145743) (xy 12.410731 -315.13023)
			(xy 12.355358 -315.107294) (xy 12.303452 -315.077327) (xy 12.255902 -315.04084) (xy 12.213522 -314.99846)
			(xy 12.177035 -314.95091) (xy 12.147068 -314.899004) (xy 12.124132 -314.843631) (xy 12.108619 -314.785738)
			(xy 12.100796 -314.726316) (xy 7.082495 -314.726316) (xy 7.076844 -314.776467) (xy 7.060974 -314.846002)
			(xy 7.037417 -314.913322) (xy 7.006472 -314.977581) (xy 6.968526 -315.037972) (xy 6.924057 -315.093734)
			(xy 6.873624 -315.144167) (xy 6.817862 -315.188636) (xy 6.757471 -315.226582) (xy 6.693212 -315.257527)
			(xy 6.625892 -315.281084) (xy 6.556357 -315.296954) (xy 6.485483 -315.30494) (xy 6.414161 -315.30494)
			(xy 6.343287 -315.296954) (xy 6.273752 -315.281084) (xy 6.206432 -315.257527) (xy 6.142173 -315.226582)
			(xy 6.081782 -315.188636) (xy 6.02602 -315.144167) (xy 5.975587 -315.093734) (xy 5.931118 -315.037972)
			(xy 5.893172 -314.977581) (xy 5.862227 -314.913322) (xy 5.83867 -314.846002) (xy 5.8228 -314.776467)
			(xy 5.814814 -314.705593) (xy 4.584962 -314.705593) (xy 4.576976 -314.776467) (xy 4.561106 -314.846002)
			(xy 4.537549 -314.913322) (xy 4.506604 -314.977581) (xy 4.468658 -315.037972) (xy 4.424189 -315.093734)
			(xy 4.373756 -315.144167) (xy 4.317994 -315.188636) (xy 4.257603 -315.226582) (xy 4.193344 -315.257527)
			(xy 4.126024 -315.281084) (xy 4.056489 -315.296954) (xy 3.985615 -315.30494) (xy 3.914293 -315.30494)
			(xy 3.843419 -315.296954) (xy 3.773884 -315.281084) (xy 3.706564 -315.257527) (xy 3.642305 -315.226582)
			(xy 3.581914 -315.188636) (xy 3.526152 -315.144167) (xy 3.475719 -315.093734) (xy 3.43125 -315.037972)
			(xy 3.393304 -314.977581) (xy 3.362359 -314.913322) (xy 3.338802 -314.846002) (xy 3.322932 -314.776467)
			(xy 3.314946 -314.705593) (xy 0.509016 -314.705593) (xy 0.509016 -315.705591) (xy 1.31495 -315.705591)
			(xy 1.31495 -315.634269) (xy 1.322936 -315.563395) (xy 1.338806 -315.49386) (xy 1.362363 -315.42654)
			(xy 1.393308 -315.362281) (xy 1.431254 -315.30189) (xy 1.475723 -315.246128) (xy 1.526156 -315.195695)
			(xy 1.581918 -315.151226) (xy 1.642309 -315.11328) (xy 1.706568 -315.082335) (xy 1.773888 -315.058778)
			(xy 1.843423 -315.042908) (xy 1.914297 -315.034922) (xy 1.949958 -315.034422) (xy 1.985619 -315.034922)
			(xy 2.056493 -315.042908) (xy 2.126028 -315.058778) (xy 2.193348 -315.082335) (xy 2.257607 -315.11328)
			(xy 2.317998 -315.151226) (xy 2.37376 -315.195695) (xy 2.424193 -315.246128) (xy 2.468662 -315.30189)
			(xy 2.506608 -315.362281) (xy 2.537553 -315.42654) (xy 2.56111 -315.49386) (xy 2.57698 -315.563395)
			(xy 2.584966 -315.634269) (xy 2.584966 -315.705591) (xy 7.81481 -315.705591) (xy 7.81481 -315.634269)
			(xy 7.822796 -315.563395) (xy 7.838666 -315.49386) (xy 7.862223 -315.42654) (xy 7.893168 -315.362281)
			(xy 7.931114 -315.30189) (xy 7.975583 -315.246128) (xy 8.026016 -315.195695) (xy 8.081778 -315.151226)
			(xy 8.142169 -315.11328) (xy 8.206428 -315.082335) (xy 8.273748 -315.058778) (xy 8.343283 -315.042908)
			(xy 8.414157 -315.034922) (xy 8.449818 -315.034422) (xy 8.485479 -315.034922) (xy 8.556353 -315.042908)
			(xy 8.625888 -315.058778) (xy 8.693208 -315.082335) (xy 8.757467 -315.11328) (xy 8.817858 -315.151226)
			(xy 8.87362 -315.195695) (xy 8.924053 -315.246128) (xy 8.968522 -315.30189) (xy 9.006468 -315.362281)
			(xy 9.037413 -315.42654) (xy 9.06097 -315.49386) (xy 9.07684 -315.563395) (xy 9.084826 -315.634269)
			(xy 9.084826 -315.705591) (xy 9.07684 -315.776465) (xy 9.06097 -315.846) (xy 9.037413 -315.91332)
			(xy 9.006468 -315.977579) (xy 8.968522 -316.03797) (xy 8.924053 -316.093732) (xy 8.87362 -316.144165)
			(xy 8.817858 -316.188634) (xy 8.757467 -316.22658) (xy 8.693208 -316.257525) (xy 8.625888 -316.281082)
			(xy 8.556353 -316.296952) (xy 8.485479 -316.304938) (xy 8.414157 -316.304938) (xy 8.343283 -316.296952)
			(xy 8.273748 -316.281082) (xy 8.206428 -316.257525) (xy 8.142169 -316.22658) (xy 8.081778 -316.188634)
			(xy 8.026016 -316.144165) (xy 7.975583 -316.093732) (xy 7.931114 -316.03797) (xy 7.893168 -315.977579)
			(xy 7.862223 -315.91332) (xy 7.838666 -315.846) (xy 7.822796 -315.776465) (xy 7.81481 -315.705591)
			(xy 2.584966 -315.705591) (xy 2.57698 -315.776465) (xy 2.56111 -315.846) (xy 2.537553 -315.91332)
			(xy 2.506608 -315.977579) (xy 2.468662 -316.03797) (xy 2.424193 -316.093732) (xy 2.37376 -316.144165)
			(xy 2.317998 -316.188634) (xy 2.257607 -316.22658) (xy 2.193348 -316.257525) (xy 2.126028 -316.281082)
			(xy 2.056493 -316.296952) (xy 1.985619 -316.304938) (xy 1.914297 -316.304938) (xy 1.843423 -316.296952)
			(xy 1.773888 -316.281082) (xy 1.706568 -316.257525) (xy 1.642309 -316.22658) (xy 1.581918 -316.188634)
			(xy 1.526156 -316.144165) (xy 1.475723 -316.093732) (xy 1.431254 -316.03797) (xy 1.393308 -315.977579)
			(xy 1.362363 -315.91332) (xy 1.338806 -315.846) (xy 1.322936 -315.776465) (xy 1.31495 -315.705591)
			(xy 0.509016 -315.705591) (xy 0.509016 -316.705589) (xy 5.814814 -316.705589) (xy 5.814814 -316.634267)
			(xy 5.8228 -316.563393) (xy 5.83867 -316.493858) (xy 5.862227 -316.426538) (xy 5.893172 -316.362279)
			(xy 5.931118 -316.301888) (xy 5.975587 -316.246126) (xy 6.02602 -316.195693) (xy 6.081782 -316.151224)
			(xy 6.142173 -316.113278) (xy 6.206432 -316.082333) (xy 6.273752 -316.058776) (xy 6.343287 -316.042906)
			(xy 6.414161 -316.03492) (xy 6.449822 -316.03442) (xy 6.485483 -316.03492) (xy 6.556357 -316.042906)
			(xy 6.625892 -316.058776) (xy 6.693212 -316.082333) (xy 6.757471 -316.113278) (xy 6.817862 -316.151224)
			(xy 6.873624 -316.195693) (xy 6.924057 -316.246126) (xy 6.968526 -316.301888) (xy 7.006472 -316.362279)
			(xy 7.037417 -316.426538) (xy 7.060974 -316.493858) (xy 7.076844 -316.563393) (xy 7.08483 -316.634267)
			(xy 7.08483 -316.705589) (xy 7.076844 -316.776463) (xy 7.060974 -316.845998) (xy 7.037417 -316.913318)
			(xy 7.006472 -316.977577) (xy 6.968526 -317.037968) (xy 6.924057 -317.09373) (xy 6.873624 -317.144163)
			(xy 6.817862 -317.188632) (xy 6.757471 -317.226578) (xy 6.693212 -317.257523) (xy 6.625892 -317.28108)
			(xy 6.556357 -317.29695) (xy 6.485483 -317.304936) (xy 6.414161 -317.304936) (xy 6.343287 -317.29695)
			(xy 6.273752 -317.28108) (xy 6.206432 -317.257523) (xy 6.142173 -317.226578) (xy 6.081782 -317.188632)
			(xy 6.02602 -317.144163) (xy 5.975587 -317.09373) (xy 5.931118 -317.037968) (xy 5.893172 -316.977577)
			(xy 5.862227 -316.913318) (xy 5.83867 -316.845998) (xy 5.8228 -316.776463) (xy 5.814814 -316.705589)
			(xy 0.509016 -316.705589) (xy 0.509016 -317.705587) (xy 1.31495 -317.705587) (xy 1.31495 -317.634265)
			(xy 1.322936 -317.563391) (xy 1.338806 -317.493856) (xy 1.362363 -317.426536) (xy 1.393308 -317.362277)
			(xy 1.431254 -317.301886) (xy 1.475723 -317.246124) (xy 1.526156 -317.195691) (xy 1.581918 -317.151222)
			(xy 1.642309 -317.113276) (xy 1.706568 -317.082331) (xy 1.773888 -317.058774) (xy 1.843423 -317.042904)
			(xy 1.914297 -317.034918) (xy 1.949958 -317.034418) (xy 1.985619 -317.034918) (xy 2.056493 -317.042904)
			(xy 2.126028 -317.058774) (xy 2.193348 -317.082331) (xy 2.257607 -317.113276) (xy 2.317998 -317.151222)
			(xy 2.37376 -317.195691) (xy 2.424193 -317.246124) (xy 2.468662 -317.301886) (xy 2.506608 -317.362277)
			(xy 2.537553 -317.426536) (xy 2.56111 -317.493856) (xy 2.57698 -317.563391) (xy 2.584966 -317.634265)
			(xy 2.584966 -317.705587) (xy 2.57698 -317.776461) (xy 2.56111 -317.845996) (xy 2.537553 -317.913316)
			(xy 2.506608 -317.977575) (xy 2.468662 -318.037966) (xy 2.424193 -318.093728) (xy 2.37376 -318.144161)
			(xy 2.317998 -318.18863) (xy 2.257607 -318.226576) (xy 2.193348 -318.257521) (xy 2.126028 -318.281078)
			(xy 2.056493 -318.296948) (xy 1.985619 -318.304934) (xy 1.914297 -318.304934) (xy 1.843423 -318.296948)
			(xy 1.773888 -318.281078) (xy 1.706568 -318.257521) (xy 1.642309 -318.226576) (xy 1.581918 -318.18863)
			(xy 1.526156 -318.144161) (xy 1.475723 -318.093728) (xy 1.431254 -318.037966) (xy 1.393308 -317.977575)
			(xy 1.362363 -317.913316) (xy 1.338806 -317.845996) (xy 1.322936 -317.776461) (xy 1.31495 -317.705587)
			(xy 0.509016 -317.705587) (xy 0.509016 -318.705585) (xy 3.314946 -318.705585) (xy 3.314946 -318.634263)
			(xy 3.322932 -318.563389) (xy 3.338802 -318.493854) (xy 3.362359 -318.426534) (xy 3.393304 -318.362275)
			(xy 3.43125 -318.301884) (xy 3.475719 -318.246122) (xy 3.526152 -318.195689) (xy 3.581914 -318.15122)
			(xy 3.642305 -318.113274) (xy 3.706564 -318.082329) (xy 3.773884 -318.058772) (xy 3.843419 -318.042902)
			(xy 3.914293 -318.034916) (xy 3.949954 -318.034416) (xy 3.985615 -318.034916) (xy 4.056489 -318.042902)
			(xy 4.126024 -318.058772) (xy 4.193344 -318.082329) (xy 4.257603 -318.113274) (xy 4.317994 -318.15122)
			(xy 4.373756 -318.195689) (xy 4.424189 -318.246122) (xy 4.468658 -318.301884) (xy 4.506604 -318.362275)
			(xy 4.537549 -318.426534) (xy 4.561106 -318.493854) (xy 4.576976 -318.563389) (xy 4.584962 -318.634263)
			(xy 4.584962 -318.705585) (xy 5.814814 -318.705585) (xy 5.814814 -318.634263) (xy 5.8228 -318.563389)
			(xy 5.83867 -318.493854) (xy 5.862227 -318.426534) (xy 5.893172 -318.362275) (xy 5.931118 -318.301884)
			(xy 5.975587 -318.246122) (xy 6.02602 -318.195689) (xy 6.081782 -318.15122) (xy 6.142173 -318.113274)
			(xy 6.206432 -318.082329) (xy 6.273752 -318.058772) (xy 6.343287 -318.042902) (xy 6.414161 -318.034916)
			(xy 6.449822 -318.034416) (xy 6.485483 -318.034916) (xy 6.556357 -318.042902) (xy 6.625892 -318.058772)
			(xy 6.693212 -318.082329) (xy 6.757471 -318.113274) (xy 6.817862 -318.15122) (xy 6.873624 -318.195689)
			(xy 6.924057 -318.246122) (xy 6.968526 -318.301884) (xy 7.006472 -318.362275) (xy 7.037417 -318.426534)
			(xy 7.060974 -318.493854) (xy 7.076844 -318.563389) (xy 7.08483 -318.634263) (xy 7.08483 -318.705585)
			(xy 7.076844 -318.776459) (xy 7.060974 -318.845994) (xy 7.037417 -318.913314) (xy 7.006472 -318.977573)
			(xy 6.968526 -319.037964) (xy 6.924057 -319.093726) (xy 6.873624 -319.144159) (xy 6.817862 -319.188628)
			(xy 6.757471 -319.226574) (xy 6.693212 -319.257519) (xy 6.625892 -319.281076) (xy 6.556357 -319.296946)
			(xy 6.485483 -319.304932) (xy 6.414161 -319.304932) (xy 6.343287 -319.296946) (xy 6.273752 -319.281076)
			(xy 6.206432 -319.257519) (xy 6.142173 -319.226574) (xy 6.081782 -319.188628) (xy 6.02602 -319.144159)
			(xy 5.975587 -319.093726) (xy 5.931118 -319.037964) (xy 5.893172 -318.977573) (xy 5.862227 -318.913314)
			(xy 5.83867 -318.845994) (xy 5.8228 -318.776459) (xy 5.814814 -318.705585) (xy 4.584962 -318.705585)
			(xy 4.576976 -318.776459) (xy 4.561106 -318.845994) (xy 4.537549 -318.913314) (xy 4.506604 -318.977573)
			(xy 4.468658 -319.037964) (xy 4.424189 -319.093726) (xy 4.373756 -319.144159) (xy 4.317994 -319.188628)
			(xy 4.257603 -319.226574) (xy 4.193344 -319.257519) (xy 4.126024 -319.281076) (xy 4.056489 -319.296946)
			(xy 3.985615 -319.304932) (xy 3.914293 -319.304932) (xy 3.843419 -319.296946) (xy 3.773884 -319.281076)
			(xy 3.706564 -319.257519) (xy 3.642305 -319.226574) (xy 3.581914 -319.188628) (xy 3.526152 -319.144159)
			(xy 3.475719 -319.093726) (xy 3.43125 -319.037964) (xy 3.393304 -318.977573) (xy 3.362359 -318.913314)
			(xy 3.338802 -318.845994) (xy 3.322932 -318.776459) (xy 3.314946 -318.705585) (xy 0.509016 -318.705585)
			(xy 0.509016 -319.705583) (xy 1.31495 -319.705583) (xy 1.31495 -319.634261) (xy 1.322936 -319.563387)
			(xy 1.338806 -319.493852) (xy 1.362363 -319.426532) (xy 1.393308 -319.362273) (xy 1.431254 -319.301882)
			(xy 1.475723 -319.24612) (xy 1.526156 -319.195687) (xy 1.581918 -319.151218) (xy 1.642309 -319.113272)
			(xy 1.706568 -319.082327) (xy 1.773888 -319.05877) (xy 1.843423 -319.0429) (xy 1.914297 -319.034914)
			(xy 1.949958 -319.034414) (xy 1.985619 -319.034914) (xy 2.056493 -319.0429) (xy 2.126028 -319.05877)
			(xy 2.193348 -319.082327) (xy 2.257607 -319.113272) (xy 2.317998 -319.151218) (xy 2.37376 -319.195687)
			(xy 2.424193 -319.24612) (xy 2.468662 -319.301882) (xy 2.506608 -319.362273) (xy 2.537553 -319.426532)
			(xy 2.56111 -319.493852) (xy 2.57698 -319.563387) (xy 2.584966 -319.634261) (xy 2.584966 -319.705583)
			(xy 2.57698 -319.776457) (xy 2.56111 -319.845992) (xy 2.537553 -319.913312) (xy 2.506608 -319.977571)
			(xy 2.468662 -320.037962) (xy 2.424193 -320.093724) (xy 2.37376 -320.144157) (xy 2.317998 -320.188626)
			(xy 2.257607 -320.226572) (xy 2.193348 -320.257517) (xy 2.126028 -320.281074) (xy 2.056493 -320.296944)
			(xy 1.985619 -320.30493) (xy 1.914297 -320.30493) (xy 1.843423 -320.296944) (xy 1.773888 -320.281074)
			(xy 1.706568 -320.257517) (xy 1.642309 -320.226572) (xy 1.581918 -320.188626) (xy 1.526156 -320.144157)
			(xy 1.475723 -320.093724) (xy 1.431254 -320.037962) (xy 1.393308 -319.977571) (xy 1.362363 -319.913312)
			(xy 1.338806 -319.845992) (xy 1.322936 -319.776457) (xy 1.31495 -319.705583) (xy 0.509016 -319.705583)
			(xy 0.509016 -320.705581) (xy 3.314946 -320.705581) (xy 3.314946 -320.634259) (xy 3.322932 -320.563385)
			(xy 3.338802 -320.49385) (xy 3.362359 -320.42653) (xy 3.393304 -320.362271) (xy 3.43125 -320.30188)
			(xy 3.475719 -320.246118) (xy 3.526152 -320.195685) (xy 3.581914 -320.151216) (xy 3.642305 -320.11327)
			(xy 3.706564 -320.082325) (xy 3.773884 -320.058768) (xy 3.843419 -320.042898) (xy 3.914293 -320.034912)
			(xy 3.949954 -320.034412) (xy 3.985615 -320.034912) (xy 4.056489 -320.042898) (xy 4.126024 -320.058768)
			(xy 4.193344 -320.082325) (xy 4.257603 -320.11327) (xy 4.317994 -320.151216) (xy 4.373756 -320.195685)
			(xy 4.424189 -320.246118) (xy 4.468658 -320.30188) (xy 4.506604 -320.362271) (xy 4.537549 -320.42653)
			(xy 4.561106 -320.49385) (xy 4.576976 -320.563385) (xy 4.584962 -320.634259) (xy 4.584962 -320.705581)
			(xy 4.576976 -320.776455) (xy 4.561106 -320.84599) (xy 4.537549 -320.91331) (xy 4.506604 -320.977569)
			(xy 4.468658 -321.03796) (xy 4.424189 -321.093722) (xy 4.373756 -321.144155) (xy 4.317994 -321.188624)
			(xy 4.257603 -321.22657) (xy 4.193344 -321.257515) (xy 4.126024 -321.281072) (xy 4.056489 -321.296942)
			(xy 3.985615 -321.304928) (xy 3.914293 -321.304928) (xy 3.843419 -321.296942) (xy 3.773884 -321.281072)
			(xy 3.706564 -321.257515) (xy 3.642305 -321.22657) (xy 3.581914 -321.188624) (xy 3.526152 -321.144155)
			(xy 3.475719 -321.093722) (xy 3.43125 -321.03796) (xy 3.393304 -320.977569) (xy 3.362359 -320.91331)
			(xy 3.338802 -320.84599) (xy 3.322932 -320.776455) (xy 3.314946 -320.705581) (xy 0.509016 -320.705581)
			(xy 0.509016 -327.705567) (xy 1.31495 -327.705567) (xy 1.31495 -327.634245) (xy 1.322936 -327.563371)
			(xy 1.338806 -327.493836) (xy 1.362363 -327.426516) (xy 1.393308 -327.362257) (xy 1.431254 -327.301866)
			(xy 1.475723 -327.246104) (xy 1.526156 -327.195671) (xy 1.581918 -327.151202) (xy 1.642309 -327.113256)
			(xy 1.706568 -327.082311) (xy 1.773888 -327.058754) (xy 1.843423 -327.042884) (xy 1.914297 -327.034898)
			(xy 1.949958 -327.034398) (xy 1.985619 -327.034898) (xy 2.056493 -327.042884) (xy 2.126028 -327.058754)
			(xy 2.193348 -327.082311) (xy 2.257607 -327.113256) (xy 2.317998 -327.151202) (xy 2.37376 -327.195671)
			(xy 2.424193 -327.246104) (xy 2.468662 -327.301866) (xy 2.506608 -327.362257) (xy 2.537553 -327.426516)
			(xy 2.56111 -327.493836) (xy 2.57698 -327.563371) (xy 2.584966 -327.634245) (xy 2.584966 -327.705567)
			(xy 2.57698 -327.776441) (xy 2.56111 -327.845976) (xy 2.537553 -327.913296) (xy 2.506608 -327.977555)
			(xy 2.468662 -328.037946) (xy 2.424193 -328.093708) (xy 2.37376 -328.144141) (xy 2.317998 -328.18861)
			(xy 2.257607 -328.226556) (xy 2.193348 -328.257501) (xy 2.126028 -328.281058) (xy 2.056493 -328.296928)
			(xy 1.985619 -328.304914) (xy 1.914297 -328.304914) (xy 1.843423 -328.296928) (xy 1.773888 -328.281058)
			(xy 1.706568 -328.257501) (xy 1.642309 -328.226556) (xy 1.581918 -328.18861) (xy 1.526156 -328.144141)
			(xy 1.475723 -328.093708) (xy 1.431254 -328.037946) (xy 1.393308 -327.977555) (xy 1.362363 -327.913296)
			(xy 1.338806 -327.845976) (xy 1.322936 -327.776441) (xy 1.31495 -327.705567) (xy 0.509016 -327.705567)
			(xy 0.509016 -329.705563) (xy 1.31495 -329.705563) (xy 1.31495 -329.634241) (xy 1.322936 -329.563367)
			(xy 1.338806 -329.493832) (xy 1.362363 -329.426512) (xy 1.393308 -329.362253) (xy 1.431254 -329.301862)
			(xy 1.475723 -329.2461) (xy 1.526156 -329.195667) (xy 1.581918 -329.151198) (xy 1.642309 -329.113252)
			(xy 1.706568 -329.082307) (xy 1.773888 -329.05875) (xy 1.843423 -329.04288) (xy 1.914297 -329.034894)
			(xy 1.949958 -329.034394) (xy 1.985619 -329.034894) (xy 2.056493 -329.04288) (xy 2.126028 -329.05875)
			(xy 2.193348 -329.082307) (xy 2.257607 -329.113252) (xy 2.317998 -329.151198) (xy 2.37376 -329.195667)
			(xy 2.424193 -329.2461) (xy 2.468662 -329.301862) (xy 2.506608 -329.362253) (xy 2.537553 -329.426512)
			(xy 2.56111 -329.493832) (xy 2.57698 -329.563367) (xy 2.584966 -329.634241) (xy 2.584966 -329.705563)
			(xy 2.57698 -329.776437) (xy 2.56111 -329.845972) (xy 2.537553 -329.913292) (xy 2.506608 -329.977551)
			(xy 2.468662 -330.037942) (xy 2.424193 -330.093704) (xy 2.37376 -330.144137) (xy 2.317998 -330.188606)
			(xy 2.257607 -330.226552) (xy 2.193348 -330.257497) (xy 2.126028 -330.281054) (xy 2.056493 -330.296924)
			(xy 1.985619 -330.30491) (xy 1.914297 -330.30491) (xy 1.843423 -330.296924) (xy 1.773888 -330.281054)
			(xy 1.706568 -330.257497) (xy 1.642309 -330.226552) (xy 1.581918 -330.188606) (xy 1.526156 -330.144137)
			(xy 1.475723 -330.093704) (xy 1.431254 -330.037942) (xy 1.393308 -329.977551) (xy 1.362363 -329.913292)
			(xy 1.338806 -329.845972) (xy 1.322936 -329.776437) (xy 1.31495 -329.705563) (xy 0.509016 -329.705563)
			(xy 0.509016 -330.705561) (xy 3.314946 -330.705561) (xy 3.314946 -330.634239) (xy 3.322932 -330.563365)
			(xy 3.338802 -330.49383) (xy 3.362359 -330.42651) (xy 3.393304 -330.362251) (xy 3.43125 -330.30186)
			(xy 3.475719 -330.246098) (xy 3.526152 -330.195665) (xy 3.581914 -330.151196) (xy 3.642305 -330.11325)
			(xy 3.706564 -330.082305) (xy 3.773884 -330.058748) (xy 3.843419 -330.042878) (xy 3.914293 -330.034892)
			(xy 3.949954 -330.034392) (xy 3.985615 -330.034892) (xy 4.056489 -330.042878) (xy 4.126024 -330.058748)
			(xy 4.193344 -330.082305) (xy 4.257603 -330.11325) (xy 4.317994 -330.151196) (xy 4.373756 -330.195665)
			(xy 4.424189 -330.246098) (xy 4.468658 -330.30186) (xy 4.506604 -330.362251) (xy 4.537549 -330.42651)
			(xy 4.561106 -330.49383) (xy 4.576976 -330.563365) (xy 4.584962 -330.634239) (xy 4.584962 -330.705561)
			(xy 4.576976 -330.776435) (xy 4.561106 -330.84597) (xy 4.537549 -330.91329) (xy 4.506604 -330.977549)
			(xy 4.468658 -331.03794) (xy 4.424189 -331.093702) (xy 4.373756 -331.144135) (xy 4.317994 -331.188604)
			(xy 4.257603 -331.22655) (xy 4.193344 -331.257495) (xy 4.126024 -331.281052) (xy 4.056489 -331.296922)
			(xy 3.985615 -331.304908) (xy 3.914293 -331.304908) (xy 3.843419 -331.296922) (xy 3.773884 -331.281052)
			(xy 3.706564 -331.257495) (xy 3.642305 -331.22655) (xy 3.581914 -331.188604) (xy 3.526152 -331.144135)
			(xy 3.475719 -331.093702) (xy 3.43125 -331.03794) (xy 3.393304 -330.977549) (xy 3.362359 -330.91329)
			(xy 3.338802 -330.84597) (xy 3.322932 -330.776435) (xy 3.314946 -330.705561) (xy 0.509016 -330.705561)
			(xy 0.509016 -331.705559) (xy 1.31495 -331.705559) (xy 1.31495 -331.634237) (xy 1.322936 -331.563363)
			(xy 1.338806 -331.493828) (xy 1.362363 -331.426508) (xy 1.393308 -331.362249) (xy 1.431254 -331.301858)
			(xy 1.475723 -331.246096) (xy 1.526156 -331.195663) (xy 1.581918 -331.151194) (xy 1.642309 -331.113248)
			(xy 1.706568 -331.082303) (xy 1.773888 -331.058746) (xy 1.843423 -331.042876) (xy 1.914297 -331.03489)
			(xy 1.949958 -331.03439) (xy 1.985619 -331.03489) (xy 2.056493 -331.042876) (xy 2.126028 -331.058746)
			(xy 2.193348 -331.082303) (xy 2.257607 -331.113248) (xy 2.317998 -331.151194) (xy 2.37376 -331.195663)
			(xy 2.424193 -331.246096) (xy 2.468662 -331.301858) (xy 2.506608 -331.362249) (xy 2.537553 -331.426508)
			(xy 2.56111 -331.493828) (xy 2.57698 -331.563363) (xy 2.584966 -331.634237) (xy 2.584966 -331.705559)
			(xy 2.57698 -331.776433) (xy 2.56111 -331.845968) (xy 2.537553 -331.913288) (xy 2.506608 -331.977547)
			(xy 2.468662 -332.037938) (xy 2.424193 -332.0937) (xy 2.37376 -332.144133) (xy 2.317998 -332.188602)
			(xy 2.257607 -332.226548) (xy 2.193348 -332.257493) (xy 2.126028 -332.28105) (xy 2.056493 -332.29692)
			(xy 1.985619 -332.304906) (xy 1.914297 -332.304906) (xy 1.843423 -332.29692) (xy 1.773888 -332.28105)
			(xy 1.706568 -332.257493) (xy 1.642309 -332.226548) (xy 1.581918 -332.188602) (xy 1.526156 -332.144133)
			(xy 1.475723 -332.0937) (xy 1.431254 -332.037938) (xy 1.393308 -331.977547) (xy 1.362363 -331.913288)
			(xy 1.338806 -331.845968) (xy 1.322936 -331.776433) (xy 1.31495 -331.705559) (xy 0.509016 -331.705559)
			(xy 0.509016 -332.705557) (xy 3.314946 -332.705557) (xy 3.314946 -332.634235) (xy 3.322932 -332.563361)
			(xy 3.338802 -332.493826) (xy 3.362359 -332.426506) (xy 3.393304 -332.362247) (xy 3.43125 -332.301856)
			(xy 3.475719 -332.246094) (xy 3.526152 -332.195661) (xy 3.581914 -332.151192) (xy 3.642305 -332.113246)
			(xy 3.706564 -332.082301) (xy 3.773884 -332.058744) (xy 3.843419 -332.042874) (xy 3.914293 -332.034888)
			(xy 3.949954 -332.034388) (xy 3.985615 -332.034888) (xy 4.056489 -332.042874) (xy 4.126024 -332.058744)
			(xy 4.193344 -332.082301) (xy 4.257603 -332.113246) (xy 4.317994 -332.151192) (xy 4.373756 -332.195661)
			(xy 4.424189 -332.246094) (xy 4.468658 -332.301856) (xy 4.506604 -332.362247) (xy 4.537549 -332.426506)
			(xy 4.561106 -332.493826) (xy 4.576976 -332.563361) (xy 4.584962 -332.634235) (xy 4.584962 -332.705557)
			(xy 5.814814 -332.705557) (xy 5.814814 -332.634235) (xy 5.8228 -332.563361) (xy 5.83867 -332.493826)
			(xy 5.862227 -332.426506) (xy 5.893172 -332.362247) (xy 5.931118 -332.301856) (xy 5.975587 -332.246094)
			(xy 6.02602 -332.195661) (xy 6.081782 -332.151192) (xy 6.142173 -332.113246) (xy 6.206432 -332.082301)
			(xy 6.273752 -332.058744) (xy 6.343287 -332.042874) (xy 6.414161 -332.034888) (xy 6.449822 -332.034388)
			(xy 6.485483 -332.034888) (xy 6.556357 -332.042874) (xy 6.625892 -332.058744) (xy 6.693212 -332.082301)
			(xy 6.757471 -332.113246) (xy 6.817862 -332.151192) (xy 6.873624 -332.195661) (xy 6.924057 -332.246094)
			(xy 6.968526 -332.301856) (xy 7.006472 -332.362247) (xy 7.037417 -332.426506) (xy 7.060974 -332.493826)
			(xy 7.076844 -332.563361) (xy 7.08483 -332.634235) (xy 7.08483 -332.705557) (xy 7.076844 -332.776431)
			(xy 7.060974 -332.845966) (xy 7.037417 -332.913286) (xy 7.006472 -332.977545) (xy 6.968526 -333.037936)
			(xy 6.924057 -333.093698) (xy 6.873624 -333.144131) (xy 6.817862 -333.1886) (xy 6.757471 -333.226546)
			(xy 6.693212 -333.257491) (xy 6.625892 -333.281048) (xy 6.556357 -333.296918) (xy 6.485483 -333.304904)
			(xy 6.414161 -333.304904) (xy 6.343287 -333.296918) (xy 6.273752 -333.281048) (xy 6.206432 -333.257491)
			(xy 6.142173 -333.226546) (xy 6.081782 -333.1886) (xy 6.02602 -333.144131) (xy 5.975587 -333.093698)
			(xy 5.931118 -333.037936) (xy 5.893172 -332.977545) (xy 5.862227 -332.913286) (xy 5.83867 -332.845966)
			(xy 5.8228 -332.776431) (xy 5.814814 -332.705557) (xy 4.584962 -332.705557) (xy 4.576976 -332.776431)
			(xy 4.561106 -332.845966) (xy 4.537549 -332.913286) (xy 4.506604 -332.977545) (xy 4.468658 -333.037936)
			(xy 4.424189 -333.093698) (xy 4.373756 -333.144131) (xy 4.317994 -333.1886) (xy 4.257603 -333.226546)
			(xy 4.193344 -333.257491) (xy 4.126024 -333.281048) (xy 4.056489 -333.296918) (xy 3.985615 -333.304904)
			(xy 3.914293 -333.304904) (xy 3.843419 -333.296918) (xy 3.773884 -333.281048) (xy 3.706564 -333.257491)
			(xy 3.642305 -333.226546) (xy 3.581914 -333.1886) (xy 3.526152 -333.144131) (xy 3.475719 -333.093698)
			(xy 3.43125 -333.037936) (xy 3.393304 -332.977545) (xy 3.362359 -332.913286) (xy 3.338802 -332.845966)
			(xy 3.322932 -332.776431) (xy 3.314946 -332.705557) (xy 0.509016 -332.705557) (xy 0.509016 -334.705553)
			(xy 3.314946 -334.705553) (xy 3.314946 -334.634231) (xy 3.322932 -334.563357) (xy 3.338802 -334.493822)
			(xy 3.362359 -334.426502) (xy 3.393304 -334.362243) (xy 3.43125 -334.301852) (xy 3.475719 -334.24609)
			(xy 3.526152 -334.195657) (xy 3.581914 -334.151188) (xy 3.642305 -334.113242) (xy 3.706564 -334.082297)
			(xy 3.773884 -334.05874) (xy 3.843419 -334.04287) (xy 3.914293 -334.034884) (xy 3.949954 -334.034384)
			(xy 3.985615 -334.034884) (xy 4.056489 -334.04287) (xy 4.126024 -334.05874) (xy 4.193344 -334.082297)
			(xy 4.257603 -334.113242) (xy 4.317994 -334.151188) (xy 4.373756 -334.195657) (xy 4.424189 -334.24609)
			(xy 4.468658 -334.301852) (xy 4.506604 -334.362243) (xy 4.537549 -334.426502) (xy 4.561106 -334.493822)
			(xy 4.576976 -334.563357) (xy 4.584962 -334.634231) (xy 4.584962 -334.705553) (xy 4.576976 -334.776427)
			(xy 4.561106 -334.845962) (xy 4.537549 -334.913282) (xy 4.506604 -334.977541) (xy 4.468658 -335.037932)
			(xy 4.424189 -335.093694) (xy 4.373756 -335.144127) (xy 4.317994 -335.188596) (xy 4.257603 -335.226542)
			(xy 4.193344 -335.257487) (xy 4.126024 -335.281044) (xy 4.056489 -335.296914) (xy 3.985615 -335.3049)
			(xy 3.914293 -335.3049) (xy 3.843419 -335.296914) (xy 3.773884 -335.281044) (xy 3.706564 -335.257487)
			(xy 3.642305 -335.226542) (xy 3.581914 -335.188596) (xy 3.526152 -335.144127) (xy 3.475719 -335.093694)
			(xy 3.43125 -335.037932) (xy 3.393304 -334.977541) (xy 3.362359 -334.913282) (xy 3.338802 -334.845962)
			(xy 3.322932 -334.776427) (xy 3.314946 -334.705553) (xy 0.509016 -334.705553) (xy 0.509016 -335.705551)
			(xy 1.31495 -335.705551) (xy 1.31495 -335.634229) (xy 1.322936 -335.563355) (xy 1.338806 -335.49382)
			(xy 1.362363 -335.4265) (xy 1.393308 -335.362241) (xy 1.431254 -335.30185) (xy 1.475723 -335.246088)
			(xy 1.526156 -335.195655) (xy 1.581918 -335.151186) (xy 1.642309 -335.11324) (xy 1.706568 -335.082295)
			(xy 1.773888 -335.058738) (xy 1.843423 -335.042868) (xy 1.914297 -335.034882) (xy 1.949958 -335.034382)
			(xy 1.985619 -335.034882) (xy 2.056493 -335.042868) (xy 2.126028 -335.058738) (xy 2.193348 -335.082295)
			(xy 2.257607 -335.11324) (xy 2.317998 -335.151186) (xy 2.37376 -335.195655) (xy 2.424193 -335.246088)
			(xy 2.468662 -335.30185) (xy 2.506608 -335.362241) (xy 2.537553 -335.4265) (xy 2.56111 -335.49382)
			(xy 2.57698 -335.563355) (xy 2.584966 -335.634229) (xy 2.584966 -335.705551) (xy 2.57698 -335.776425)
			(xy 2.56111 -335.84596) (xy 2.537553 -335.91328) (xy 2.506608 -335.977539) (xy 2.468662 -336.03793)
			(xy 2.424193 -336.093692) (xy 2.37376 -336.144125) (xy 2.317998 -336.188594) (xy 2.257607 -336.22654)
			(xy 2.193348 -336.257485) (xy 2.126028 -336.281042) (xy 2.056493 -336.296912) (xy 1.985619 -336.304898)
			(xy 1.914297 -336.304898) (xy 1.843423 -336.296912) (xy 1.773888 -336.281042) (xy 1.706568 -336.257485)
			(xy 1.642309 -336.22654) (xy 1.581918 -336.188594) (xy 1.526156 -336.144125) (xy 1.475723 -336.093692)
			(xy 1.431254 -336.03793) (xy 1.393308 -335.977539) (xy 1.362363 -335.91328) (xy 1.338806 -335.84596)
			(xy 1.322936 -335.776425) (xy 1.31495 -335.705551) (xy 0.509016 -335.705551) (xy 0.509016 -336.705549)
			(xy 3.314946 -336.705549) (xy 3.314946 -336.634227) (xy 3.322932 -336.563353) (xy 3.338802 -336.493818)
			(xy 3.362359 -336.426498) (xy 3.393304 -336.362239) (xy 3.43125 -336.301848) (xy 3.475719 -336.246086)
			(xy 3.526152 -336.195653) (xy 3.581914 -336.151184) (xy 3.642305 -336.113238) (xy 3.706564 -336.082293)
			(xy 3.773884 -336.058736) (xy 3.843419 -336.042866) (xy 3.914293 -336.03488) (xy 3.949954 -336.03438)
			(xy 3.985615 -336.03488) (xy 4.056489 -336.042866) (xy 4.126024 -336.058736) (xy 4.193344 -336.082293)
			(xy 4.257603 -336.113238) (xy 4.317994 -336.151184) (xy 4.373756 -336.195653) (xy 4.424189 -336.246086)
			(xy 4.468658 -336.301848) (xy 4.506604 -336.362239) (xy 4.537549 -336.426498) (xy 4.561106 -336.493818)
			(xy 4.576976 -336.563353) (xy 4.584962 -336.634227) (xy 4.584962 -336.705549) (xy 5.814814 -336.705549)
			(xy 5.814814 -336.634227) (xy 5.8228 -336.563353) (xy 5.83867 -336.493818) (xy 5.862227 -336.426498)
			(xy 5.893172 -336.362239) (xy 5.931118 -336.301848) (xy 5.975587 -336.246086) (xy 6.02602 -336.195653)
			(xy 6.081782 -336.151184) (xy 6.142173 -336.113238) (xy 6.206432 -336.082293) (xy 6.273752 -336.058736)
			(xy 6.343287 -336.042866) (xy 6.414161 -336.03488) (xy 6.449822 -336.03438) (xy 6.485483 -336.03488)
			(xy 6.556357 -336.042866) (xy 6.625892 -336.058736) (xy 6.693212 -336.082293) (xy 6.757471 -336.113238)
			(xy 6.817862 -336.151184) (xy 6.873624 -336.195653) (xy 6.924057 -336.246086) (xy 6.968526 -336.301848)
			(xy 7.006472 -336.362239) (xy 7.037417 -336.426498) (xy 7.060974 -336.493818) (xy 7.076844 -336.563353)
			(xy 7.08483 -336.634227) (xy 7.08483 -336.705549) (xy 7.076844 -336.776423) (xy 7.060974 -336.845958)
			(xy 7.037417 -336.913278) (xy 7.006472 -336.977537) (xy 6.968526 -337.037928) (xy 6.924057 -337.09369)
			(xy 6.873624 -337.144123) (xy 6.817862 -337.188592) (xy 6.757471 -337.226538) (xy 6.693212 -337.257483)
			(xy 6.625892 -337.28104) (xy 6.556357 -337.29691) (xy 6.485483 -337.304896) (xy 6.414161 -337.304896)
			(xy 6.343287 -337.29691) (xy 6.273752 -337.28104) (xy 6.206432 -337.257483) (xy 6.142173 -337.226538)
			(xy 6.081782 -337.188592) (xy 6.02602 -337.144123) (xy 5.975587 -337.09369) (xy 5.931118 -337.037928)
			(xy 5.893172 -336.977537) (xy 5.862227 -336.913278) (xy 5.83867 -336.845958) (xy 5.8228 -336.776423)
			(xy 5.814814 -336.705549) (xy 4.584962 -336.705549) (xy 4.576976 -336.776423) (xy 4.561106 -336.845958)
			(xy 4.537549 -336.913278) (xy 4.506604 -336.977537) (xy 4.468658 -337.037928) (xy 4.424189 -337.09369)
			(xy 4.373756 -337.144123) (xy 4.317994 -337.188592) (xy 4.257603 -337.226538) (xy 4.193344 -337.257483)
			(xy 4.126024 -337.28104) (xy 4.056489 -337.29691) (xy 3.985615 -337.304896) (xy 3.914293 -337.304896)
			(xy 3.843419 -337.29691) (xy 3.773884 -337.28104) (xy 3.706564 -337.257483) (xy 3.642305 -337.226538)
			(xy 3.581914 -337.188592) (xy 3.526152 -337.144123) (xy 3.475719 -337.09369) (xy 3.43125 -337.037928)
			(xy 3.393304 -336.977537) (xy 3.362359 -336.913278) (xy 3.338802 -336.845958) (xy 3.322932 -336.776423)
			(xy 3.314946 -336.705549) (xy 0.509016 -336.705549) (xy 0.509016 -337.705547) (xy 1.31495 -337.705547)
			(xy 1.31495 -337.634225) (xy 1.322936 -337.563351) (xy 1.338806 -337.493816) (xy 1.362363 -337.426496)
			(xy 1.393308 -337.362237) (xy 1.431254 -337.301846) (xy 1.475723 -337.246084) (xy 1.526156 -337.195651)
			(xy 1.581918 -337.151182) (xy 1.642309 -337.113236) (xy 1.706568 -337.082291) (xy 1.773888 -337.058734)
			(xy 1.843423 -337.042864) (xy 1.914297 -337.034878) (xy 1.949958 -337.034378) (xy 1.985619 -337.034878)
			(xy 2.056493 -337.042864) (xy 2.126028 -337.058734) (xy 2.193348 -337.082291) (xy 2.257607 -337.113236)
			(xy 2.317998 -337.151182) (xy 2.37376 -337.195651) (xy 2.424193 -337.246084) (xy 2.468662 -337.301846)
			(xy 2.506608 -337.362237) (xy 2.537553 -337.426496) (xy 2.56111 -337.493816) (xy 2.57698 -337.563351)
			(xy 2.584966 -337.634225) (xy 2.584966 -337.705547) (xy 2.57698 -337.776421) (xy 2.56111 -337.845956)
			(xy 2.537553 -337.913276) (xy 2.506608 -337.977535) (xy 2.468662 -338.037926) (xy 2.424193 -338.093688)
			(xy 2.37376 -338.144121) (xy 2.317998 -338.18859) (xy 2.257607 -338.226536) (xy 2.193348 -338.257481)
			(xy 2.126028 -338.281038) (xy 2.056493 -338.296908) (xy 1.985619 -338.304894) (xy 1.914297 -338.304894)
			(xy 1.843423 -338.296908) (xy 1.773888 -338.281038) (xy 1.706568 -338.257481) (xy 1.642309 -338.226536)
			(xy 1.581918 -338.18859) (xy 1.526156 -338.144121) (xy 1.475723 -338.093688) (xy 1.431254 -338.037926)
			(xy 1.393308 -337.977535) (xy 1.362363 -337.913276) (xy 1.338806 -337.845956) (xy 1.322936 -337.776421)
			(xy 1.31495 -337.705547) (xy 0.509016 -337.705547) (xy 0.509016 -338.705545) (xy 3.314946 -338.705545)
			(xy 3.314946 -338.634223) (xy 3.322932 -338.563349) (xy 3.338802 -338.493814) (xy 3.362359 -338.426494)
			(xy 3.393304 -338.362235) (xy 3.43125 -338.301844) (xy 3.475719 -338.246082) (xy 3.526152 -338.195649)
			(xy 3.581914 -338.15118) (xy 3.642305 -338.113234) (xy 3.706564 -338.082289) (xy 3.773884 -338.058732)
			(xy 3.843419 -338.042862) (xy 3.914293 -338.034876) (xy 3.949954 -338.034376) (xy 3.985615 -338.034876)
			(xy 4.056489 -338.042862) (xy 4.126024 -338.058732) (xy 4.193344 -338.082289) (xy 4.257603 -338.113234)
			(xy 4.317994 -338.15118) (xy 4.373756 -338.195649) (xy 4.424189 -338.246082) (xy 4.468658 -338.301844)
			(xy 4.506604 -338.362235) (xy 4.537549 -338.426494) (xy 4.561106 -338.493814) (xy 4.576976 -338.563349)
			(xy 4.584962 -338.634223) (xy 4.584962 -338.705545) (xy 5.814814 -338.705545) (xy 5.814814 -338.634223)
			(xy 5.8228 -338.563349) (xy 5.83867 -338.493814) (xy 5.862227 -338.426494) (xy 5.893172 -338.362235)
			(xy 5.931118 -338.301844) (xy 5.975587 -338.246082) (xy 6.02602 -338.195649) (xy 6.081782 -338.15118)
			(xy 6.142173 -338.113234) (xy 6.206432 -338.082289) (xy 6.273752 -338.058732) (xy 6.343287 -338.042862)
			(xy 6.414161 -338.034876) (xy 6.449822 -338.034376) (xy 6.485483 -338.034876) (xy 6.556357 -338.042862)
			(xy 6.625892 -338.058732) (xy 6.693212 -338.082289) (xy 6.757471 -338.113234) (xy 6.817862 -338.15118)
			(xy 6.873624 -338.195649) (xy 6.924057 -338.246082) (xy 6.968526 -338.301844) (xy 7.006472 -338.362235)
			(xy 7.037417 -338.426494) (xy 7.060974 -338.493814) (xy 7.076844 -338.563349) (xy 7.08483 -338.634223)
			(xy 7.08483 -338.705545) (xy 7.076844 -338.776419) (xy 7.060974 -338.845954) (xy 7.037417 -338.913274)
			(xy 7.006472 -338.977533) (xy 6.968526 -339.037924) (xy 6.924057 -339.093686) (xy 6.873624 -339.144119)
			(xy 6.817862 -339.188588) (xy 6.757471 -339.226534) (xy 6.693212 -339.257479) (xy 6.625892 -339.281036)
			(xy 6.556357 -339.296906) (xy 6.485483 -339.304892) (xy 6.414161 -339.304892) (xy 6.343287 -339.296906)
			(xy 6.273752 -339.281036) (xy 6.206432 -339.257479) (xy 6.142173 -339.226534) (xy 6.081782 -339.188588)
			(xy 6.02602 -339.144119) (xy 5.975587 -339.093686) (xy 5.931118 -339.037924) (xy 5.893172 -338.977533)
			(xy 5.862227 -338.913274) (xy 5.83867 -338.845954) (xy 5.8228 -338.776419) (xy 5.814814 -338.705545)
			(xy 4.584962 -338.705545) (xy 4.576976 -338.776419) (xy 4.561106 -338.845954) (xy 4.537549 -338.913274)
			(xy 4.506604 -338.977533) (xy 4.468658 -339.037924) (xy 4.424189 -339.093686) (xy 4.373756 -339.144119)
			(xy 4.317994 -339.188588) (xy 4.257603 -339.226534) (xy 4.193344 -339.257479) (xy 4.126024 -339.281036)
			(xy 4.056489 -339.296906) (xy 3.985615 -339.304892) (xy 3.914293 -339.304892) (xy 3.843419 -339.296906)
			(xy 3.773884 -339.281036) (xy 3.706564 -339.257479) (xy 3.642305 -339.226534) (xy 3.581914 -339.188588)
			(xy 3.526152 -339.144119) (xy 3.475719 -339.093686) (xy 3.43125 -339.037924) (xy 3.393304 -338.977533)
			(xy 3.362359 -338.913274) (xy 3.338802 -338.845954) (xy 3.322932 -338.776419) (xy 3.314946 -338.705545)
			(xy 0.509016 -338.705545) (xy 0.509016 -339.705543) (xy 1.31495 -339.705543) (xy 1.31495 -339.634221)
			(xy 1.322936 -339.563347) (xy 1.338806 -339.493812) (xy 1.362363 -339.426492) (xy 1.393308 -339.362233)
			(xy 1.431254 -339.301842) (xy 1.475723 -339.24608) (xy 1.526156 -339.195647) (xy 1.581918 -339.151178)
			(xy 1.642309 -339.113232) (xy 1.706568 -339.082287) (xy 1.773888 -339.05873) (xy 1.843423 -339.04286)
			(xy 1.914297 -339.034874) (xy 1.949958 -339.034374) (xy 1.985619 -339.034874) (xy 2.056493 -339.04286)
			(xy 2.126028 -339.05873) (xy 2.193348 -339.082287) (xy 2.257607 -339.113232) (xy 2.317998 -339.151178)
			(xy 2.37376 -339.195647) (xy 2.424193 -339.24608) (xy 2.468662 -339.301842) (xy 2.506608 -339.362233)
			(xy 2.537553 -339.426492) (xy 2.56111 -339.493812) (xy 2.57698 -339.563347) (xy 2.584966 -339.634221)
			(xy 2.584966 -339.705543) (xy 2.57698 -339.776417) (xy 2.56111 -339.845952) (xy 2.537553 -339.913272)
			(xy 2.506608 -339.977531) (xy 2.468662 -340.037922) (xy 2.424193 -340.093684) (xy 2.37376 -340.144117)
			(xy 2.317998 -340.188586) (xy 2.257607 -340.226532) (xy 2.193348 -340.257477) (xy 2.126028 -340.281034)
			(xy 2.056493 -340.296904) (xy 1.985619 -340.30489) (xy 1.914297 -340.30489) (xy 1.843423 -340.296904)
			(xy 1.773888 -340.281034) (xy 1.706568 -340.257477) (xy 1.642309 -340.226532) (xy 1.581918 -340.188586)
			(xy 1.526156 -340.144117) (xy 1.475723 -340.093684) (xy 1.431254 -340.037922) (xy 1.393308 -339.977531)
			(xy 1.362363 -339.913272) (xy 1.338806 -339.845952) (xy 1.322936 -339.776417) (xy 1.31495 -339.705543)
			(xy 0.509016 -339.705543) (xy 0.509016 -342.652033) (xy 3.314157 -342.652033) (xy 3.32012 -342.581187)
			(xy 3.333954 -342.511448) (xy 3.355484 -342.44369) (xy 3.384443 -342.378758) (xy 3.420469 -342.317464)
			(xy 3.46311 -342.260574) (xy 3.511835 -342.208799) (xy 3.566034 -342.162786) (xy 3.62503 -342.12311)
			(xy 3.65633 -342.10625) (xy 3.675751 -342.095588) (xy 3.710895 -342.068619) (xy 3.740831 -342.035964)
			(xy 3.764651 -341.998614) (xy 3.781635 -341.957699) (xy 3.791266 -341.914459) (xy 3.793255 -341.870204)
			(xy 3.78754 -341.826274) (xy 3.774295 -341.784001) (xy 3.764534 -341.764112) (xy 3.739522 -341.714851)
			(xy 3.695492 -341.613513) (xy 3.658484 -341.509405) (xy 3.628672 -341.403013) (xy 3.606195 -341.294833)
			(xy 3.591158 -341.185371) (xy 3.583631 -341.075137) (xy 3.583178 -341.019892) (xy 3.583683 -340.962517)
			(xy 3.591825 -340.848057) (xy 3.608063 -340.734463) (xy 3.632316 -340.622306) (xy 3.664462 -340.512151)
			(xy 3.704339 -340.404554) (xy 3.751746 -340.300055) (xy 3.806444 -340.199181) (xy 3.868157 -340.10244)
			(xy 3.936576 -340.010319) (xy 4.011356 -339.923282) (xy 4.092119 -339.841768) (xy 4.17846 -339.766186)
			(xy 4.269943 -339.696917) (xy 4.366108 -339.63431) (xy 4.466471 -339.57868) (xy 4.570527 -339.530308)
			(xy 4.67775 -339.489436) (xy 4.787603 -339.456272) (xy 4.89953 -339.430981) (xy 5.012969 -339.413691)
			(xy 5.127349 -339.40449) (xy 5.242093 -339.403423) (xy 5.356624 -339.410496) (xy 5.470366 -339.425673)
			(xy 5.582744 -339.448878) (xy 5.693194 -339.479993) (xy 5.801159 -339.518864) (xy 5.906096 -339.565292)
			(xy 6.007476 -339.619046) (xy 6.104789 -339.679854) (xy 6.197545 -339.747409) (xy 6.285277 -339.821373)
			(xy 6.367542 -339.901371) (xy 6.443927 -339.987003) (xy 6.514047 -340.077835) (xy 6.577549 -340.173412)
			(xy 6.634114 -340.273251) (xy 6.683456 -340.37685) (xy 6.725326 -340.483687) (xy 6.759515 -340.593225)
			(xy 6.78585 -340.704911) (xy 6.804198 -340.818184) (xy 6.814468 -340.932473) (xy 6.816606 -341.047202)
			(xy 6.810603 -341.161795) (xy 6.796489 -341.275672) (xy 6.774334 -341.388263) (xy 6.744251 -341.498998)
			(xy 6.706391 -341.607322) (xy 6.660944 -341.712688) (xy 6.634988 -341.763858) (xy 6.625193 -341.783747)
			(xy 6.611932 -341.826049) (xy 6.606207 -341.87001) (xy 6.608191 -341.914297) (xy 6.617823 -341.95757)
			(xy 6.634812 -341.998517) (xy 6.658643 -342.035899) (xy 6.688594 -342.068583) (xy 6.723758 -342.095579)
			(xy 6.743192 -342.10625) (xy 6.774485 -342.123119) (xy 6.833489 -342.162778) (xy 6.887697 -342.208775)
			(xy 6.936433 -342.260536) (xy 6.979086 -342.317413) (xy 7.015123 -342.378696) (xy 7.044095 -342.443618)
			(xy 7.065639 -342.511368) (xy 7.079486 -342.5811) (xy 7.085463 -342.651942) (xy 7.083495 -342.723008)
			(xy 7.073607 -342.793411) (xy 7.055922 -342.86227) (xy 7.030662 -342.928724) (xy 6.998141 -342.991944)
			(xy 6.958768 -343.051138) (xy 6.913032 -343.105568) (xy 6.861507 -343.154552) (xy 6.804837 -343.197479)
			(xy 6.743729 -343.233812) (xy 6.678947 -343.263097) (xy 6.611301 -343.284967) (xy 6.541637 -343.299151)
			(xy 6.470825 -343.305469) (xy 6.39975 -343.303844) (xy 6.3293 -343.294296) (xy 6.260357 -343.276943)
			(xy 6.193781 -343.252004) (xy 6.130406 -343.219789) (xy 6.071022 -343.180701) (xy 6.016373 -343.135229)
			(xy 5.96714 -343.083941) (xy 5.92394 -343.027478) (xy 5.887313 -342.966546) (xy 5.857716 -342.901906)
			(xy 5.835519 -342.834367) (xy 5.827776 -342.79967) (xy 5.822798 -342.778068) (xy 5.806347 -342.736906)
			(xy 5.783004 -342.699222) (xy 5.753478 -342.66616) (xy 5.718664 -342.63872) (xy 5.679617 -342.617737)
			(xy 5.637523 -342.603845) (xy 5.593656 -342.597466) (xy 5.549349 -342.598794) (xy 5.527548 -342.60282)
			(xy 5.473606 -342.613548) (xy 5.364635 -342.628518) (xy 5.254898 -342.636041) (xy 5.144904 -342.636082)
			(xy 5.035162 -342.628641) (xy 4.92618 -342.613752) (xy 4.872228 -342.603074) (xy 4.850439 -342.599028)
			(xy 4.806148 -342.597667) (xy 4.762293 -342.604013) (xy 4.720204 -342.617873) (xy 4.681159 -342.638827)
			(xy 4.646344 -342.666239) (xy 4.616813 -342.699278) (xy 4.593465 -342.736939) (xy 4.577006 -342.778082)
			(xy 4.572 -342.79967) (xy 4.564252 -342.834367) (xy 4.542053 -342.90191) (xy 4.512454 -342.966552)
			(xy 4.475825 -343.027487) (xy 4.432624 -343.083953) (xy 4.38339 -343.135245) (xy 4.328739 -343.18072)
			(xy 4.269354 -343.219812) (xy 4.205977 -343.252031) (xy 4.139399 -343.276976) (xy 4.070454 -343.294333)
			(xy 4.000002 -343.303887) (xy 3.928924 -343.305517) (xy 3.858108 -343.299204) (xy 3.788439 -343.285026)
			(xy 3.720787 -343.263161) (xy 3.655999 -343.233882) (xy 3.594884 -343.197555) (xy 3.538206 -343.154633)
			(xy 3.486672 -343.105653) (xy 3.440927 -343.051227) (xy 3.401542 -342.992036) (xy 3.36901 -342.928818)
			(xy 3.343738 -342.862365) (xy 3.32604 -342.793506) (xy 3.316139 -342.723102) (xy 3.314157 -342.652033)
			(xy 0.509016 -342.652033) (xy 0.509016 -343.705535) (xy 1.31495 -343.705535) (xy 1.31495 -343.634213)
			(xy 1.322936 -343.563339) (xy 1.338806 -343.493804) (xy 1.362363 -343.426484) (xy 1.393308 -343.362225)
			(xy 1.431254 -343.301834) (xy 1.475723 -343.246072) (xy 1.526156 -343.195639) (xy 1.581918 -343.15117)
			(xy 1.642309 -343.113224) (xy 1.706568 -343.082279) (xy 1.773888 -343.058722) (xy 1.843423 -343.042852)
			(xy 1.914297 -343.034866) (xy 1.949958 -343.034366) (xy 1.985619 -343.034866) (xy 2.056493 -343.042852)
			(xy 2.126028 -343.058722) (xy 2.193348 -343.082279) (xy 2.257607 -343.113224) (xy 2.317998 -343.15117)
			(xy 2.37376 -343.195639) (xy 2.424193 -343.246072) (xy 2.468662 -343.301834) (xy 2.506608 -343.362225)
			(xy 2.537553 -343.426484) (xy 2.56111 -343.493804) (xy 2.57698 -343.563339) (xy 2.584966 -343.634213)
			(xy 2.584966 -343.705535) (xy 2.57698 -343.776409) (xy 2.56111 -343.845944) (xy 2.537553 -343.913264)
			(xy 2.506608 -343.977523) (xy 2.468662 -344.037914) (xy 2.424193 -344.093676) (xy 2.37376 -344.144109)
			(xy 2.317998 -344.188578) (xy 2.257607 -344.226524) (xy 2.193348 -344.257469) (xy 2.126028 -344.281026)
			(xy 2.056493 -344.296896) (xy 1.985619 -344.304882) (xy 1.914297 -344.304882) (xy 1.843423 -344.296896)
			(xy 1.773888 -344.281026) (xy 1.706568 -344.257469) (xy 1.642309 -344.226524) (xy 1.581918 -344.188578)
			(xy 1.526156 -344.144109) (xy 1.475723 -344.093676) (xy 1.431254 -344.037914) (xy 1.393308 -343.977523)
			(xy 1.362363 -343.913264) (xy 1.338806 -343.845944) (xy 1.322936 -343.776409) (xy 1.31495 -343.705535)
			(xy 0.509016 -343.705535) (xy 0.509016 -345.604338) (xy 1.153668 -346.24899) (xy 2.39014 -346.24899)
			(xy 2.891282 -345.747848) (xy 4.361688 -345.747848) (xy 5.548122 -344.561414) (xy 5.724652 -344.561414)
			(xy 5.843778 -344.474546) (xy 5.85724 -344.439748) (xy 5.870549 -344.406824) (xy 5.903471 -344.343899)
			(xy 5.943203 -344.285035) (xy 5.989247 -344.230967) (xy 6.041032 -344.182368) (xy 6.097911 -344.139844)
			(xy 6.159175 -344.103926) (xy 6.224062 -344.07506) (xy 6.291761 -344.053606) (xy 6.36143 -344.039833)
			(xy 6.4322 -344.03391) (xy 6.50319 -344.035913) (xy 6.573513 -344.045817) (xy 6.642295 -344.063497)
			(xy 6.708677 -344.088734) (xy 6.771832 -344.121213) (xy 6.830974 -344.16053) (xy 6.885364 -344.206193)
			(xy 6.934326 -344.257635) (xy 6.977248 -344.314213) (xy 7.013597 -344.375224) (xy 7.042918 -344.439905)
			(xy 7.054342 -344.47353) (xy 7.067042 -344.5129) (xy 7.133844 -344.561414) (xy 9.06272 -344.561414)
			(xy 9.077091 -344.56103) (xy 9.105101 -344.55458) (xy 9.130951 -344.542012) (xy 9.153323 -344.523967)
			(xy 9.17108 -344.501365) (xy 9.177528 -344.488516) (xy 9.177528 -344.337386) (xy 9.170018 -344.315598)
			(xy 9.148269 -344.274971) (xy 9.119551 -344.238932) (xy 9.084805 -344.208663) (xy 9.04517 -344.185156)
			(xy 9.001945 -344.169182) (xy 8.956549 -344.161264) (xy 8.910469 -344.161663) (xy 8.865216 -344.170364)
			(xy 8.822275 -344.187083) (xy 8.80237 -344.198702) (xy 8.772037 -344.218314) (xy 8.707779 -344.25131)
			(xy 8.640194 -344.276807) (xy 8.570154 -344.294477) (xy 8.498562 -344.304093) (xy 8.426342 -344.30553)
			(xy 8.354424 -344.298769) (xy 8.283737 -344.283899) (xy 8.215191 -344.26111) (xy 8.149672 -344.230696)
			(xy 8.088022 -344.19305) (xy 8.031039 -344.148657) (xy 7.979456 -344.09809) (xy 7.933939 -344.042001)
			(xy 7.895074 -343.981112) (xy 7.863364 -343.91621) (xy 7.839216 -343.848132) (xy 7.822942 -343.777754)
			(xy 7.814753 -343.705985) (xy 7.814753 -343.63375) (xy 7.822943 -343.561982) (xy 7.839217 -343.491604)
			(xy 7.863365 -343.423526) (xy 7.895076 -343.358624) (xy 7.933941 -343.297736) (xy 7.979459 -343.241647)
			(xy 8.031042 -343.19108) (xy 8.088026 -343.146687) (xy 8.149676 -343.109042) (xy 8.215196 -343.078629)
			(xy 8.283741 -343.05584) (xy 8.354429 -343.04097) (xy 8.426346 -343.03421) (xy 8.498567 -343.035647)
			(xy 8.570158 -343.045263) (xy 8.640198 -343.062934) (xy 8.707783 -343.088432) (xy 8.772041 -343.121428)
			(xy 8.80237 -343.141046) (xy 8.822245 -343.152722) (xy 8.865192 -343.169454) (xy 8.910453 -343.178164)
			(xy 8.956542 -343.178564) (xy 9.001947 -343.170643) (xy 9.045178 -343.15466) (xy 9.084816 -343.13114)
			(xy 9.119561 -343.100854) (xy 9.148271 -343.064796) (xy 9.170004 -343.024151) (xy 9.177528 -343.002362)
			(xy 9.177528 -340.337394) (xy 9.170018 -340.315605) (xy 9.14827 -340.274977) (xy 9.119553 -340.238938)
			(xy 9.084806 -340.208667) (xy 9.045171 -340.185159) (xy 9.001946 -340.169185) (xy 8.956549 -340.161267)
			(xy 8.910468 -340.161665) (xy 8.865215 -340.170367) (xy 8.822273 -340.187087) (xy 8.80237 -340.19871)
			(xy 8.772037 -340.218322) (xy 8.707779 -340.251318) (xy 8.640194 -340.276815) (xy 8.570155 -340.294486)
			(xy 8.498563 -340.304101) (xy 8.426343 -340.305538) (xy 8.354426 -340.298778) (xy 8.283739 -340.283907)
			(xy 8.215193 -340.261118) (xy 8.149673 -340.230705) (xy 8.088024 -340.193059) (xy 8.031041 -340.148667)
			(xy 7.979458 -340.0981) (xy 7.933941 -340.042011) (xy 7.895076 -339.981123) (xy 7.863365 -339.916221)
			(xy 7.839218 -339.848142) (xy 7.822944 -339.777765) (xy 7.814754 -339.705996) (xy 7.814755 -339.633762)
			(xy 7.822944 -339.561993) (xy 7.839218 -339.491616) (xy 7.863366 -339.423537) (xy 7.895077 -339.358636)
			(xy 7.933942 -339.297748) (xy 7.979459 -339.241659) (xy 8.031043 -339.191092) (xy 8.088026 -339.146699)
			(xy 8.149675 -339.109054) (xy 8.215195 -339.078641) (xy 8.283741 -339.055852) (xy 8.354428 -339.040982)
			(xy 8.426345 -339.034222) (xy 8.498565 -339.035659) (xy 8.570157 -339.045275) (xy 8.640197 -339.062946)
			(xy 8.707781 -339.088443) (xy 8.772039 -339.121439) (xy 8.80237 -339.141054) (xy 8.822245 -339.15273)
			(xy 8.865192 -339.169461) (xy 8.910453 -339.178171) (xy 8.956543 -339.178571) (xy 9.001948 -339.17065)
			(xy 9.045179 -339.154667) (xy 9.084818 -339.131147) (xy 9.119562 -339.100862) (xy 9.148273 -339.064805)
			(xy 9.170007 -339.02416) (xy 9.177528 -339.00237) (xy 9.177528 -338.337398) (xy 9.170019 -338.315609)
			(xy 9.148271 -338.27498) (xy 9.119553 -338.23894) (xy 9.084807 -338.208669) (xy 9.045171 -338.185161)
			(xy 9.001946 -338.169186) (xy 8.956549 -338.161268) (xy 8.910468 -338.161666) (xy 8.865214 -338.170369)
			(xy 8.822271 -338.187089) (xy 8.80237 -338.198714) (xy 8.772038 -338.218326) (xy 8.70778 -338.251322)
			(xy 8.640196 -338.276819) (xy 8.570157 -338.29449) (xy 8.498566 -338.304106) (xy 8.426347 -338.305543)
			(xy 8.35443 -338.298783) (xy 8.283743 -338.283913) (xy 8.215198 -338.261125) (xy 8.149679 -338.230712)
			(xy 8.08803 -338.193067) (xy 8.031047 -338.148675) (xy 7.979464 -338.098109) (xy 7.933947 -338.04202)
			(xy 7.895082 -337.981133) (xy 7.863371 -337.916232) (xy 7.839223 -337.848154) (xy 7.822949 -337.777777)
			(xy 7.81476 -337.706009) (xy 7.814759 -337.633775) (xy 7.822949 -337.562007) (xy 7.839222 -337.49163)
			(xy 7.86337 -337.423552) (xy 7.89508 -337.358651) (xy 7.933944 -337.297763) (xy 7.979461 -337.241674)
			(xy 8.031043 -337.191108) (xy 8.088026 -337.146715) (xy 8.149675 -337.10907) (xy 8.215194 -337.078657)
			(xy 8.283739 -337.055868) (xy 8.354425 -337.040997) (xy 8.426342 -337.034237) (xy 8.498562 -337.035674)
			(xy 8.570153 -337.045289) (xy 8.640192 -337.062959) (xy 8.707776 -337.088456) (xy 8.772034 -337.121452)
			(xy 8.80237 -337.141058) (xy 8.822245 -337.152733) (xy 8.865193 -337.169465) (xy 8.910453 -337.178174)
			(xy 8.956543 -337.178575) (xy 9.001948 -337.170653) (xy 9.04518 -337.154671) (xy 9.084818 -337.131151)
			(xy 9.119563 -337.100866) (xy 9.148274 -337.064809) (xy 9.170009 -337.024165) (xy 9.177528 -337.002374)
			(xy 9.177528 -336.337402) (xy 9.170019 -336.315613) (xy 9.148272 -336.274984) (xy 9.119554 -336.238943)
			(xy 9.084808 -336.208671) (xy 9.045172 -336.185163) (xy 9.001946 -336.169187) (xy 8.956549 -336.161269)
			(xy 8.910467 -336.161668) (xy 8.865213 -336.17037) (xy 8.82227 -336.187091) (xy 8.80237 -336.198718)
			(xy 8.772037 -336.21833) (xy 8.707779 -336.251326) (xy 8.640195 -336.276823) (xy 8.570156 -336.294494)
			(xy 8.498564 -336.30411) (xy 8.426344 -336.305547) (xy 8.354427 -336.298786) (xy 8.28374 -336.283916)
			(xy 8.215195 -336.261127) (xy 8.149675 -336.230714) (xy 8.088026 -336.193069) (xy 8.031043 -336.148676)
			(xy 7.97946 -336.098109) (xy 7.933943 -336.042021) (xy 7.895078 -335.981133) (xy 7.863367 -335.916231)
			(xy 7.83922 -335.848153) (xy 7.822946 -335.777776) (xy 7.814756 -335.706007) (xy 7.814756 -335.633773)
			(xy 7.822946 -335.562004) (xy 7.83922 -335.491627) (xy 7.863367 -335.423549) (xy 7.895078 -335.358647)
			(xy 7.933943 -335.297759) (xy 7.97946 -335.241671) (xy 8.031043 -335.191104) (xy 8.088026 -335.146711)
			(xy 8.149675 -335.109066) (xy 8.215195 -335.078653) (xy 8.28374 -335.055864) (xy 8.354427 -335.040994)
			(xy 8.426344 -335.034233) (xy 8.498564 -335.03567) (xy 8.570156 -335.045286) (xy 8.640195 -335.062957)
			(xy 8.707779 -335.088454) (xy 8.772037 -335.12145) (xy 8.80237 -335.141062) (xy 8.822246 -335.152737)
			(xy 8.865193 -335.169469) (xy 8.910454 -335.178177) (xy 8.956543 -335.178578) (xy 9.001949 -335.170657)
			(xy 9.04518 -335.154674) (xy 9.084819 -335.131155) (xy 9.119564 -335.10087) (xy 9.148275 -335.064814)
			(xy 9.170011 -335.024169) (xy 9.177528 -335.002378) (xy 9.177528 -334.337406) (xy 9.170019 -334.315616)
			(xy 9.148272 -334.274987) (xy 9.119555 -334.238945) (xy 9.084808 -334.208673) (xy 9.045172 -334.185164)
			(xy 9.001947 -334.169189) (xy 8.956548 -334.16127) (xy 8.910467 -334.161669) (xy 8.865212 -334.170372)
			(xy 8.822269 -334.187093) (xy 8.80237 -334.198722) (xy 8.772037 -334.218334) (xy 8.707779 -334.25133)
			(xy 8.640194 -334.276827) (xy 8.570154 -334.294497) (xy 8.498562 -334.304113) (xy 8.426342 -334.30555)
			(xy 8.354424 -334.298789) (xy 8.283737 -334.283919) (xy 8.215191 -334.26113) (xy 8.149672 -334.230716)
			(xy 8.088022 -334.19307) (xy 8.031039 -334.148677) (xy 7.979456 -334.09811) (xy 7.933939 -334.042021)
			(xy 7.895074 -333.981132) (xy 7.863364 -333.91623) (xy 7.839216 -333.848152) (xy 7.822942 -333.777774)
			(xy 7.814753 -333.706005) (xy 7.814753 -333.63377) (xy 7.822943 -333.562002) (xy 7.839217 -333.491624)
			(xy 7.863365 -333.423546) (xy 7.895076 -333.358644) (xy 7.933941 -333.297756) (xy 7.979459 -333.241667)
			(xy 8.031042 -333.1911) (xy 8.088026 -333.146707) (xy 8.149676 -333.109062) (xy 8.215196 -333.078649)
			(xy 8.283741 -333.05586) (xy 8.354429 -333.04099) (xy 8.426346 -333.03423) (xy 8.498567 -333.035667)
			(xy 8.570158 -333.045283) (xy 8.640198 -333.062954) (xy 8.707783 -333.088452) (xy 8.772041 -333.121448)
			(xy 8.80237 -333.141066) (xy 8.822246 -333.152741) (xy 8.865193 -333.169472) (xy 8.910454 -333.178181)
			(xy 8.956544 -333.178581) (xy 9.001949 -333.17066) (xy 9.045181 -333.154678) (xy 9.084819 -333.131159)
			(xy 9.119565 -333.100874) (xy 9.148277 -333.064818) (xy 9.170013 -333.024174) (xy 9.177528 -333.002382)
			(xy 9.177528 -332.33741) (xy 9.170019 -332.31562) (xy 9.148273 -332.27499) (xy 9.119555 -332.238948)
			(xy 9.084809 -332.208675) (xy 9.045173 -332.185166) (xy 9.001947 -332.16919) (xy 8.956548 -332.161272)
			(xy 8.910466 -332.16167) (xy 8.865211 -332.170373) (xy 8.822268 -332.187095) (xy 8.80237 -332.198726)
			(xy 8.772194 -332.218265) (xy 8.708274 -332.251168) (xy 8.641049 -332.276647) (xy 8.571378 -332.294377)
			(xy 8.500152 -332.304132) (xy 8.428279 -332.305787) (xy 8.356679 -332.29932) (xy 8.286266 -332.284815)
			(xy 8.21794 -332.262456) (xy 8.152573 -332.23253) (xy 8.091002 -332.195418) (xy 8.034011 -332.151595)
			(xy 7.98233 -332.101621) (xy 7.936618 -332.046134) (xy 7.89746 -331.985843) (xy 7.865356 -331.921518)
			(xy 7.840716 -331.853981) (xy 7.823855 -331.784094) (xy 7.814988 -331.712752) (xy 7.814228 -331.640864)
			(xy 7.821586 -331.56935) (xy 7.836967 -331.499124) (xy 7.860175 -331.431081) (xy 7.890913 -331.366092)
			(xy 7.928788 -331.304987) (xy 7.973318 -331.248547) (xy 7.998206 -331.222604) (xy 8.008298 -331.212541)
			(xy 8.02926 -331.193228) (xy 8.040116 -331.183996) (xy 8.060436 -331.166724) (xy 8.086598 -331.113384)
			(xy 8.093077 -331.099028) (xy 8.099515 -331.068206) (xy 8.098187 -331.036747) (xy 8.089175 -331.006577)
			(xy 8.073031 -330.979544) (xy 8.062214 -330.968096) (xy 8.047228 -330.952856) (xy 7.978394 -330.952856)
			(xy 6.949694 -329.924156) (xy 6.87832 -329.924156) (xy 6.861668 -329.924697) (xy 6.829497 -329.93331)
			(xy 6.800651 -329.949956) (xy 6.777095 -329.9735) (xy 6.760435 -330.002337) (xy 6.751805 -330.034504)
			(xy 6.75132 -330.051156) (xy 6.75132 -330.070714) (xy 6.780784 -330.12634) (xy 6.806946 -330.14412)
			(xy 6.83641 -330.164735) (xy 6.890956 -330.211596) (xy 6.939865 -330.264314) (xy 6.982511 -330.322216)
			(xy 7.01835 -330.384561) (xy 7.046922 -330.450553) (xy 7.067864 -330.519348) (xy 7.080907 -330.590067)
			(xy 7.085885 -330.661806) (xy 7.082735 -330.733648) (xy 7.071495 -330.804676) (xy 7.052311 -330.873982)
			(xy 7.025427 -330.940679) (xy 6.991186 -331.003916) (xy 6.950027 -331.062884) (xy 6.902476 -331.11683)
			(xy 6.849139 -331.165064) (xy 6.7907 -331.20697) (xy 6.727904 -331.242012) (xy 6.661554 -331.269743)
			(xy 6.592498 -331.289808) (xy 6.521619 -331.30195) (xy 6.449822 -331.306015) (xy 6.378025 -331.30195)
			(xy 6.307146 -331.289808) (xy 6.23809 -331.269743) (xy 6.17174 -331.242012) (xy 6.108944 -331.20697)
			(xy 6.050505 -331.165064) (xy 5.997168 -331.11683) (xy 5.949617 -331.062884) (xy 5.908458 -331.003916)
			(xy 5.874217 -330.940679) (xy 5.847333 -330.873982) (xy 5.828149 -330.804676) (xy 5.816909 -330.733648)
			(xy 5.813759 -330.661806) (xy 5.818737 -330.590067) (xy 5.83178 -330.519348) (xy 5.852722 -330.450553)
			(xy 5.881294 -330.384561) (xy 5.917133 -330.322216) (xy 5.959779 -330.264314) (xy 6.008688 -330.211596)
			(xy 6.063234 -330.164735) (xy 6.092698 -330.14412) (xy 6.105282 -330.135056) (xy 6.125981 -330.111971)
			(xy 6.140482 -330.084566) (xy 6.147925 -330.054467) (xy 6.148324 -330.038964) (xy 6.148324 -329.998324)
			(xy 6.074156 -329.924156) (xy 5.979922 -329.924156) (xy 4.873498 -328.817732) (xy 4.853024 -328.807749)
			(xy 4.809469 -328.794433) (xy 4.764238 -328.789101) (xy 4.718781 -328.791922) (xy 4.674556 -328.802807)
			(xy 4.632982 -328.821407) (xy 4.595392 -328.847124) (xy 4.562993 -328.879134) (xy 4.536824 -328.916409)
			(xy 4.526788 -328.936858) (xy 4.511305 -328.96915) (xy 4.474114 -329.030353) (xy 4.430278 -329.086987)
			(xy 4.380354 -329.138335) (xy 4.324974 -329.183745) (xy 4.264841 -329.222643) (xy 4.200716 -329.254534)
			(xy 4.133414 -329.279015) (xy 4.063785 -329.295776) (xy 3.992714 -329.304603) (xy 3.921101 -329.305385)
			(xy 3.849854 -329.298113) (xy 3.779877 -329.282878) (xy 3.712055 -329.259873) (xy 3.647249 -329.22939)
			(xy 3.58628 -329.191815) (xy 3.529922 -329.147626) (xy 3.478888 -329.097381) (xy 3.433825 -329.041718)
			(xy 3.395305 -328.981342) (xy 3.363816 -328.917019) (xy 3.339757 -328.849564) (xy 3.323434 -328.779832)
			(xy 3.318764 -328.744326) (xy 3.315027 -328.708218) (xy 3.314796 -328.635624) (xy 3.322839 -328.563476)
			(xy 3.33905 -328.492715) (xy 3.36322 -328.424262) (xy 3.395032 -328.359009) (xy 3.434073 -328.297806)
			(xy 3.479833 -328.241451) (xy 3.531717 -328.190677) (xy 3.560064 -328.168) (xy 3.589515 -328.145795)
			(xy 3.652613 -328.107592) (xy 3.719708 -328.07695) (xy 3.7899 -328.054282) (xy 3.862244 -328.039892)
			(xy 3.935767 -328.033973) (xy 4.009482 -328.036606) (xy 4.082396 -328.047754) (xy 4.118102 -328.057002)
			(xy 4.138991 -328.0623) (xy 4.181866 -328.066597) (xy 4.224852 -328.063595) (xy 4.266713 -328.053378)
			(xy 4.30625 -328.036241) (xy 4.342325 -328.012676) (xy 4.373905 -327.983358) (xy 4.400081 -327.94913)
			(xy 4.420104 -327.910974) (xy 4.42722 -327.890632) (xy 4.42722 -327.44918) (xy 4.420106 -327.428848)
			(xy 4.400031 -327.390741) (xy 4.373826 -327.356558) (xy 4.34224 -327.327276) (xy 4.306173 -327.303731)
			(xy 4.266656 -327.286596) (xy 4.224818 -327.276361) (xy 4.181854 -327.273317) (xy 4.138991 -327.277552)
			(xy 4.118102 -327.28281) (xy 4.08189 -327.292182) (xy 4.007928 -327.303362) (xy 3.933164 -327.305772)
			(xy 3.895852 -327.30313) (xy 3.86086 -327.299667) (xy 3.791883 -327.285984) (xy 3.724839 -327.264769)
			(xy 3.660547 -327.236283) (xy 3.599792 -327.200873) (xy 3.543318 -327.158973) (xy 3.491815 -327.111094)
			(xy 3.445912 -327.057822) (xy 3.406171 -326.999808) (xy 3.373077 -326.937761) (xy 3.347036 -326.87244)
			(xy 3.328364 -326.804644) (xy 3.317292 -326.7352) (xy 3.313953 -326.664959) (xy 3.318389 -326.594779)
			(xy 3.330546 -326.525517) (xy 3.350275 -326.458021) (xy 3.377334 -326.393115) (xy 3.411394 -326.331593)
			(xy 3.452037 -326.274207) (xy 3.498766 -326.221659) (xy 3.551012 -326.174591) (xy 3.608134 -326.133579)
			(xy 3.63855 -326.115934) (xy 3.658572 -326.103066) (xy 3.69385 -326.071126) (xy 3.722571 -326.03318)
			(xy 3.743732 -325.990554) (xy 3.756595 -325.944736) (xy 3.760711 -325.897325) (xy 3.755935 -325.849976)
			(xy 3.742435 -325.804342) (xy 3.732022 -325.78294) (xy 3.607308 -325.657972) (xy 3.607308 -325.270622)
			(xy 3.606914 -325.256203) (xy 3.600418 -325.228105) (xy 3.587775 -325.202186) (xy 3.569632 -325.179769)
			(xy 3.55854 -325.170546) (xy 3.531771 -325.149029) (xy 3.482541 -325.101133) (xy 3.438762 -325.048209)
			(xy 3.400945 -324.990873) (xy 3.369529 -324.929794) (xy 3.344882 -324.865685) (xy 3.32729 -324.799291)
			(xy 3.31696 -324.731388) (xy 3.31401 -324.662767) (xy 3.318476 -324.594228) (xy 3.330306 -324.52657)
			(xy 3.349361 -324.460582) (xy 3.37542 -324.397033) (xy 3.391408 -324.366636) (xy 3.401153 -324.345704)
			(xy 3.413735 -324.301285) (xy 3.418092 -324.255324) (xy 3.41408 -324.209332) (xy 3.401831 -324.16482)
			(xy 3.381748 -324.12325) (xy 3.35449 -324.085989) (xy 3.320954 -324.054261) (xy 3.28224 -324.029108)
			(xy 3.239622 -324.011357) (xy 3.1945 -324.001591) (xy 3.171444 -324.000368) (xy 2.560066 -324.000368)
			(xy 2.545329 -324.000794) (xy 2.516646 -324.007571) (xy 2.490285 -324.020755) (xy 2.467658 -324.039641)
			(xy 2.458466 -324.051168) (xy 2.43691 -324.079119) (xy 2.388569 -324.130556) (xy 2.334827 -324.176319)
			(xy 2.276344 -324.215846) (xy 2.213841 -324.248649) (xy 2.148089 -324.274325) (xy 2.079897 -324.292557)
			(xy 2.010104 -324.30312) (xy 1.93957 -324.305885) (xy 1.869165 -324.300818) (xy 1.799755 -324.28798)
			(xy 1.732194 -324.267531) (xy 1.667315 -324.239721) (xy 1.605918 -324.204894) (xy 1.548757 -324.163478)
			(xy 1.496538 -324.115983) (xy 1.449903 -324.062994) (xy 1.409426 -324.005165) (xy 1.375607 -323.943206)
			(xy 1.348861 -323.877882) (xy 1.329518 -323.809997) (xy 1.317816 -323.740386) (xy 1.3139 -323.669907)
			(xy 1.317817 -323.599428) (xy 1.329519 -323.529817) (xy 1.348863 -323.461932) (xy 1.37561 -323.396608)
			(xy 1.40943 -323.33465) (xy 1.449907 -323.27682) (xy 1.496543 -323.223833) (xy 1.548762 -323.176338)
			(xy 1.605923 -323.134923) (xy 1.667321 -323.100096) (xy 1.7322 -323.072287) (xy 1.799761 -323.051838)
			(xy 1.869171 -323.039001) (xy 1.939577 -323.033935) (xy 2.01011 -323.0367) (xy 2.079903 -323.047265)
			(xy 2.148095 -323.065497) (xy 2.213847 -323.091173) (xy 2.276349 -323.123977) (xy 2.334832 -323.163505)
			(xy 2.388574 -323.209269) (xy 2.436915 -323.260706) (xy 2.458466 -323.28866) (xy 2.467644 -323.300202)
			(xy 2.490271 -323.319101) (xy 2.516635 -323.332294) (xy 2.545326 -323.339076) (xy 2.560066 -323.33946)
			(xy 3.171444 -323.33946) (xy 3.194504 -323.338242) (xy 3.239639 -323.328501) (xy 3.282272 -323.310767)
			(xy 3.320999 -323.285622) (xy 3.354546 -323.253894) (xy 3.381808 -323.216627) (xy 3.40189 -323.175048)
			(xy 3.414129 -323.130526) (xy 3.418123 -323.084525) (xy 3.41374 -323.038559) (xy 3.401126 -322.994142)
			(xy 3.391408 -322.973192) (xy 3.374631 -322.941235) (xy 3.347596 -322.874311) (xy 3.328317 -322.804754)
			(xy 3.317043 -322.733461) (xy 3.313917 -322.66135) (xy 3.318982 -322.589349) (xy 3.332171 -322.518386)
			(xy 3.353315 -322.449373) (xy 3.382141 -322.383201) (xy 3.418278 -322.32072) (xy 3.461262 -322.262735)
			(xy 3.510537 -322.209993) (xy 3.565471 -322.163174) (xy 3.625355 -322.122879) (xy 3.689419 -322.089628)
			(xy 3.756837 -322.06385) (xy 3.826742 -322.045875) (xy 3.898233 -322.035935) (xy 3.97039 -322.034159)
			(xy 4.042284 -322.040569) (xy 4.112988 -322.055082) (xy 4.181593 -322.077513) (xy 4.247216 -322.107571)
			(xy 4.30901 -322.14487) (xy 4.366181 -322.18893) (xy 4.417992 -322.239183) (xy 4.463776 -322.294983)
			(xy 4.502944 -322.35561) (xy 4.519422 -322.387722) (xy 4.53083 -322.408151) (xy 4.559905 -322.444803)
			(xy 4.5952 -322.47551) (xy 4.635522 -322.499235) (xy 4.679506 -322.515175) (xy 4.725666 -322.52279)
			(xy 4.77244 -322.521824) (xy 4.818246 -322.512308) (xy 4.861534 -322.494565) (xy 4.900842 -322.469195)
			(xy 4.918202 -322.453508) (xy 5.663692 -321.708272) (xy 6.159246 -321.212464) (xy 6.963918 -321.212464)
			(xy 7.239508 -320.937128) (xy 7.650988 -320.525648) (xy 7.802626 -320.525648) (xy 7.824813 -320.524506)
			(xy 7.868299 -320.515437) (xy 7.909547 -320.498944) (xy 7.947297 -320.475529) (xy 7.980401 -320.445907)
			(xy 8.00785 -320.41098) (xy 8.028806 -320.371811) (xy 8.042632 -320.329595) (xy 8.048907 -320.285618)
			(xy 8.047438 -320.24122) (xy 8.038271 -320.197753) (xy 8.021685 -320.156543) (xy 7.998186 -320.118845)
			(xy 7.983728 -320.101976) (xy 7.959656 -320.075276) (xy 7.917044 -320.017373) (xy 7.881238 -319.955031)
			(xy 7.852696 -319.889047) (xy 7.831782 -319.820263) (xy 7.818765 -319.749559) (xy 7.813809 -319.677837)
			(xy 7.816978 -319.606014) (xy 7.828232 -319.535008) (xy 7.847428 -319.465725) (xy 7.874319 -319.399051)
			(xy 7.908562 -319.335838) (xy 7.94972 -319.276892) (xy 7.997267 -319.222968) (xy 8.050595 -319.174754)
			(xy 8.109024 -319.132865) (xy 8.171807 -319.097838) (xy 8.238141 -319.070119) (xy 8.307179 -319.050063)
			(xy 8.37804 -319.037926) (xy 8.449818 -319.033863) (xy 8.521596 -319.037926) (xy 8.592457 -319.050063)
			(xy 8.661495 -319.070119) (xy 8.727829 -319.097838) (xy 8.790612 -319.132865) (xy 8.849041 -319.174754)
			(xy 8.902369 -319.222968) (xy 8.949916 -319.276892) (xy 8.991074 -319.335838) (xy 9.025317 -319.399051)
			(xy 9.037148 -319.428386) (xy 14.636495 -319.428386) (xy 14.642595 -319.372949) (xy 14.656701 -319.318992)
			(xy 14.678513 -319.267663) (xy 14.707567 -319.220057) (xy 14.743242 -319.177189) (xy 14.784779 -319.139972)
			(xy 14.831292 -319.109199) (xy 14.881789 -319.085527) (xy 14.935196 -319.069459) (xy 14.990372 -319.061339)
			(xy 15.018258 -319.06083) (xy 15.046144 -319.061339) (xy 15.10132 -319.069459) (xy 15.154727 -319.085527)
			(xy 15.205224 -319.109199) (xy 15.251737 -319.139972) (xy 15.293274 -319.177189) (xy 15.328949 -319.220057)
			(xy 15.358003 -319.267663) (xy 15.379815 -319.318992) (xy 15.393921 -319.372949) (xy 15.400021 -319.428386)
			(xy 15.397984 -319.48412) (xy 15.387854 -319.538963) (xy 15.369847 -319.591747) (xy 15.344346 -319.641347)
			(xy 15.311895 -319.686705) (xy 15.273186 -319.726854) (xy 15.229043 -319.76094) (xy 15.180408 -319.788236)
			(xy 15.128317 -319.808159) (xy 15.07388 -319.820285) (xy 15.018258 -319.824356) (xy 14.962636 -319.820285)
			(xy 14.908199 -319.808159) (xy 14.856108 -319.788236) (xy 14.807473 -319.76094) (xy 14.76333 -319.726854)
			(xy 14.724621 -319.686705) (xy 14.69217 -319.641347) (xy 14.666669 -319.591747) (xy 14.648662 -319.538963)
			(xy 14.638532 -319.48412) (xy 14.636495 -319.428386) (xy 9.037148 -319.428386) (xy 9.052208 -319.465725)
			(xy 9.071404 -319.535008) (xy 9.082658 -319.606014) (xy 9.085827 -319.677837) (xy 9.080871 -319.749559)
			(xy 9.067854 -319.820263) (xy 9.04694 -319.889047) (xy 9.018398 -319.955031) (xy 8.982592 -320.017373)
			(xy 8.93998 -320.075276) (xy 8.915908 -320.101976) (xy 8.901418 -320.118809) (xy 8.877954 -320.156517)
			(xy 8.861399 -320.197729) (xy 8.852257 -320.24119) (xy 8.850806 -320.285578) (xy 8.857091 -320.329544)
			(xy 8.870919 -320.371748) (xy 8.891871 -320.410908) (xy 8.919308 -320.445831) (xy 8.952397 -320.475455)
			(xy 8.99013 -320.498879) (xy 9.031359 -320.51539) (xy 9.07483 -320.524485) (xy 9.09701 -320.525648)
			(xy 9.29513 -320.525648) (xy 10.115296 -321.34556) (xy 10.664444 -321.894708) (xy 10.664444 -323.17133)
			(xy 14.455901 -323.17133) (xy 14.462001 -323.115893) (xy 14.476107 -323.061936) (xy 14.497919 -323.010607)
			(xy 14.526973 -322.963001) (xy 14.562648 -322.920133) (xy 14.604185 -322.882916) (xy 14.650698 -322.852143)
			(xy 14.701195 -322.828471) (xy 14.754602 -322.812403) (xy 14.809778 -322.804283) (xy 14.837664 -322.803774)
			(xy 14.86555 -322.804283) (xy 14.920726 -322.812403) (xy 14.974133 -322.828471) (xy 15.02463 -322.852143)
			(xy 15.071143 -322.882916) (xy 15.11268 -322.920133) (xy 15.148355 -322.963001) (xy 15.177409 -323.010607)
			(xy 15.199221 -323.061936) (xy 15.213327 -323.115893) (xy 15.219427 -323.17133) (xy 15.21739 -323.227064)
			(xy 15.20726 -323.281907) (xy 15.189253 -323.334691) (xy 15.163752 -323.384291) (xy 15.131301 -323.429649)
			(xy 15.092592 -323.469798) (xy 15.048449 -323.503884) (xy 14.999814 -323.53118) (xy 14.947723 -323.551103)
			(xy 14.893286 -323.563229) (xy 14.837664 -323.5673) (xy 14.782042 -323.563229) (xy 14.727605 -323.551103)
			(xy 14.675514 -323.53118) (xy 14.626879 -323.503884) (xy 14.582736 -323.469798) (xy 14.544027 -323.429649)
			(xy 14.511576 -323.384291) (xy 14.486075 -323.334691) (xy 14.468068 -323.281907) (xy 14.457938 -323.227064)
			(xy 14.455901 -323.17133) (xy 10.664444 -323.17133) (xy 10.664444 -324.65391) (xy 11.06859 -325.058296)
			(xy 14.440661 -325.058296) (xy 14.446761 -325.002859) (xy 14.460867 -324.948902) (xy 14.482679 -324.897573)
			(xy 14.511733 -324.849967) (xy 14.547408 -324.807099) (xy 14.588945 -324.769882) (xy 14.635458 -324.739109)
			(xy 14.685955 -324.715437) (xy 14.739362 -324.699369) (xy 14.794538 -324.691249) (xy 14.822424 -324.69074)
			(xy 14.85031 -324.691249) (xy 14.905486 -324.699369) (xy 14.958893 -324.715437) (xy 15.00939 -324.739109)
			(xy 15.055903 -324.769882) (xy 15.09744 -324.807099) (xy 15.133115 -324.849967) (xy 15.162169 -324.897573)
			(xy 15.183981 -324.948902) (xy 15.198087 -325.002859) (xy 15.204187 -325.058296) (xy 15.20215 -325.11403)
			(xy 15.19202 -325.168873) (xy 15.174013 -325.221657) (xy 15.148512 -325.271257) (xy 15.116061 -325.316615)
			(xy 15.077352 -325.356764) (xy 15.033209 -325.39085) (xy 14.984574 -325.418146) (xy 14.932483 -325.438069)
			(xy 14.878046 -325.450195) (xy 14.822424 -325.454266) (xy 14.766802 -325.450195) (xy 14.712365 -325.438069)
			(xy 14.660274 -325.418146) (xy 14.611639 -325.39085) (xy 14.567496 -325.356764) (xy 14.528787 -325.316615)
			(xy 14.496336 -325.271257) (xy 14.470835 -325.221657) (xy 14.452828 -325.168873) (xy 14.442698 -325.11403)
			(xy 14.440661 -325.058296) (xy 11.06859 -325.058296) (xy 11.091418 -325.081138) (xy 11.729212 -325.718932)
			(xy 11.729212 -332.514698) (xy 13.396704 -332.514698) (xy 13.396704 -332.454762) (xy 13.404527 -332.39534)
			(xy 13.42004 -332.337447) (xy 13.442976 -332.282074) (xy 13.472943 -332.230168) (xy 13.50943 -332.182618)
			(xy 13.55181 -332.140238) (xy 13.59936 -332.103751) (xy 13.651266 -332.073784) (xy 13.706639 -332.050848)
			(xy 13.764532 -332.035335) (xy 13.823954 -332.027512) (xy 13.853922 -332.027022) (xy 13.88389 -332.027512)
			(xy 13.943312 -332.035335) (xy 14.001205 -332.050848) (xy 14.056578 -332.073784) (xy 14.108484 -332.103751)
			(xy 14.156034 -332.140238) (xy 14.198414 -332.182618) (xy 14.234901 -332.230168) (xy 14.264868 -332.282074)
			(xy 14.287804 -332.337447) (xy 14.303317 -332.39534) (xy 14.31114 -332.454762) (xy 14.31114 -332.514698)
			(xy 14.304619 -332.564228) (xy 15.256746 -332.564228) (xy 15.256746 -332.504292) (xy 15.264569 -332.44487)
			(xy 15.280082 -332.386977) (xy 15.303018 -332.331604) (xy 15.332985 -332.279698) (xy 15.369472 -332.232148)
			(xy 15.411852 -332.189768) (xy 15.459402 -332.153281) (xy 15.511308 -332.123314) (xy 15.566681 -332.100378)
			(xy 15.624574 -332.084865) (xy 15.683996 -332.077042) (xy 15.713964 -332.076552) (xy 15.743932 -332.077042)
			(xy 15.803354 -332.084865) (xy 15.861247 -332.100378) (xy 15.91662 -332.123314) (xy 15.968526 -332.153281)
			(xy 16.016076 -332.189768) (xy 16.044842 -332.218534) (xy 16.705054 -332.218534) (xy 16.705054 -332.158598)
			(xy 16.712877 -332.099176) (xy 16.72839 -332.041283) (xy 16.751326 -331.98591) (xy 16.781293 -331.934004)
			(xy 16.81778 -331.886454) (xy 16.86016 -331.844074) (xy 16.90771 -331.807587) (xy 16.959616 -331.77762)
			(xy 17.014989 -331.754684) (xy 17.072882 -331.739171) (xy 17.132304 -331.731348) (xy 17.162272 -331.730858)
			(xy 17.19224 -331.731348) (xy 17.251662 -331.739171) (xy 17.309555 -331.754684) (xy 17.364928 -331.77762)
			(xy 17.416834 -331.807587) (xy 17.464384 -331.844074) (xy 17.506764 -331.886454) (xy 17.543251 -331.934004)
			(xy 17.573218 -331.98591) (xy 17.596154 -332.041283) (xy 17.611667 -332.099176) (xy 17.61949 -332.158598)
			(xy 17.61949 -332.218534) (xy 17.611667 -332.277956) (xy 17.596154 -332.335849) (xy 17.573218 -332.391222)
			(xy 17.543251 -332.443128) (xy 17.506764 -332.490678) (xy 17.464384 -332.533058) (xy 17.416834 -332.569545)
			(xy 17.364928 -332.599512) (xy 17.309555 -332.622448) (xy 17.251662 -332.637961) (xy 17.19224 -332.645784)
			(xy 17.132304 -332.645784) (xy 17.072882 -332.637961) (xy 17.014989 -332.622448) (xy 16.959616 -332.599512)
			(xy 16.90771 -332.569545) (xy 16.86016 -332.533058) (xy 16.81778 -332.490678) (xy 16.781293 -332.443128)
			(xy 16.751326 -332.391222) (xy 16.72839 -332.335849) (xy 16.712877 -332.277956) (xy 16.705054 -332.218534)
			(xy 16.044842 -332.218534) (xy 16.058456 -332.232148) (xy 16.094943 -332.279698) (xy 16.12491 -332.331604)
			(xy 16.147846 -332.386977) (xy 16.163359 -332.44487) (xy 16.171182 -332.504292) (xy 16.171182 -332.564228)
			(xy 16.163359 -332.62365) (xy 16.147846 -332.681543) (xy 16.12491 -332.736916) (xy 16.094943 -332.788822)
			(xy 16.058456 -332.836372) (xy 16.016076 -332.878752) (xy 15.968526 -332.915239) (xy 15.91662 -332.945206)
			(xy 15.861247 -332.968142) (xy 15.803354 -332.983655) (xy 15.743932 -332.991478) (xy 15.683996 -332.991478)
			(xy 15.624574 -332.983655) (xy 15.566681 -332.968142) (xy 15.511308 -332.945206) (xy 15.459402 -332.915239)
			(xy 15.411852 -332.878752) (xy 15.369472 -332.836372) (xy 15.332985 -332.788822) (xy 15.303018 -332.736916)
			(xy 15.280082 -332.681543) (xy 15.264569 -332.62365) (xy 15.256746 -332.564228) (xy 14.304619 -332.564228)
			(xy 14.303317 -332.57412) (xy 14.287804 -332.632013) (xy 14.264868 -332.687386) (xy 14.234901 -332.739292)
			(xy 14.198414 -332.786842) (xy 14.156034 -332.829222) (xy 14.108484 -332.865709) (xy 14.056578 -332.895676)
			(xy 14.001205 -332.918612) (xy 13.943312 -332.934125) (xy 13.88389 -332.941948) (xy 13.823954 -332.941948)
			(xy 13.764532 -332.934125) (xy 13.706639 -332.918612) (xy 13.651266 -332.895676) (xy 13.59936 -332.865709)
			(xy 13.55181 -332.829222) (xy 13.50943 -332.786842) (xy 13.472943 -332.739292) (xy 13.442976 -332.687386)
			(xy 13.42004 -332.632013) (xy 13.404527 -332.57412) (xy 13.396704 -332.514698) (xy 11.729212 -332.514698)
			(xy 11.729212 -333.52232) (xy 11.730439 -333.545257) (xy 11.740128 -333.590152) (xy 11.757723 -333.632577)
			(xy 11.782653 -333.671152) (xy 11.814106 -333.704621) (xy 11.851059 -333.731896) (xy 11.89231 -333.75209)
			(xy 11.936518 -333.764547) (xy 11.959336 -333.767176) (xy 11.98987 -333.769414) (xy 12.049983 -333.781031)
			(xy 12.10801 -333.800559) (xy 12.162916 -333.827648) (xy 12.213721 -333.861814) (xy 12.259518 -333.902449)
			(xy 12.299488 -333.948826) (xy 12.33292 -334.000117) (xy 12.359215 -334.055408) (xy 12.377905 -334.11371)
			(xy 12.388655 -334.173984) (xy 12.391275 -334.235153) (xy 12.385717 -334.296125) (xy 12.37208 -334.355812)
			(xy 12.350607 -334.413148) (xy 12.321683 -334.46711) (xy 12.285824 -334.516734) (xy 12.243669 -334.561135)
			(xy 12.195971 -334.59952) (xy 12.143581 -334.631203) (xy 12.087436 -334.65562) (xy 12.028537 -334.672334)
			(xy 11.967935 -334.681047) (xy 11.906713 -334.681603) (xy 11.876278 -334.678274) (xy 11.87323 -334.677766)
			(xy 11.872976 -334.677766) (xy 11.864594 -334.67675) (xy 11.856212 -334.67675) (xy 11.839559 -334.677243)
			(xy 11.807387 -334.685863) (xy 11.778543 -334.702519) (xy 11.754995 -334.726074) (xy 11.738349 -334.754922)
			(xy 11.729738 -334.787096) (xy 11.729212 -334.80375) (xy 11.729212 -334.914494) (xy 11.729706 -334.931149)
			(xy 11.738326 -334.963323) (xy 11.754981 -334.99217) (xy 11.778535 -335.015723) (xy 11.807382 -335.032376)
			(xy 11.839557 -335.040995) (xy 11.856212 -335.041494) (xy 11.864594 -335.041494) (xy 11.872976 -335.040478)
			(xy 11.87323 -335.040478) (xy 11.876278 -335.03997) (xy 11.905953 -335.036755) (xy 11.965642 -335.03713)
			(xy 12.024776 -335.045263) (xy 12.082351 -335.061014) (xy 12.137389 -335.084117) (xy 12.188957 -335.114179)
			(xy 12.236178 -335.150689) (xy 12.278253 -335.193029) (xy 12.314465 -335.24048) (xy 12.344202 -335.292236)
			(xy 12.366958 -335.347418) (xy 12.382346 -335.405091) (xy 12.390106 -335.464275) (xy 12.390106 -335.523965)
			(xy 12.382346 -335.583149) (xy 12.366958 -335.640821) (xy 12.344202 -335.696004) (xy 12.314466 -335.74776)
			(xy 12.278253 -335.79521) (xy 12.236179 -335.83755) (xy 12.188957 -335.874061) (xy 12.137389 -335.904123)
			(xy 12.082351 -335.927226) (xy 12.024777 -335.942977) (xy 11.965643 -335.95111) (xy 11.905954 -335.951485)
			(xy 11.876278 -335.948274) (xy 11.87323 -335.947766) (xy 11.872976 -335.947766) (xy 11.864594 -335.94675)
			(xy 11.856212 -335.94675) (xy 11.839559 -335.947243) (xy 11.807387 -335.955863) (xy 11.778543 -335.972519)
			(xy 11.754995 -335.996074) (xy 11.738349 -336.024922) (xy 11.729738 -336.057096) (xy 11.729212 -336.07375)
			(xy 11.729212 -336.184494) (xy 11.729706 -336.201149) (xy 11.738326 -336.233323) (xy 11.754981 -336.26217)
			(xy 11.778535 -336.285723) (xy 11.807382 -336.302376) (xy 11.839557 -336.310995) (xy 11.856212 -336.311494)
			(xy 11.864594 -336.311494) (xy 11.872976 -336.310478) (xy 11.87323 -336.310478) (xy 11.876278 -336.30997)
			(xy 11.905953 -336.306755) (xy 11.965642 -336.30713) (xy 12.024776 -336.315263) (xy 12.082351 -336.331014)
			(xy 12.137389 -336.354117) (xy 12.188957 -336.384179) (xy 12.236178 -336.420689) (xy 12.278253 -336.463029)
			(xy 12.314465 -336.51048) (xy 12.344202 -336.562236) (xy 12.366958 -336.617418) (xy 12.382346 -336.675091)
			(xy 12.390106 -336.734275) (xy 12.390106 -336.793965) (xy 12.382346 -336.853149) (xy 12.366958 -336.910821)
			(xy 12.344202 -336.966004) (xy 12.314466 -337.01776) (xy 12.278253 -337.06521) (xy 12.236179 -337.10755)
			(xy 12.188957 -337.144061) (xy 12.137389 -337.174123) (xy 12.082351 -337.197226) (xy 12.024777 -337.212977)
			(xy 11.965643 -337.22111) (xy 11.905954 -337.221485) (xy 11.876278 -337.218274) (xy 11.87323 -337.217766)
			(xy 11.872976 -337.217766) (xy 11.864594 -337.21675) (xy 11.856212 -337.21675) (xy 11.839559 -337.217243)
			(xy 11.807387 -337.225863) (xy 11.778543 -337.242519) (xy 11.754995 -337.266074) (xy 11.738349 -337.294922)
			(xy 11.729738 -337.327096) (xy 11.729212 -337.34375) (xy 11.729212 -337.454494) (xy 11.729706 -337.471149)
			(xy 11.738326 -337.503323) (xy 11.754981 -337.53217) (xy 11.778535 -337.555723) (xy 11.807382 -337.572376)
			(xy 11.839557 -337.580995) (xy 11.856212 -337.581494) (xy 11.864594 -337.581494) (xy 11.872976 -337.580478)
			(xy 11.87323 -337.580478) (xy 11.876278 -337.57997) (xy 11.905953 -337.576755) (xy 11.965642 -337.57713)
			(xy 12.024776 -337.585263) (xy 12.082351 -337.601014) (xy 12.137389 -337.624117) (xy 12.188957 -337.654179)
			(xy 12.236178 -337.690689) (xy 12.278253 -337.733029) (xy 12.314465 -337.78048) (xy 12.344202 -337.832236)
			(xy 12.366958 -337.887418) (xy 12.382346 -337.945091) (xy 12.390106 -338.004275) (xy 12.390106 -338.063965)
			(xy 12.382346 -338.123149) (xy 12.366958 -338.180821) (xy 12.344202 -338.236004) (xy 12.314466 -338.28776)
			(xy 12.278253 -338.33521) (xy 12.236179 -338.37755) (xy 12.188957 -338.414061) (xy 12.137389 -338.444123)
			(xy 12.082351 -338.467226) (xy 12.024777 -338.482977) (xy 11.965643 -338.49111) (xy 11.905954 -338.491485)
			(xy 11.876278 -338.488274) (xy 11.87323 -338.487766) (xy 11.872976 -338.487766) (xy 11.864594 -338.48675)
			(xy 11.856212 -338.48675) (xy 11.839559 -338.487243) (xy 11.807387 -338.495863) (xy 11.778543 -338.512519)
			(xy 11.754995 -338.536074) (xy 11.738349 -338.564922) (xy 11.729738 -338.597096) (xy 11.729212 -338.61375)
			(xy 11.729212 -338.724494) (xy 11.729706 -338.741149) (xy 11.738326 -338.773323) (xy 11.754981 -338.80217)
			(xy 11.778535 -338.825723) (xy 11.807382 -338.842376) (xy 11.839557 -338.850995) (xy 11.856212 -338.851494)
			(xy 11.864594 -338.851494) (xy 11.872976 -338.850478) (xy 11.87323 -338.850478) (xy 11.876278 -338.84997)
			(xy 11.905953 -338.846755) (xy 11.965642 -338.84713) (xy 12.024776 -338.855263) (xy 12.082351 -338.871014)
			(xy 12.137389 -338.894117) (xy 12.188957 -338.924179) (xy 12.236178 -338.960689) (xy 12.278253 -339.003029)
			(xy 12.314465 -339.05048) (xy 12.344202 -339.102236) (xy 12.366958 -339.157418) (xy 12.382346 -339.215091)
			(xy 12.390106 -339.274275) (xy 12.390106 -339.333965) (xy 12.382346 -339.393149) (xy 12.366958 -339.450821)
			(xy 12.344202 -339.506004) (xy 12.314466 -339.55776) (xy 12.278253 -339.60521) (xy 12.236179 -339.64755)
			(xy 12.188957 -339.684061) (xy 12.137389 -339.714123) (xy 12.082351 -339.737226) (xy 12.024777 -339.752977)
			(xy 11.965643 -339.76111) (xy 11.905954 -339.761485) (xy 11.876278 -339.758274) (xy 11.87323 -339.757766)
			(xy 11.872976 -339.757766) (xy 11.864594 -339.75675) (xy 11.856212 -339.75675) (xy 11.839559 -339.757243)
			(xy 11.807387 -339.765863) (xy 11.778543 -339.782519) (xy 11.754995 -339.806074) (xy 11.738349 -339.834922)
			(xy 11.729738 -339.867096) (xy 11.729212 -339.88375) (xy 11.729212 -339.994494) (xy 11.729706 -340.011149)
			(xy 11.738326 -340.043323) (xy 11.754981 -340.07217) (xy 11.778535 -340.095723) (xy 11.807382 -340.112376)
			(xy 11.839557 -340.120995) (xy 11.856212 -340.121494) (xy 11.864594 -340.121494) (xy 11.872976 -340.120478)
			(xy 11.87323 -340.120478) (xy 11.876278 -340.11997) (xy 11.905953 -340.116755) (xy 11.965642 -340.11713)
			(xy 12.024776 -340.125263) (xy 12.082351 -340.141014) (xy 12.137389 -340.164117) (xy 12.188957 -340.194179)
			(xy 12.236178 -340.230689) (xy 12.278253 -340.273029) (xy 12.314465 -340.32048) (xy 12.344202 -340.372236)
			(xy 12.366958 -340.427418) (xy 12.382346 -340.485091) (xy 12.390106 -340.544275) (xy 12.390106 -340.603965)
			(xy 12.382346 -340.663149) (xy 12.366958 -340.720821) (xy 12.344202 -340.776004) (xy 12.314466 -340.82776)
			(xy 12.278253 -340.87521) (xy 12.236179 -340.91755) (xy 12.22734 -340.924384) (xy 15.256746 -340.924384)
			(xy 15.256746 -340.864448) (xy 15.264569 -340.805026) (xy 15.280082 -340.747133) (xy 15.303018 -340.69176)
			(xy 15.332985 -340.639854) (xy 15.369472 -340.592304) (xy 15.411852 -340.549924) (xy 15.459402 -340.513437)
			(xy 15.511308 -340.48347) (xy 15.566681 -340.460534) (xy 15.624574 -340.445021) (xy 15.683996 -340.437198)
			(xy 15.713964 -340.436708) (xy 15.743932 -340.437198) (xy 15.803354 -340.445021) (xy 15.861247 -340.460534)
			(xy 15.91662 -340.48347) (xy 15.968526 -340.513437) (xy 16.016076 -340.549924) (xy 16.058456 -340.592304)
			(xy 16.094943 -340.639854) (xy 16.12491 -340.69176) (xy 16.147846 -340.747133) (xy 16.163359 -340.805026)
			(xy 16.171182 -340.864448) (xy 16.171182 -340.924384) (xy 16.163359 -340.983806) (xy 16.147846 -341.041699)
			(xy 16.12491 -341.097072) (xy 16.094943 -341.148978) (xy 16.058456 -341.196528) (xy 16.016076 -341.238908)
			(xy 15.968526 -341.275395) (xy 15.91662 -341.305362) (xy 15.861247 -341.328298) (xy 15.803354 -341.343811)
			(xy 15.743932 -341.351634) (xy 15.683996 -341.351634) (xy 15.624574 -341.343811) (xy 15.566681 -341.328298)
			(xy 15.511308 -341.305362) (xy 15.459402 -341.275395) (xy 15.411852 -341.238908) (xy 15.369472 -341.196528)
			(xy 15.332985 -341.148978) (xy 15.303018 -341.097072) (xy 15.280082 -341.041699) (xy 15.264569 -340.983806)
			(xy 15.256746 -340.924384) (xy 12.22734 -340.924384) (xy 12.188957 -340.954061) (xy 12.137389 -340.984123)
			(xy 12.082351 -341.007226) (xy 12.024777 -341.022977) (xy 11.965643 -341.03111) (xy 11.905954 -341.031485)
			(xy 11.876278 -341.028274) (xy 11.87323 -341.027766) (xy 11.872976 -341.027766) (xy 11.864594 -341.02675)
			(xy 11.856212 -341.02675) (xy 11.839559 -341.027243) (xy 11.807387 -341.035863) (xy 11.778543 -341.052519)
			(xy 11.754995 -341.076074) (xy 11.738349 -341.104922) (xy 11.729738 -341.137096) (xy 11.729212 -341.15375)
			(xy 11.729212 -341.264494) (xy 11.729706 -341.281149) (xy 11.738326 -341.313323) (xy 11.754981 -341.34217)
			(xy 11.778535 -341.365723) (xy 11.807382 -341.382376) (xy 11.839557 -341.390995) (xy 11.856212 -341.391494)
			(xy 11.864594 -341.391494) (xy 11.872976 -341.390478) (xy 11.87323 -341.390478) (xy 11.876278 -341.38997)
			(xy 11.907057 -341.386628) (xy 11.968964 -341.38728) (xy 12.030218 -341.396271) (xy 12.089701 -341.413436)
			(xy 12.146328 -341.438464) (xy 12.199063 -341.470897) (xy 12.246945 -341.510143) (xy 12.2891 -341.555485)
			(xy 12.324758 -341.606095) (xy 12.353268 -341.661051) (xy 12.374109 -341.719348) (xy 12.386901 -341.779922)
			(xy 12.391412 -341.841669) (xy 12.387557 -341.903459) (xy 12.375408 -341.964166) (xy 12.355186 -342.022681)
			(xy 12.327261 -342.077936) (xy 12.31011 -342.10371) (xy 12.28598 -342.138508) (xy 14.04239 -343.894918)
			(xy 14.04239 -371.823488)
		)
		(stroke
			(width 0)
			(type solid)
		)
		(fill yes)
		(layer "B.Cu")
		(net "GND")
	)
	(gr_poly
		(pts
			(xy 101.000052 -529.49094) (xy 101.055822 -529.490433) (xy 101.167051 -529.482101) (xy 101.277346 -529.46548)
			(xy 101.38609 -529.440662) (xy 101.492675 -529.407788) (xy 101.596506 -529.367039) (xy 101.697001 -529.318645)
			(xy 101.793598 -529.262876) (xy 101.885758 -529.200044) (xy 101.972964 -529.130501) (xy 102.054729 -529.054635)
			(xy 102.130596 -528.97287) (xy 102.20014 -528.885664) (xy 102.262972 -528.793505) (xy 102.318742 -528.696908)
			(xy 102.367136 -528.596413) (xy 102.407885 -528.492583) (xy 102.44076 -528.385998) (xy 102.465578 -528.277253)
			(xy 102.4822 -528.166959) (xy 102.490533 -528.05573) (xy 102.491032 -527.99996) (xy 102.491032 -1.999996)
			(xy 102.490523 -1.944227) (xy 102.482188 -1.833002) (xy 102.465563 -1.72271) (xy 102.440743 -1.613969)
			(xy 102.407866 -1.507387) (xy 102.367116 -1.40356) (xy 102.31872 -1.303069) (xy 102.26295 -1.206475)
			(xy 102.200118 -1.11432) (xy 102.130574 -1.027117) (xy 102.054708 -0.945356) (xy 101.972944 -0.869492)
			(xy 101.885739 -0.799951) (xy 101.793581 -0.737122) (xy 101.696985 -0.681355) (xy 101.596492 -0.632964)
			(xy 101.492664 -0.592217) (xy 101.386081 -0.559343) (xy 101.277339 -0.534527) (xy 101.167047 -0.517907)
			(xy 101.055821 -0.509575) (xy 101.000052 -0.509016) (xy 26.500074 -0.509016) (xy 26.454278 -0.509546)
			(xy 26.363077 -0.517999) (xy 26.273045 -0.534832) (xy 26.184949 -0.559899) (xy 26.099543 -0.592988)
			(xy 26.017554 -0.633817) (xy 25.939682 -0.682036) (xy 25.866592 -0.737234) (xy 25.798906 -0.798941)
			(xy 25.737202 -0.86663) (xy 25.682007 -0.939724) (xy 25.633792 -1.017598) (xy 25.592968 -1.099589)
			(xy 25.559883 -1.184997) (xy 25.53482 -1.273093) (xy 25.517992 -1.363126) (xy 25.509543 -1.454328)
			(xy 25.508966 -1.500124) (xy 25.508966 -2.500122) (xy 25.50847 -2.563238) (xy 25.500544 -2.689221)
			(xy 25.484723 -2.814458) (xy 25.461069 -2.938455) (xy 25.429676 -3.060721) (xy 25.390668 -3.180775)
			(xy 25.344199 -3.298143) (xy 25.290452 -3.412362) (xy 25.229639 -3.52298) (xy 25.162 -3.629561) (xy 25.087803 -3.731685)
			(xy 25.007339 -3.828949) (xy 24.920927 -3.920968) (xy 24.828907 -4.00738) (xy 24.731644 -4.087844)
			(xy 24.62952 -4.162041) (xy 24.522938 -4.22968) (xy 24.41232 -4.290493) (xy 24.298101 -4.34424) (xy 24.180733 -4.390709)
			(xy 24.060679 -4.429717) (xy 23.938413 -4.46111) (xy 23.814416 -4.484763) (xy 23.689179 -4.500584)
			(xy 23.563196 -4.50851) (xy 23.50008 -4.509008) (xy 1.500124 -4.509008) (xy 1.454327 -4.509537) (xy 1.363123 -4.517988)
			(xy 1.273088 -4.534819) (xy 1.18499 -4.559885) (xy 1.099581 -4.592972) (xy 1.017589 -4.6338) (xy 0.939714 -4.682018)
			(xy 0.86662 -4.737216) (xy 0.798931 -4.798923) (xy 0.737224 -4.866612) (xy 0.682026 -4.939706) (xy 0.633808 -5.017581)
			(xy 0.59298 -5.099573) (xy 0.559893 -5.184982) (xy 0.534827 -5.27308) (xy 0.517996 -5.363115) (xy 0.509545 -5.454319)
			(xy 0.509016 -5.500116) (xy 0.509016 -6.378617) (xy 3.67918 -6.378617) (xy 3.67918 -6.297507) (xy 3.68713 -6.216788)
			(xy 3.702953 -6.137237) (xy 3.726498 -6.059621) (xy 3.757537 -5.984685) (xy 3.795772 -5.913153) (xy 3.840834 -5.845713)
			(xy 3.892289 -5.783014) (xy 3.949642 -5.725661) (xy 4.012341 -5.674206) (xy 4.079781 -5.629144) (xy 4.151313 -5.590909)
			(xy 4.226249 -5.55987) (xy 4.303865 -5.536325) (xy 4.383416 -5.520502) (xy 4.464135 -5.512552) (xy 4.50469 -5.512054)
			(xy 4.545245 -5.512552) (xy 4.625964 -5.520502) (xy 4.705515 -5.536325) (xy 4.783131 -5.55987) (xy 4.858067 -5.590909)
			(xy 4.929599 -5.629144) (xy 4.997039 -5.674206) (xy 5.059738 -5.725661) (xy 5.117091 -5.783014) (xy 5.168546 -5.845713)
			(xy 5.213608 -5.913153) (xy 5.251843 -5.984685) (xy 5.282882 -6.059621) (xy 5.306427 -6.137237) (xy 5.32225 -6.216788)
			(xy 5.3302 -6.297507) (xy 5.3302 -6.378617) (xy 6.21918 -6.378617) (xy 6.21918 -6.297507) (xy 6.22713 -6.216788)
			(xy 6.242953 -6.137237) (xy 6.266498 -6.059621) (xy 6.297537 -5.984685) (xy 6.335772 -5.913153) (xy 6.380834 -5.845713)
			(xy 6.432289 -5.783014) (xy 6.489642 -5.725661) (xy 6.552341 -5.674206) (xy 6.619781 -5.629144) (xy 6.691313 -5.590909)
			(xy 6.766249 -5.55987) (xy 6.843865 -5.536325) (xy 6.923416 -5.520502) (xy 7.004135 -5.512552) (xy 7.04469 -5.512054)
			(xy 7.085245 -5.512552) (xy 7.165964 -5.520502) (xy 7.245515 -5.536325) (xy 7.323131 -5.55987) (xy 7.398067 -5.590909)
			(xy 7.469599 -5.629144) (xy 7.537039 -5.674206) (xy 7.599738 -5.725661) (xy 7.657091 -5.783014) (xy 7.708546 -5.845713)
			(xy 7.753608 -5.913153) (xy 7.791843 -5.984685) (xy 7.822882 -6.059621) (xy 7.846427 -6.137237) (xy 7.86225 -6.216788)
			(xy 7.8702 -6.297507) (xy 7.8702 -6.378617) (xy 11.29918 -6.378617) (xy 11.29918 -6.297507) (xy 11.30713 -6.216788)
			(xy 11.322953 -6.137237) (xy 11.346498 -6.059621) (xy 11.377537 -5.984685) (xy 11.415772 -5.913153)
			(xy 11.460834 -5.845713) (xy 11.512289 -5.783014) (xy 11.569642 -5.725661) (xy 11.632341 -5.674206)
			(xy 11.699781 -5.629144) (xy 11.771313 -5.590909) (xy 11.846249 -5.55987) (xy 11.923865 -5.536325)
			(xy 12.003416 -5.520502) (xy 12.084135 -5.512552) (xy 12.12469 -5.512054) (xy 12.165245 -5.512552)
			(xy 12.245964 -5.520502) (xy 12.325515 -5.536325) (xy 12.403131 -5.55987) (xy 12.478067 -5.590909)
			(xy 12.549599 -5.629144) (xy 12.617039 -5.674206) (xy 12.679738 -5.725661) (xy 12.737091 -5.783014)
			(xy 12.788546 -5.845713) (xy 12.833608 -5.913153) (xy 12.871843 -5.984685) (xy 12.902882 -6.059621)
			(xy 12.926427 -6.137237) (xy 12.94225 -6.216788) (xy 12.9502 -6.297507) (xy 12.9502 -6.378617) (xy 12.94225 -6.459336)
			(xy 12.926427 -6.538887) (xy 12.902882 -6.616503) (xy 12.871843 -6.691439) (xy 12.833608 -6.762971)
			(xy 12.788546 -6.830411) (xy 12.737091 -6.89311) (xy 12.679738 -6.950463) (xy 12.617039 -7.001918)
			(xy 12.549599 -7.04698) (xy 12.478067 -7.085215) (xy 12.403131 -7.116254) (xy 12.325515 -7.139799)
			(xy 12.245964 -7.155622) (xy 12.165245 -7.163572) (xy 12.084135 -7.163572) (xy 12.003416 -7.155622)
			(xy 11.923865 -7.139799) (xy 11.846249 -7.116254) (xy 11.771313 -7.085215) (xy 11.699781 -7.04698)
			(xy 11.632341 -7.001918) (xy 11.569642 -6.950463) (xy 11.512289 -6.89311) (xy 11.460834 -6.830411)
			(xy 11.415772 -6.762971) (xy 11.377537 -6.691439) (xy 11.346498 -6.616503) (xy 11.322953 -6.538887)
			(xy 11.30713 -6.459336) (xy 11.29918 -6.378617) (xy 7.8702 -6.378617) (xy 7.86225 -6.459336) (xy 7.846427 -6.538887)
			(xy 7.822882 -6.616503) (xy 7.791843 -6.691439) (xy 7.753608 -6.762971) (xy 7.708546 -6.830411) (xy 7.657091 -6.89311)
			(xy 7.599738 -6.950463) (xy 7.537039 -7.001918) (xy 7.469599 -7.04698) (xy 7.398067 -7.085215) (xy 7.323131 -7.116254)
			(xy 7.245515 -7.139799) (xy 7.165964 -7.155622) (xy 7.085245 -7.163572) (xy 7.004135 -7.163572) (xy 6.923416 -7.155622)
			(xy 6.843865 -7.139799) (xy 6.766249 -7.116254) (xy 6.691313 -7.085215) (xy 6.619781 -7.04698) (xy 6.552341 -7.001918)
			(xy 6.489642 -6.950463) (xy 6.432289 -6.89311) (xy 6.380834 -6.830411) (xy 6.335772 -6.762971) (xy 6.297537 -6.691439)
			(xy 6.266498 -6.616503) (xy 6.242953 -6.538887) (xy 6.22713 -6.459336) (xy 6.21918 -6.378617) (xy 5.3302 -6.378617)
			(xy 5.32225 -6.459336) (xy 5.306427 -6.538887) (xy 5.282882 -6.616503) (xy 5.251843 -6.691439) (xy 5.213608 -6.762971)
			(xy 5.168546 -6.830411) (xy 5.117091 -6.89311) (xy 5.059738 -6.950463) (xy 4.997039 -7.001918) (xy 4.929599 -7.04698)
			(xy 4.858067 -7.085215) (xy 4.783131 -7.116254) (xy 4.705515 -7.139799) (xy 4.625964 -7.155622) (xy 4.545245 -7.163572)
			(xy 4.464135 -7.163572) (xy 4.383416 -7.155622) (xy 4.303865 -7.139799) (xy 4.226249 -7.116254) (xy 4.151313 -7.085215)
			(xy 4.079781 -7.04698) (xy 4.012341 -7.001918) (xy 3.949642 -6.950463) (xy 3.892289 -6.89311) (xy 3.840834 -6.830411)
			(xy 3.795772 -6.762971) (xy 3.757537 -6.691439) (xy 3.726498 -6.616503) (xy 3.702953 -6.538887) (xy 3.68713 -6.459336)
			(xy 3.67918 -6.378617) (xy 0.509016 -6.378617) (xy 0.509016 -8.918617) (xy 4.94918 -8.918617) (xy 4.94918 -8.837507)
			(xy 4.95713 -8.756788) (xy 4.972953 -8.677237) (xy 4.996498 -8.599621) (xy 5.027537 -8.524685) (xy 5.065772 -8.453153)
			(xy 5.110834 -8.385713) (xy 5.162289 -8.323014) (xy 5.219642 -8.265661) (xy 5.282341 -8.214206) (xy 5.349781 -8.169144)
			(xy 5.421313 -8.130909) (xy 5.496249 -8.09987) (xy 5.573865 -8.076325) (xy 5.653416 -8.060502) (xy 5.734135 -8.052552)
			(xy 5.77469 -8.052054) (xy 5.815245 -8.052552) (xy 5.895964 -8.060502) (xy 5.975515 -8.076325) (xy 6.053131 -8.09987)
			(xy 6.128067 -8.130909) (xy 6.199599 -8.169144) (xy 6.267039 -8.214206) (xy 6.329738 -8.265661) (xy 6.387091 -8.323014)
			(xy 6.438546 -8.385713) (xy 6.483608 -8.453153) (xy 6.521843 -8.524685) (xy 6.552882 -8.599621) (xy 6.576427 -8.677237)
			(xy 6.59225 -8.756788) (xy 6.6002 -8.837507) (xy 6.6002 -8.918617) (xy 10.02918 -8.918617) (xy 10.02918 -8.837507)
			(xy 10.03713 -8.756788) (xy 10.052953 -8.677237) (xy 10.076498 -8.599621) (xy 10.107537 -8.524685)
			(xy 10.145772 -8.453153) (xy 10.190834 -8.385713) (xy 10.242289 -8.323014) (xy 10.299642 -8.265661)
			(xy 10.362341 -8.214206) (xy 10.429781 -8.169144) (xy 10.501313 -8.130909) (xy 10.576249 -8.09987)
			(xy 10.653865 -8.076325) (xy 10.733416 -8.060502) (xy 10.814135 -8.052552) (xy 10.85469 -8.052054)
			(xy 10.875375 -8.052308) (xy 12.568936 -8.052308) (xy 14.220444 -8.052308) (xy 14.220444 -9.703816)
			(xy 12.568936 -9.703816) (xy 12.568936 -8.052308) (xy 10.875375 -8.052308) (xy 10.895245 -8.052552)
			(xy 10.975964 -8.060502) (xy 11.055515 -8.076325) (xy 11.133131 -8.09987) (xy 11.208067 -8.130909)
			(xy 11.279599 -8.169144) (xy 11.347039 -8.214206) (xy 11.409738 -8.265661) (xy 11.467091 -8.323014)
			(xy 11.518546 -8.385713) (xy 11.563608 -8.453153) (xy 11.601843 -8.524685) (xy 11.632882 -8.599621)
			(xy 11.656427 -8.677237) (xy 11.67225 -8.756788) (xy 11.6802 -8.837507) (xy 11.6802 -8.918617) (xy 11.67225 -8.999336)
			(xy 11.656427 -9.078887) (xy 11.632882 -9.156503) (xy 11.601843 -9.231439) (xy 11.563608 -9.302971)
			(xy 11.518546 -9.370411) (xy 11.467091 -9.43311) (xy 11.409738 -9.490463) (xy 11.347039 -9.541918)
			(xy 11.279599 -9.58698) (xy 11.208067 -9.625215) (xy 11.133131 -9.656254) (xy 11.055515 -9.679799)
			(xy 10.975964 -9.695622) (xy 10.895245 -9.703572) (xy 10.814135 -9.703572) (xy 10.733416 -9.695622)
			(xy 10.653865 -9.679799) (xy 10.576249 -9.656254) (xy 10.501313 -9.625215) (xy 10.429781 -9.58698)
			(xy 10.362341 -9.541918) (xy 10.299642 -9.490463) (xy 10.242289 -9.43311) (xy 10.190834 -9.370411)
			(xy 10.145772 -9.302971) (xy 10.107537 -9.231439) (xy 10.076498 -9.156503) (xy 10.052953 -9.078887)
			(xy 10.03713 -8.999336) (xy 10.02918 -8.918617) (xy 6.6002 -8.918617) (xy 6.59225 -8.999336) (xy 6.576427 -9.078887)
			(xy 6.552882 -9.156503) (xy 6.521843 -9.231439) (xy 6.483608 -9.302971) (xy 6.438546 -9.370411) (xy 6.387091 -9.43311)
			(xy 6.329738 -9.490463) (xy 6.267039 -9.541918) (xy 6.199599 -9.58698) (xy 6.128067 -9.625215) (xy 6.053131 -9.656254)
			(xy 5.975515 -9.679799) (xy 5.895964 -9.695622) (xy 5.815245 -9.703572) (xy 5.734135 -9.703572) (xy 5.653416 -9.695622)
			(xy 5.573865 -9.679799) (xy 5.496249 -9.656254) (xy 5.421313 -9.625215) (xy 5.349781 -9.58698) (xy 5.282341 -9.541918)
			(xy 5.219642 -9.490463) (xy 5.162289 -9.43311) (xy 5.110834 -9.370411) (xy 5.065772 -9.302971) (xy 5.027537 -9.231439)
			(xy 4.996498 -9.156503) (xy 4.972953 -9.078887) (xy 4.95713 -8.999336) (xy 4.94918 -8.918617) (xy 0.509016 -8.918617)
			(xy 0.509016 -15.260473) (xy 1.150876 -15.260473) (xy 1.152892 -15.13086) (xy 1.162962 -15.001624)
			(xy 1.181047 -14.873263) (xy 1.207077 -14.746275) (xy 1.240952 -14.621151) (xy 1.28254 -14.498375)
			(xy 1.331681 -14.378422) (xy 1.388184 -14.261757) (xy 1.451831 -14.148829) (xy 1.522375 -14.040077)
			(xy 1.599544 -13.935921) (xy 1.683039 -13.836764) (xy 1.772537 -13.74299) (xy 1.867692 -13.654961)
			(xy 1.968135 -13.573018) (xy 2.073478 -13.497479) (xy 2.183314 -13.428634) (xy 2.297218 -13.366751)
			(xy 2.414748 -13.31207) (xy 2.535451 -13.2648) (xy 2.658859 -13.225127) (xy 2.784495 -13.193202)
			(xy 2.911872 -13.16915) (xy 3.040498 -13.153063) (xy 3.169876 -13.145004) (xy 3.23469 -13.1445) (xy 3.299504 -13.145004)
			(xy 3.428882 -13.153063) (xy 3.557508 -13.16915) (xy 3.684885 -13.193202) (xy 3.810521 -13.225127)
			(xy 3.933929 -13.2648) (xy 4.054632 -13.31207) (xy 4.172162 -13.366751) (xy 4.286066 -13.428634)
			(xy 4.395902 -13.497479) (xy 4.501245 -13.573018) (xy 4.601688 -13.654961) (xy 4.696843 -13.74299)
			(xy 4.786341 -13.836764) (xy 4.869836 -13.935921) (xy 4.947005 -14.040077) (xy 5.017549 -14.148829)
			(xy 5.081196 -14.261757) (xy 5.137699 -14.378422) (xy 5.18684 -14.498375) (xy 5.228428 -14.621151)
			(xy 5.262303 -14.746275) (xy 5.288333 -14.873263) (xy 5.306418 -15.001624) (xy 5.316488 -15.13086)
			(xy 5.318504 -15.260473) (xy 12.580876 -15.260473) (xy 12.582892 -15.13086) (xy 12.592962 -15.001624)
			(xy 12.611047 -14.873263) (xy 12.637077 -14.746275) (xy 12.670952 -14.621151) (xy 12.71254 -14.498375)
			(xy 12.761681 -14.378422) (xy 12.818184 -14.261757) (xy 12.881831 -14.148829) (xy 12.952375 -14.040077)
			(xy 13.029544 -13.935921) (xy 13.113039 -13.836764) (xy 13.202537 -13.74299) (xy 13.297692 -13.654961)
			(xy 13.398135 -13.573018) (xy 13.503478 -13.497479) (xy 13.613314 -13.428634) (xy 13.727218 -13.366751)
			(xy 13.844748 -13.31207) (xy 13.965451 -13.2648) (xy 14.088859 -13.225127) (xy 14.214495 -13.193202)
			(xy 14.341872 -13.16915) (xy 14.470498 -13.153063) (xy 14.599876 -13.145004) (xy 14.66469 -13.1445)
			(xy 14.729504 -13.145004) (xy 14.858882 -13.153063) (xy 14.987508 -13.16915) (xy 15.114885 -13.193202)
			(xy 15.240521 -13.225127) (xy 15.363929 -13.2648) (xy 15.484632 -13.31207) (xy 15.602162 -13.366751)
			(xy 15.716066 -13.428634) (xy 15.825902 -13.497479) (xy 15.931245 -13.573018) (xy 16.031688 -13.654961)
			(xy 16.126843 -13.74299) (xy 16.216341 -13.836764) (xy 16.299836 -13.935921) (xy 16.377005 -14.040077)
			(xy 16.447549 -14.148829) (xy 16.511196 -14.261757) (xy 16.567699 -14.378422) (xy 16.61684 -14.498375)
			(xy 16.658428 -14.621151) (xy 16.692303 -14.746275) (xy 16.718333 -14.873263) (xy 16.736418 -15.001624)
			(xy 16.746488 -15.13086) (xy 16.748504 -15.260473) (xy 16.742458 -15.38996) (xy 16.728374 -15.518821)
			(xy 16.706305 -15.646557) (xy 16.676338 -15.772674) (xy 16.638589 -15.896684) (xy 16.593202 -16.018107)
			(xy 16.540355 -16.136474) (xy 16.480251 -16.251326) (xy 16.413123 -16.362219) (xy 16.339231 -16.468725)
			(xy 16.25886 -16.570431) (xy 16.172322 -16.666943) (xy 16.07995 -16.757888) (xy 15.982104 -16.842915)
			(xy 15.879161 -16.921695) (xy 15.771519 -16.993922) (xy 15.659595 -17.059317) (xy 15.543822 -17.117628)
			(xy 15.424648 -17.168628) (xy 15.302534 -17.21212) (xy 15.177951 -17.247937) (xy 15.051384 -17.275939)
			(xy 14.92332 -17.296018) (xy 14.794256 -17.308097) (xy 14.66469 -17.312128) (xy 14.535124 -17.308097)
			(xy 14.40606 -17.296018) (xy 14.277996 -17.275939) (xy 14.151429 -17.247937) (xy 14.026846 -17.21212)
			(xy 13.904732 -17.168628) (xy 13.785558 -17.117628) (xy 13.669785 -17.059317) (xy 13.557861 -16.993922)
			(xy 13.450219 -16.921695) (xy 13.347276 -16.842915) (xy 13.24943 -16.757888) (xy 13.157058 -16.666943)
			(xy 13.07052 -16.570431) (xy 12.990149 -16.468725) (xy 12.916257 -16.362219) (xy 12.849129 -16.251326)
			(xy 12.789025 -16.136474) (xy 12.736178 -16.018107) (xy 12.690791 -15.896684) (xy 12.653042 -15.772674)
			(xy 12.623075 -15.646557) (xy 12.601006 -15.518821) (xy 12.586922 -15.38996) (xy 12.580876 -15.260473)
			(xy 5.318504 -15.260473) (xy 5.312458 -15.38996) (xy 5.298374 -15.518821) (xy 5.276305 -15.646557)
			(xy 5.246338 -15.772674) (xy 5.208589 -15.896684) (xy 5.163202 -16.018107) (xy 5.110355 -16.136474)
			(xy 5.050251 -16.251326) (xy 4.983123 -16.362219) (xy 4.909231 -16.468725) (xy 4.82886 -16.570431)
			(xy 4.742322 -16.666943) (xy 4.64995 -16.757888) (xy 4.552104 -16.842915) (xy 4.449161 -16.921695)
			(xy 4.341519 -16.993922) (xy 4.229595 -17.059317) (xy 4.113822 -17.117628) (xy 3.994648 -17.168628)
			(xy 3.872534 -17.21212) (xy 3.747951 -17.247937) (xy 3.621384 -17.275939) (xy 3.49332 -17.296018)
			(xy 3.364256 -17.308097) (xy 3.23469 -17.312128) (xy 3.105124 -17.308097) (xy 2.97606 -17.296018)
			(xy 2.847996 -17.275939) (xy 2.721429 -17.247937) (xy 2.596846 -17.21212) (xy 2.474732 -17.168628)
			(xy 2.355558 -17.117628) (xy 2.239785 -17.059317) (xy 2.127861 -16.993922) (xy 2.020219 -16.921695)
			(xy 1.917276 -16.842915) (xy 1.81943 -16.757888) (xy 1.727058 -16.666943) (xy 1.64052 -16.570431)
			(xy 1.560149 -16.468725) (xy 1.486257 -16.362219) (xy 1.419129 -16.251326) (xy 1.359025 -16.136474)
			(xy 1.306178 -16.018107) (xy 1.260791 -15.896684) (xy 1.223042 -15.772674) (xy 1.193075 -15.646557)
			(xy 1.171006 -15.518821) (xy 1.156922 -15.38996) (xy 1.150876 -15.260473) (xy 0.509016 -15.260473)
			(xy 0.509016 -29.200094) (xy 11.599164 -29.200094) (xy 11.599658 -29.100658) (xy 11.607565 -28.901944)
			(xy 11.623365 -28.703701) (xy 11.647034 -28.506243) (xy 11.678535 -28.309883) (xy 11.717818 -28.114929)
			(xy 11.76482 -27.921692) (xy 11.819467 -27.730476) (xy 11.881674 -27.541584) (xy 11.95134 -27.355315)
			(xy 12.028358 -27.171962) (xy 12.112603 -26.991816) (xy 12.203944 -26.815162) (xy 12.302236 -26.642279)
			(xy 12.407324 -26.473441) (xy 12.519041 -26.308913) (xy 12.637211 -26.148958) (xy 12.761646 -25.993827)
			(xy 12.892151 -25.843765) (xy 13.028518 -25.699011) (xy 13.170532 -25.559793) (xy 13.317969 -25.42633)
			(xy 13.470596 -25.298835) (xy 13.62817 -25.177509) (xy 13.790444 -25.062543) (xy 13.957159 -24.954119)
			(xy 14.128054 -24.852409) (xy 14.302857 -24.757574) (xy 14.481292 -24.669763) (xy 14.663077 -24.589115)
			(xy 14.847925 -24.515759) (xy 15.035543 -24.449809) (xy 15.225635 -24.391371) (xy 15.417899 -24.340536)
			(xy 15.612033 -24.297385) (xy 15.807728 -24.261987) (xy 16.004677 -24.234396) (xy 16.202566 -24.214657)
			(xy 16.401084 -24.202801) (xy 16.599916 -24.198848) (xy 16.798748 -24.202801) (xy 16.997266 -24.214657)
			(xy 17.195155 -24.234396) (xy 17.392104 -24.261987) (xy 17.587799 -24.297385) (xy 17.781933 -24.340536)
			(xy 17.974197 -24.391371) (xy 18.164289 -24.449809) (xy 18.351907 -24.515759) (xy 18.536755 -24.589115)
			(xy 18.71854 -24.669763) (xy 18.896975 -24.757574) (xy 19.071778 -24.852409) (xy 19.242673 -24.954119)
			(xy 19.409388 -25.062543) (xy 19.571662 -25.177509) (xy 19.729236 -25.298835) (xy 19.881863 -25.42633)
			(xy 20.0293 -25.559793) (xy 20.171314 -25.699011) (xy 20.307681 -25.843765) (xy 20.438186 -25.993827)
			(xy 20.562621 -26.148958) (xy 20.680791 -26.308913) (xy 20.792508 -26.473441) (xy 20.897596 -26.642279)
			(xy 20.995888 -26.815162) (xy 21.087229 -26.991816) (xy 21.171474 -27.171962) (xy 21.248492 -27.355315)
			(xy 21.318158 -27.541584) (xy 21.380365 -27.730476) (xy 21.435012 -27.921692) (xy 21.482014 -28.114929)
			(xy 21.521297 -28.309883) (xy 21.552798 -28.506243) (xy 21.576467 -28.703701) (xy 21.592267 -28.901944)
			(xy 21.600174 -29.100658) (xy 21.600668 -29.200094) (xy 21.600174 -29.29953) (xy 21.592267 -29.498244)
			(xy 21.576467 -29.696487) (xy 21.552798 -29.893945) (xy 21.521297 -30.090305) (xy 21.482014 -30.285259)
			(xy 21.435012 -30.478496) (xy 21.380365 -30.669712) (xy 21.318158 -30.858604) (xy 21.248492 -31.044873)
			(xy 21.171474 -31.228226) (xy 21.087229 -31.408372) (xy 20.995888 -31.585026) (xy 20.897596 -31.757909)
			(xy 20.792508 -31.926747) (xy 20.680791 -32.091275) (xy 20.562621 -32.25123) (xy 20.438186 -32.406361)
			(xy 20.307681 -32.556423) (xy 20.171314 -32.701177) (xy 20.0293 -32.840395) (xy 19.881863 -32.973858)
			(xy 19.729236 -33.101353) (xy 19.571662 -33.222679) (xy 19.409388 -33.337645) (xy 19.242673 -33.446069)
			(xy 19.071778 -33.547779) (xy 18.896975 -33.642614) (xy 18.71854 -33.730425) (xy 18.536755 -33.811073)
			(xy 18.351907 -33.884429) (xy 18.164289 -33.950379) (xy 17.974197 -34.008817) (xy 17.781933 -34.059652)
			(xy 17.587799 -34.102803) (xy 17.392104 -34.138201) (xy 17.195155 -34.165792) (xy 16.997266 -34.185531)
			(xy 16.798748 -34.197387) (xy 16.599916 -34.201341) (xy 16.401084 -34.197387) (xy 16.202566 -34.185531)
			(xy 16.004677 -34.165792) (xy 15.807728 -34.138201) (xy 15.612033 -34.102803) (xy 15.417899 -34.059652)
			(xy 15.225635 -34.008817) (xy 15.035543 -33.950379) (xy 14.847925 -33.884429) (xy 14.663077 -33.811073)
			(xy 14.481292 -33.730425) (xy 14.302857 -33.642614) (xy 14.128054 -33.547779) (xy 13.957159 -33.446069)
			(xy 13.790444 -33.337645) (xy 13.62817 -33.222679) (xy 13.470596 -33.101353) (xy 13.317969 -32.973858)
			(xy 13.170532 -32.840395) (xy 13.028518 -32.701177) (xy 12.892151 -32.556423) (xy 12.761646 -32.406361)
			(xy 12.637211 -32.25123) (xy 12.519041 -32.091275) (xy 12.407324 -31.926747) (xy 12.302236 -31.757909)
			(xy 12.203944 -31.585026) (xy 12.112603 -31.408372) (xy 12.028358 -31.228226) (xy 11.95134 -31.044873)
			(xy 11.881674 -30.858604) (xy 11.819467 -30.669712) (xy 11.76482 -30.478496) (xy 11.717818 -30.285259)
			(xy 11.678535 -30.090305) (xy 11.647034 -29.893945) (xy 11.623365 -29.696487) (xy 11.607565 -29.498244)
			(xy 11.599658 -29.29953) (xy 11.599164 -29.200094) (xy 0.509016 -29.200094) (xy 0.509016 -46.254315)
			(xy 1.150876 -46.254315) (xy 1.152892 -46.124702) (xy 1.162962 -45.995466) (xy 1.181047 -45.867105)
			(xy 1.207077 -45.740117) (xy 1.240952 -45.614993) (xy 1.28254 -45.492217) (xy 1.331681 -45.372264)
			(xy 1.388184 -45.255599) (xy 1.451831 -45.142671) (xy 1.522375 -45.033919) (xy 1.599544 -44.929763)
			(xy 1.683039 -44.830606) (xy 1.772537 -44.736832) (xy 1.867692 -44.648803) (xy 1.968135 -44.56686)
			(xy 2.073478 -44.491321) (xy 2.183314 -44.422476) (xy 2.297218 -44.360593) (xy 2.414748 -44.305912)
			(xy 2.535451 -44.258642) (xy 2.658859 -44.218969) (xy 2.784495 -44.187044) (xy 2.911872 -44.162992)
			(xy 3.040498 -44.146905) (xy 3.169876 -44.138846) (xy 3.23469 -44.138342) (xy 3.299504 -44.138846)
			(xy 3.428882 -44.146905) (xy 3.557508 -44.162992) (xy 3.684885 -44.187044) (xy 3.810521 -44.218969)
			(xy 3.933929 -44.258642) (xy 4.054632 -44.305912) (xy 4.172162 -44.360593) (xy 4.286066 -44.422476)
			(xy 4.395902 -44.491321) (xy 4.501245 -44.56686) (xy 4.601688 -44.648803) (xy 4.696843 -44.736832)
			(xy 4.786341 -44.830606) (xy 4.869836 -44.929763) (xy 4.947005 -45.033919) (xy 5.017549 -45.142671)
			(xy 5.081196 -45.255599) (xy 5.137699 -45.372264) (xy 5.18684 -45.492217) (xy 5.228428 -45.614993)
			(xy 5.262303 -45.740117) (xy 5.288333 -45.867105) (xy 5.306418 -45.995466) (xy 5.316488 -46.124702)
			(xy 5.318504 -46.254315) (xy 12.580876 -46.254315) (xy 12.582892 -46.124702) (xy 12.592962 -45.995466)
			(xy 12.611047 -45.867105) (xy 12.637077 -45.740117) (xy 12.670952 -45.614993) (xy 12.71254 -45.492217)
			(xy 12.761681 -45.372264) (xy 12.818184 -45.255599) (xy 12.881831 -45.142671) (xy 12.952375 -45.033919)
			(xy 13.029544 -44.929763) (xy 13.113039 -44.830606) (xy 13.202537 -44.736832) (xy 13.297692 -44.648803)
			(xy 13.398135 -44.56686) (xy 13.503478 -44.491321) (xy 13.613314 -44.422476) (xy 13.727218 -44.360593)
			(xy 13.844748 -44.305912) (xy 13.965451 -44.258642) (xy 14.088859 -44.218969) (xy 14.214495 -44.187044)
			(xy 14.341872 -44.162992) (xy 14.470498 -44.146905) (xy 14.599876 -44.138846) (xy 14.66469 -44.138342)
			(xy 14.729504 -44.138846) (xy 14.858882 -44.146905) (xy 14.987508 -44.162992) (xy 15.114885 -44.187044)
			(xy 15.240521 -44.218969) (xy 15.363929 -44.258642) (xy 15.484632 -44.305912) (xy 15.602162 -44.360593)
			(xy 15.716066 -44.422476) (xy 15.825902 -44.491321) (xy 15.931245 -44.56686) (xy 16.031688 -44.648803)
			(xy 16.126843 -44.736832) (xy 16.216341 -44.830606) (xy 16.299836 -44.929763) (xy 16.377005 -45.033919)
			(xy 16.447549 -45.142671) (xy 16.511196 -45.255599) (xy 16.567699 -45.372264) (xy 16.61684 -45.492217)
			(xy 16.658428 -45.614993) (xy 16.692303 -45.740117) (xy 16.718333 -45.867105) (xy 16.736418 -45.995466)
			(xy 16.746488 -46.124702) (xy 16.748504 -46.254315) (xy 16.742458 -46.383802) (xy 16.728374 -46.512663)
			(xy 16.706305 -46.640399) (xy 16.676338 -46.766516) (xy 16.638589 -46.890526) (xy 16.593202 -47.011949)
			(xy 16.540355 -47.130316) (xy 16.480251 -47.245168) (xy 16.413123 -47.356061) (xy 16.339231 -47.462567)
			(xy 16.25886 -47.564273) (xy 16.172322 -47.660785) (xy 16.07995 -47.75173) (xy 15.982104 -47.836757)
			(xy 15.879161 -47.915537) (xy 15.771519 -47.987764) (xy 15.659595 -48.053159) (xy 15.543822 -48.11147)
			(xy 15.424648 -48.16247) (xy 15.302534 -48.205962) (xy 15.177951 -48.241779) (xy 15.051384 -48.269781)
			(xy 14.92332 -48.28986) (xy 14.794256 -48.301939) (xy 14.66469 -48.30597) (xy 14.535124 -48.301939)
			(xy 14.40606 -48.28986) (xy 14.277996 -48.269781) (xy 14.151429 -48.241779) (xy 14.026846 -48.205962)
			(xy 13.904732 -48.16247) (xy 13.785558 -48.11147) (xy 13.669785 -48.053159) (xy 13.557861 -47.987764)
			(xy 13.450219 -47.915537) (xy 13.347276 -47.836757) (xy 13.24943 -47.75173) (xy 13.157058 -47.660785)
			(xy 13.07052 -47.564273) (xy 12.990149 -47.462567) (xy 12.916257 -47.356061) (xy 12.849129 -47.245168)
			(xy 12.789025 -47.130316) (xy 12.736178 -47.011949) (xy 12.690791 -46.890526) (xy 12.653042 -46.766516)
			(xy 12.623075 -46.640399) (xy 12.601006 -46.512663) (xy 12.586922 -46.383802) (xy 12.580876 -46.254315)
			(xy 5.318504 -46.254315) (xy 5.312458 -46.383802) (xy 5.298374 -46.512663) (xy 5.276305 -46.640399)
			(xy 5.246338 -46.766516) (xy 5.208589 -46.890526) (xy 5.163202 -47.011949) (xy 5.110355 -47.130316)
			(xy 5.050251 -47.245168) (xy 4.983123 -47.356061) (xy 4.909231 -47.462567) (xy 4.82886 -47.564273)
			(xy 4.742322 -47.660785) (xy 4.64995 -47.75173) (xy 4.552104 -47.836757) (xy 4.449161 -47.915537)
			(xy 4.341519 -47.987764) (xy 4.229595 -48.053159) (xy 4.113822 -48.11147) (xy 3.994648 -48.16247)
			(xy 3.872534 -48.205962) (xy 3.747951 -48.241779) (xy 3.621384 -48.269781) (xy 3.49332 -48.28986)
			(xy 3.364256 -48.301939) (xy 3.23469 -48.30597) (xy 3.105124 -48.301939) (xy 2.97606 -48.28986) (xy 2.847996 -48.269781)
			(xy 2.721429 -48.241779) (xy 2.596846 -48.205962) (xy 2.474732 -48.16247) (xy 2.355558 -48.11147)
			(xy 2.239785 -48.053159) (xy 2.127861 -47.987764) (xy 2.020219 -47.915537) (xy 1.917276 -47.836757)
			(xy 1.81943 -47.75173) (xy 1.727058 -47.660785) (xy 1.64052 -47.564273) (xy 1.560149 -47.462567)
			(xy 1.486257 -47.356061) (xy 1.419129 -47.245168) (xy 1.359025 -47.130316) (xy 1.306178 -47.011949)
			(xy 1.260791 -46.890526) (xy 1.223042 -46.766516) (xy 1.193075 -46.640399) (xy 1.171006 -46.512663)
			(xy 1.156922 -46.383802) (xy 1.150876 -46.254315) (xy 0.509016 -46.254315) (xy 0.509016 -51.745896)
			(xy 3.678936 -51.745896) (xy 5.330444 -51.745896) (xy 5.330444 -52.612459) (xy 6.21918 -52.612459)
			(xy 6.21918 -52.531349) (xy 6.22713 -52.45063) (xy 6.242953 -52.371079) (xy 6.266498 -52.293463)
			(xy 6.297537 -52.218527) (xy 6.335772 -52.146995) (xy 6.380834 -52.079555) (xy 6.432289 -52.016856)
			(xy 6.489642 -51.959503) (xy 6.552341 -51.908048) (xy 6.619781 -51.862986) (xy 6.691313 -51.824751)
			(xy 6.766249 -51.793712) (xy 6.843865 -51.770167) (xy 6.923416 -51.754344) (xy 7.004135 -51.746394)
			(xy 7.04469 -51.745896) (xy 7.085245 -51.746394) (xy 7.165964 -51.754344) (xy 7.245515 -51.770167)
			(xy 7.323131 -51.793712) (xy 7.398067 -51.824751) (xy 7.469599 -51.862986) (xy 7.537039 -51.908048)
			(xy 7.599738 -51.959503) (xy 7.657091 -52.016856) (xy 7.708546 -52.079555) (xy 7.753608 -52.146995)
			(xy 7.791843 -52.218527) (xy 7.822882 -52.293463) (xy 7.846427 -52.371079) (xy 7.86225 -52.45063)
			(xy 7.8702 -52.531349) (xy 7.8702 -52.612459) (xy 11.29918 -52.612459) (xy 11.29918 -52.531349) (xy 11.30713 -52.45063)
			(xy 11.322953 -52.371079) (xy 11.346498 -52.293463) (xy 11.377537 -52.218527) (xy 11.415772 -52.146995)
			(xy 11.460834 -52.079555) (xy 11.512289 -52.016856) (xy 11.569642 -51.959503) (xy 11.632341 -51.908048)
			(xy 11.699781 -51.862986) (xy 11.771313 -51.824751) (xy 11.846249 -51.793712) (xy 11.923865 -51.770167)
			(xy 12.003416 -51.754344) (xy 12.084135 -51.746394) (xy 12.12469 -51.745896) (xy 12.165245 -51.746394)
			(xy 12.245964 -51.754344) (xy 12.325515 -51.770167) (xy 12.403131 -51.793712) (xy 12.478067 -51.824751)
			(xy 12.549599 -51.862986) (xy 12.617039 -51.908048) (xy 12.679738 -51.959503) (xy 12.737091 -52.016856)
			(xy 12.788546 -52.079555) (xy 12.833608 -52.146995) (xy 12.871843 -52.218527) (xy 12.902882 -52.293463)
			(xy 12.926427 -52.371079) (xy 12.94225 -52.45063) (xy 12.9502 -52.531349) (xy 12.9502 -52.612459)
			(xy 12.94225 -52.693178) (xy 12.926427 -52.772729) (xy 12.902882 -52.850345) (xy 12.871843 -52.925281)
			(xy 12.833608 -52.996813) (xy 12.788546 -53.064253) (xy 12.737091 -53.126952) (xy 12.679738 -53.184305)
			(xy 12.617039 -53.23576) (xy 12.549599 -53.280822) (xy 12.478067 -53.319057) (xy 12.403131 -53.350096)
			(xy 12.325515 -53.373641) (xy 12.245964 -53.389464) (xy 12.165245 -53.397414) (xy 12.084135 -53.397414)
			(xy 12.003416 -53.389464) (xy 11.923865 -53.373641) (xy 11.846249 -53.350096) (xy 11.771313 -53.319057)
			(xy 11.699781 -53.280822) (xy 11.632341 -53.23576) (xy 11.569642 -53.184305) (xy 11.512289 -53.126952)
			(xy 11.460834 -53.064253) (xy 11.415772 -52.996813) (xy 11.377537 -52.925281) (xy 11.346498 -52.850345)
			(xy 11.322953 -52.772729) (xy 11.30713 -52.693178) (xy 11.29918 -52.612459) (xy 7.8702 -52.612459)
			(xy 7.86225 -52.693178) (xy 7.846427 -52.772729) (xy 7.822882 -52.850345) (xy 7.791843 -52.925281)
			(xy 7.753608 -52.996813) (xy 7.708546 -53.064253) (xy 7.657091 -53.126952) (xy 7.599738 -53.184305)
			(xy 7.537039 -53.23576) (xy 7.469599 -53.280822) (xy 7.398067 -53.319057) (xy 7.323131 -53.350096)
			(xy 7.245515 -53.373641) (xy 7.165964 -53.389464) (xy 7.085245 -53.397414) (xy 7.004135 -53.397414)
			(xy 6.923416 -53.389464) (xy 6.843865 -53.373641) (xy 6.766249 -53.350096) (xy 6.691313 -53.319057)
			(xy 6.619781 -53.280822) (xy 6.552341 -53.23576) (xy 6.489642 -53.184305) (xy 6.432289 -53.126952)
			(xy 6.380834 -53.064253) (xy 6.335772 -52.996813) (xy 6.297537 -52.925281) (xy 6.266498 -52.850345)
			(xy 6.242953 -52.772729) (xy 6.22713 -52.693178) (xy 6.21918 -52.612459) (xy 5.330444 -52.612459)
			(xy 5.330444 -53.397912) (xy 3.678936 -53.397912) (xy 3.678936 -51.745896) (xy 0.509016 -51.745896)
			(xy 0.509016 -55.152459) (xy 4.94918 -55.152459) (xy 4.94918 -55.071349) (xy 4.95713 -54.99063) (xy 4.972953 -54.911079)
			(xy 4.996498 -54.833463) (xy 5.027537 -54.758527) (xy 5.065772 -54.686995) (xy 5.110834 -54.619555)
			(xy 5.162289 -54.556856) (xy 5.219642 -54.499503) (xy 5.282341 -54.448048) (xy 5.349781 -54.402986)
			(xy 5.421313 -54.364751) (xy 5.496249 -54.333712) (xy 5.573865 -54.310167) (xy 5.653416 -54.294344)
			(xy 5.734135 -54.286394) (xy 5.77469 -54.285896) (xy 5.815245 -54.286394) (xy 5.895964 -54.294344)
			(xy 5.975515 -54.310167) (xy 6.053131 -54.333712) (xy 6.128067 -54.364751) (xy 6.199599 -54.402986)
			(xy 6.267039 -54.448048) (xy 6.329738 -54.499503) (xy 6.387091 -54.556856) (xy 6.438546 -54.619555)
			(xy 6.483608 -54.686995) (xy 6.521843 -54.758527) (xy 6.552882 -54.833463) (xy 6.576427 -54.911079)
			(xy 6.59225 -54.99063) (xy 6.6002 -55.071349) (xy 6.6002 -55.152459) (xy 10.02918 -55.152459) (xy 10.02918 -55.071349)
			(xy 10.03713 -54.99063) (xy 10.052953 -54.911079) (xy 10.076498 -54.833463) (xy 10.107537 -54.758527)
			(xy 10.145772 -54.686995) (xy 10.190834 -54.619555) (xy 10.242289 -54.556856) (xy 10.299642 -54.499503)
			(xy 10.362341 -54.448048) (xy 10.429781 -54.402986) (xy 10.501313 -54.364751) (xy 10.576249 -54.333712)
			(xy 10.653865 -54.310167) (xy 10.733416 -54.294344) (xy 10.814135 -54.286394) (xy 10.85469 -54.285896)
			(xy 10.895245 -54.286394) (xy 10.975964 -54.294344) (xy 11.055515 -54.310167) (xy 11.133131 -54.333712)
			(xy 11.208067 -54.364751) (xy 11.279599 -54.402986) (xy 11.347039 -54.448048) (xy 11.409738 -54.499503)
			(xy 11.467091 -54.556856) (xy 11.518546 -54.619555) (xy 11.563608 -54.686995) (xy 11.601843 -54.758527)
			(xy 11.632882 -54.833463) (xy 11.656427 -54.911079) (xy 11.67225 -54.99063) (xy 11.6802 -55.071349)
			(xy 11.6802 -55.152459) (xy 12.56918 -55.152459) (xy 12.56918 -55.071349) (xy 12.57713 -54.99063)
			(xy 12.592953 -54.911079) (xy 12.616498 -54.833463) (xy 12.647537 -54.758527) (xy 12.685772 -54.686995)
			(xy 12.730834 -54.619555) (xy 12.782289 -54.556856) (xy 12.839642 -54.499503) (xy 12.902341 -54.448048)
			(xy 12.969781 -54.402986) (xy 13.041313 -54.364751) (xy 13.116249 -54.333712) (xy 13.193865 -54.310167)
			(xy 13.273416 -54.294344) (xy 13.354135 -54.286394) (xy 13.39469 -54.285896) (xy 13.435245 -54.286394)
			(xy 13.515964 -54.294344) (xy 13.595515 -54.310167) (xy 13.673131 -54.333712) (xy 13.748067 -54.364751)
			(xy 13.819599 -54.402986) (xy 13.887039 -54.448048) (xy 13.949738 -54.499503) (xy 14.007091 -54.556856)
			(xy 14.058546 -54.619555) (xy 14.103608 -54.686995) (xy 14.141843 -54.758527) (xy 14.172882 -54.833463)
			(xy 14.196427 -54.911079) (xy 14.21225 -54.99063) (xy 14.2202 -55.071349) (xy 14.2202 -55.152459)
			(xy 14.21225 -55.233178) (xy 14.196427 -55.312729) (xy 14.172882 -55.390345) (xy 14.141843 -55.465281)
			(xy 14.103608 -55.536813) (xy 14.058546 -55.604253) (xy 14.007091 -55.666952) (xy 13.949738 -55.724305)
			(xy 13.887039 -55.77576) (xy 13.819599 -55.820822) (xy 13.748067 -55.859057) (xy 13.673131 -55.890096)
			(xy 13.595515 -55.913641) (xy 13.515964 -55.929464) (xy 13.435245 -55.937414) (xy 13.354135 -55.937414)
			(xy 13.273416 -55.929464) (xy 13.193865 -55.913641) (xy 13.116249 -55.890096) (xy 13.041313 -55.859057)
			(xy 12.969781 -55.820822) (xy 12.902341 -55.77576) (xy 12.839642 -55.724305) (xy 12.782289 -55.666952)
			(xy 12.730834 -55.604253) (xy 12.685772 -55.536813) (xy 12.647537 -55.465281) (xy 12.616498 -55.390345)
			(xy 12.592953 -55.312729) (xy 12.57713 -55.233178) (xy 12.56918 -55.152459) (xy 11.6802 -55.152459)
			(xy 11.67225 -55.233178) (xy 11.656427 -55.312729) (xy 11.632882 -55.390345) (xy 11.601843 -55.465281)
			(xy 11.563608 -55.536813) (xy 11.518546 -55.604253) (xy 11.467091 -55.666952) (xy 11.409738 -55.724305)
			(xy 11.347039 -55.77576) (xy 11.279599 -55.820822) (xy 11.208067 -55.859057) (xy 11.133131 -55.890096)
			(xy 11.055515 -55.913641) (xy 10.975964 -55.929464) (xy 10.895245 -55.937414) (xy 10.814135 -55.937414)
			(xy 10.733416 -55.929464) (xy 10.653865 -55.913641) (xy 10.576249 -55.890096) (xy 10.501313 -55.859057)
			(xy 10.429781 -55.820822) (xy 10.362341 -55.77576) (xy 10.299642 -55.724305) (xy 10.242289 -55.666952)
			(xy 10.190834 -55.604253) (xy 10.145772 -55.536813) (xy 10.107537 -55.465281) (xy 10.076498 -55.390345)
			(xy 10.052953 -55.312729) (xy 10.03713 -55.233178) (xy 10.02918 -55.152459) (xy 6.6002 -55.152459)
			(xy 6.59225 -55.233178) (xy 6.576427 -55.312729) (xy 6.552882 -55.390345) (xy 6.521843 -55.465281)
			(xy 6.483608 -55.536813) (xy 6.438546 -55.604253) (xy 6.387091 -55.666952) (xy 6.329738 -55.724305)
			(xy 6.267039 -55.77576) (xy 6.199599 -55.820822) (xy 6.128067 -55.859057) (xy 6.053131 -55.890096)
			(xy 5.975515 -55.913641) (xy 5.895964 -55.929464) (xy 5.815245 -55.937414) (xy 5.734135 -55.937414)
			(xy 5.653416 -55.929464) (xy 5.573865 -55.913641) (xy 5.496249 -55.890096) (xy 5.421313 -55.859057)
			(xy 5.349781 -55.820822) (xy 5.282341 -55.77576) (xy 5.219642 -55.724305) (xy 5.162289 -55.666952)
			(xy 5.110834 -55.604253) (xy 5.065772 -55.536813) (xy 5.027537 -55.465281) (xy 4.996498 -55.390345)
			(xy 4.972953 -55.312729) (xy 4.95713 -55.233178) (xy 4.94918 -55.152459) (xy 0.509016 -55.152459)
			(xy 0.509016 -59.428549) (xy 3.67918 -59.428549) (xy 3.67918 -59.347439) (xy 3.68713 -59.26672) (xy 3.702953 -59.187169)
			(xy 3.726498 -59.109553) (xy 3.757537 -59.034617) (xy 3.795772 -58.963085) (xy 3.840834 -58.895645)
			(xy 3.892289 -58.832946) (xy 3.949642 -58.775593) (xy 4.012341 -58.724138) (xy 4.079781 -58.679076)
			(xy 4.151313 -58.640841) (xy 4.226249 -58.609802) (xy 4.303865 -58.586257) (xy 4.383416 -58.570434)
			(xy 4.464135 -58.562484) (xy 4.50469 -58.561986) (xy 4.545245 -58.562484) (xy 4.625964 -58.570434)
			(xy 4.705515 -58.586257) (xy 4.783131 -58.609802) (xy 4.858067 -58.640841) (xy 4.929599 -58.679076)
			(xy 4.997039 -58.724138) (xy 5.059738 -58.775593) (xy 5.117091 -58.832946) (xy 5.168546 -58.895645)
			(xy 5.213608 -58.963085) (xy 5.251843 -59.034617) (xy 5.282882 -59.109553) (xy 5.306427 -59.187169)
			(xy 5.32225 -59.26672) (xy 5.3302 -59.347439) (xy 5.3302 -59.428549) (xy 6.21918 -59.428549) (xy 6.21918 -59.347439)
			(xy 6.22713 -59.26672) (xy 6.242953 -59.187169) (xy 6.266498 -59.109553) (xy 6.297537 -59.034617)
			(xy 6.335772 -58.963085) (xy 6.380834 -58.895645) (xy 6.432289 -58.832946) (xy 6.489642 -58.775593)
			(xy 6.552341 -58.724138) (xy 6.619781 -58.679076) (xy 6.691313 -58.640841) (xy 6.766249 -58.609802)
			(xy 6.843865 -58.586257) (xy 6.923416 -58.570434) (xy 7.004135 -58.562484) (xy 7.04469 -58.561986)
			(xy 7.085245 -58.562484) (xy 7.165964 -58.570434) (xy 7.245515 -58.586257) (xy 7.323131 -58.609802)
			(xy 7.398067 -58.640841) (xy 7.469599 -58.679076) (xy 7.537039 -58.724138) (xy 7.599738 -58.775593)
			(xy 7.657091 -58.832946) (xy 7.708546 -58.895645) (xy 7.753608 -58.963085) (xy 7.791843 -59.034617)
			(xy 7.822882 -59.109553) (xy 7.846427 -59.187169) (xy 7.86225 -59.26672) (xy 7.8702 -59.347439) (xy 7.8702 -59.428549)
			(xy 8.75918 -59.428549) (xy 8.75918 -59.347439) (xy 8.76713 -59.26672) (xy 8.782953 -59.187169) (xy 8.806498 -59.109553)
			(xy 8.837537 -59.034617) (xy 8.875772 -58.963085) (xy 8.920834 -58.895645) (xy 8.972289 -58.832946)
			(xy 9.029642 -58.775593) (xy 9.092341 -58.724138) (xy 9.159781 -58.679076) (xy 9.231313 -58.640841)
			(xy 9.306249 -58.609802) (xy 9.383865 -58.586257) (xy 9.463416 -58.570434) (xy 9.544135 -58.562484)
			(xy 9.58469 -58.561986) (xy 9.625245 -58.562484) (xy 9.705964 -58.570434) (xy 9.785515 -58.586257)
			(xy 9.863131 -58.609802) (xy 9.938067 -58.640841) (xy 10.009599 -58.679076) (xy 10.077039 -58.724138)
			(xy 10.139738 -58.775593) (xy 10.197091 -58.832946) (xy 10.248546 -58.895645) (xy 10.293608 -58.963085)
			(xy 10.331843 -59.034617) (xy 10.362882 -59.109553) (xy 10.386427 -59.187169) (xy 10.40225 -59.26672)
			(xy 10.4102 -59.347439) (xy 10.4102 -59.428549) (xy 11.29918 -59.428549) (xy 11.29918 -59.347439)
			(xy 11.30713 -59.26672) (xy 11.322953 -59.187169) (xy 11.346498 -59.109553) (xy 11.377537 -59.034617)
			(xy 11.415772 -58.963085) (xy 11.460834 -58.895645) (xy 11.512289 -58.832946) (xy 11.569642 -58.775593)
			(xy 11.632341 -58.724138) (xy 11.699781 -58.679076) (xy 11.771313 -58.640841) (xy 11.846249 -58.609802)
			(xy 11.923865 -58.586257) (xy 12.003416 -58.570434) (xy 12.084135 -58.562484) (xy 12.12469 -58.561986)
			(xy 12.165245 -58.562484) (xy 12.245964 -58.570434) (xy 12.325515 -58.586257) (xy 12.403131 -58.609802)
			(xy 12.478067 -58.640841) (xy 12.549599 -58.679076) (xy 12.617039 -58.724138) (xy 12.679738 -58.775593)
			(xy 12.737091 -58.832946) (xy 12.788546 -58.895645) (xy 12.833608 -58.963085) (xy 12.871843 -59.034617)
			(xy 12.902882 -59.109553) (xy 12.926427 -59.187169) (xy 12.94225 -59.26672) (xy 12.9502 -59.347439)
			(xy 12.9502 -59.428549) (xy 12.94225 -59.509268) (xy 12.926427 -59.588819) (xy 12.902882 -59.666435)
			(xy 12.871843 -59.741371) (xy 12.833608 -59.812903) (xy 12.788546 -59.880343) (xy 12.737091 -59.943042)
			(xy 12.679738 -60.000395) (xy 12.617039 -60.05185) (xy 12.549599 -60.096912) (xy 12.478067 -60.135147)
			(xy 12.403131 -60.166186) (xy 12.325515 -60.189731) (xy 12.245964 -60.205554) (xy 12.165245 -60.213504)
			(xy 12.084135 -60.213504) (xy 12.003416 -60.205554) (xy 11.923865 -60.189731) (xy 11.846249 -60.166186)
			(xy 11.771313 -60.135147) (xy 11.699781 -60.096912) (xy 11.632341 -60.05185) (xy 11.569642 -60.000395)
			(xy 11.512289 -59.943042) (xy 11.460834 -59.880343) (xy 11.415772 -59.812903) (xy 11.377537 -59.741371)
			(xy 11.346498 -59.666435) (xy 11.322953 -59.588819) (xy 11.30713 -59.509268) (xy 11.29918 -59.428549)
			(xy 10.4102 -59.428549) (xy 10.40225 -59.509268) (xy 10.386427 -59.588819) (xy 10.362882 -59.666435)
			(xy 10.331843 -59.741371) (xy 10.293608 -59.812903) (xy 10.248546 -59.880343) (xy 10.197091 -59.943042)
			(xy 10.139738 -60.000395) (xy 10.077039 -60.05185) (xy 10.009599 -60.096912) (xy 9.938067 -60.135147)
			(xy 9.863131 -60.166186) (xy 9.785515 -60.189731) (xy 9.705964 -60.205554) (xy 9.625245 -60.213504)
			(xy 9.544135 -60.213504) (xy 9.463416 -60.205554) (xy 9.383865 -60.189731) (xy 9.306249 -60.166186)
			(xy 9.231313 -60.135147) (xy 9.159781 -60.096912) (xy 9.092341 -60.05185) (xy 9.029642 -60.000395)
			(xy 8.972289 -59.943042) (xy 8.920834 -59.880343) (xy 8.875772 -59.812903) (xy 8.837537 -59.741371)
			(xy 8.806498 -59.666435) (xy 8.782953 -59.588819) (xy 8.76713 -59.509268) (xy 8.75918 -59.428549)
			(xy 7.8702 -59.428549) (xy 7.86225 -59.509268) (xy 7.846427 -59.588819) (xy 7.822882 -59.666435)
			(xy 7.791843 -59.741371) (xy 7.753608 -59.812903) (xy 7.708546 -59.880343) (xy 7.657091 -59.943042)
			(xy 7.599738 -60.000395) (xy 7.537039 -60.05185) (xy 7.469599 -60.096912) (xy 7.398067 -60.135147)
			(xy 7.323131 -60.166186) (xy 7.245515 -60.189731) (xy 7.165964 -60.205554) (xy 7.085245 -60.213504)
			(xy 7.004135 -60.213504) (xy 6.923416 -60.205554) (xy 6.843865 -60.189731) (xy 6.766249 -60.166186)
			(xy 6.691313 -60.135147) (xy 6.619781 -60.096912) (xy 6.552341 -60.05185) (xy 6.489642 -60.000395)
			(xy 6.432289 -59.943042) (xy 6.380834 -59.880343) (xy 6.335772 -59.812903) (xy 6.297537 -59.741371)
			(xy 6.266498 -59.666435) (xy 6.242953 -59.588819) (xy 6.22713 -59.509268) (xy 6.21918 -59.428549)
			(xy 5.3302 -59.428549) (xy 5.32225 -59.509268) (xy 5.306427 -59.588819) (xy 5.282882 -59.666435)
			(xy 5.251843 -59.741371) (xy 5.213608 -59.812903) (xy 5.168546 -59.880343) (xy 5.117091 -59.943042)
			(xy 5.059738 -60.000395) (xy 4.997039 -60.05185) (xy 4.929599 -60.096912) (xy 4.858067 -60.135147)
			(xy 4.783131 -60.166186) (xy 4.705515 -60.189731) (xy 4.625964 -60.205554) (xy 4.545245 -60.213504)
			(xy 4.464135 -60.213504) (xy 4.383416 -60.205554) (xy 4.303865 -60.189731) (xy 4.226249 -60.166186)
			(xy 4.151313 -60.135147) (xy 4.079781 -60.096912) (xy 4.012341 -60.05185) (xy 3.949642 -60.000395)
			(xy 3.892289 -59.943042) (xy 3.840834 -59.880343) (xy 3.795772 -59.812903) (xy 3.757537 -59.741371)
			(xy 3.726498 -59.666435) (xy 3.702953 -59.588819) (xy 3.68713 -59.509268) (xy 3.67918 -59.428549)
			(xy 0.509016 -59.428549) (xy 0.509016 -61.968549) (xy 4.94918 -61.968549) (xy 4.94918 -61.887439)
			(xy 4.95713 -61.80672) (xy 4.972953 -61.727169) (xy 4.996498 -61.649553) (xy 5.027537 -61.574617)
			(xy 5.065772 -61.503085) (xy 5.110834 -61.435645) (xy 5.162289 -61.372946) (xy 5.219642 -61.315593)
			(xy 5.282341 -61.264138) (xy 5.349781 -61.219076) (xy 5.421313 -61.180841) (xy 5.496249 -61.149802)
			(xy 5.573865 -61.126257) (xy 5.653416 -61.110434) (xy 5.734135 -61.102484) (xy 5.77469 -61.101986)
			(xy 5.815245 -61.102484) (xy 5.895964 -61.110434) (xy 5.975515 -61.126257) (xy 6.053131 -61.149802)
			(xy 6.128067 -61.180841) (xy 6.199599 -61.219076) (xy 6.267039 -61.264138) (xy 6.329738 -61.315593)
			(xy 6.387091 -61.372946) (xy 6.438546 -61.435645) (xy 6.483608 -61.503085) (xy 6.521843 -61.574617)
			(xy 6.552882 -61.649553) (xy 6.576427 -61.727169) (xy 6.59225 -61.80672) (xy 6.6002 -61.887439) (xy 6.6002 -61.968549)
			(xy 10.02918 -61.968549) (xy 10.02918 -61.887439) (xy 10.03713 -61.80672) (xy 10.052953 -61.727169)
			(xy 10.076498 -61.649553) (xy 10.107537 -61.574617) (xy 10.145772 -61.503085) (xy 10.190834 -61.435645)
			(xy 10.242289 -61.372946) (xy 10.299642 -61.315593) (xy 10.362341 -61.264138) (xy 10.429781 -61.219076)
			(xy 10.501313 -61.180841) (xy 10.576249 -61.149802) (xy 10.653865 -61.126257) (xy 10.733416 -61.110434)
			(xy 10.814135 -61.102484) (xy 10.85469 -61.101986) (xy 10.875375 -61.10224) (xy 12.568936 -61.10224)
			(xy 14.220444 -61.10224) (xy 14.220444 -62.753748) (xy 12.568936 -62.753748) (xy 12.568936 -61.10224)
			(xy 10.875375 -61.10224) (xy 10.895245 -61.102484) (xy 10.975964 -61.110434) (xy 11.055515 -61.126257)
			(xy 11.133131 -61.149802) (xy 11.208067 -61.180841) (xy 11.279599 -61.219076) (xy 11.347039 -61.264138)
			(xy 11.409738 -61.315593) (xy 11.467091 -61.372946) (xy 11.518546 -61.435645) (xy 11.563608 -61.503085)
			(xy 11.601843 -61.574617) (xy 11.632882 -61.649553) (xy 11.656427 -61.727169) (xy 11.67225 -61.80672)
			(xy 11.6802 -61.887439) (xy 11.6802 -61.968549) (xy 11.67225 -62.049268) (xy 11.656427 -62.128819)
			(xy 11.632882 -62.206435) (xy 11.601843 -62.281371) (xy 11.563608 -62.352903) (xy 11.518546 -62.420343)
			(xy 11.467091 -62.483042) (xy 11.409738 -62.540395) (xy 11.347039 -62.59185) (xy 11.279599 -62.636912)
			(xy 11.208067 -62.675147) (xy 11.133131 -62.706186) (xy 11.055515 -62.729731) (xy 10.975964 -62.745554)
			(xy 10.895245 -62.753504) (xy 10.814135 -62.753504) (xy 10.733416 -62.745554) (xy 10.653865 -62.729731)
			(xy 10.576249 -62.706186) (xy 10.501313 -62.675147) (xy 10.429781 -62.636912) (xy 10.362341 -62.59185)
			(xy 10.299642 -62.540395) (xy 10.242289 -62.483042) (xy 10.190834 -62.420343) (xy 10.145772 -62.352903)
			(xy 10.107537 -62.281371) (xy 10.076498 -62.206435) (xy 10.052953 -62.128819) (xy 10.03713 -62.049268)
			(xy 10.02918 -61.968549) (xy 6.6002 -61.968549) (xy 6.59225 -62.049268) (xy 6.576427 -62.128819)
			(xy 6.552882 -62.206435) (xy 6.521843 -62.281371) (xy 6.483608 -62.352903) (xy 6.438546 -62.420343)
			(xy 6.387091 -62.483042) (xy 6.329738 -62.540395) (xy 6.267039 -62.59185) (xy 6.199599 -62.636912)
			(xy 6.128067 -62.675147) (xy 6.053131 -62.706186) (xy 5.975515 -62.729731) (xy 5.895964 -62.745554)
			(xy 5.815245 -62.753504) (xy 5.734135 -62.753504) (xy 5.653416 -62.745554) (xy 5.573865 -62.729731)
			(xy 5.496249 -62.706186) (xy 5.421313 -62.675147) (xy 5.349781 -62.636912) (xy 5.282341 -62.59185)
			(xy 5.219642 -62.540395) (xy 5.162289 -62.483042) (xy 5.110834 -62.420343) (xy 5.065772 -62.352903)
			(xy 5.027537 -62.281371) (xy 4.996498 -62.206435) (xy 4.972953 -62.128819) (xy 4.95713 -62.049268)
			(xy 4.94918 -61.968549) (xy 0.509016 -61.968549) (xy 0.509016 -68.310405) (xy 1.150876 -68.310405)
			(xy 1.152892 -68.180792) (xy 1.162962 -68.051556) (xy 1.181047 -67.923195) (xy 1.207077 -67.796207)
			(xy 1.240952 -67.671083) (xy 1.28254 -67.548307) (xy 1.331681 -67.428354) (xy 1.388184 -67.311689)
			(xy 1.451831 -67.198761) (xy 1.522375 -67.090009) (xy 1.599544 -66.985853) (xy 1.683039 -66.886696)
			(xy 1.772537 -66.792922) (xy 1.867692 -66.704893) (xy 1.968135 -66.62295) (xy 2.073478 -66.547411)
			(xy 2.183314 -66.478566) (xy 2.297218 -66.416683) (xy 2.414748 -66.362002) (xy 2.535451 -66.314732)
			(xy 2.658859 -66.275059) (xy 2.784495 -66.243134) (xy 2.911872 -66.219082) (xy 3.040498 -66.202995)
			(xy 3.169876 -66.194936) (xy 3.23469 -66.194432) (xy 3.299504 -66.194936) (xy 3.428882 -66.202995)
			(xy 3.557508 -66.219082) (xy 3.684885 -66.243134) (xy 3.810521 -66.275059) (xy 3.933929 -66.314732)
			(xy 4.054632 -66.362002) (xy 4.172162 -66.416683) (xy 4.286066 -66.478566) (xy 4.395902 -66.547411)
			(xy 4.501245 -66.62295) (xy 4.601688 -66.704893) (xy 4.696843 -66.792922) (xy 4.786341 -66.886696)
			(xy 4.869836 -66.985853) (xy 4.947005 -67.090009) (xy 5.017549 -67.198761) (xy 5.081196 -67.311689)
			(xy 5.137699 -67.428354) (xy 5.18684 -67.548307) (xy 5.228428 -67.671083) (xy 5.262303 -67.796207)
			(xy 5.288333 -67.923195) (xy 5.306418 -68.051556) (xy 5.316488 -68.180792) (xy 5.318504 -68.310405)
			(xy 12.580876 -68.310405) (xy 12.582892 -68.180792) (xy 12.592962 -68.051556) (xy 12.611047 -67.923195)
			(xy 12.637077 -67.796207) (xy 12.670952 -67.671083) (xy 12.71254 -67.548307) (xy 12.761681 -67.428354)
			(xy 12.818184 -67.311689) (xy 12.881831 -67.198761) (xy 12.952375 -67.090009) (xy 13.029544 -66.985853)
			(xy 13.113039 -66.886696) (xy 13.202537 -66.792922) (xy 13.297692 -66.704893) (xy 13.398135 -66.62295)
			(xy 13.503478 -66.547411) (xy 13.613314 -66.478566) (xy 13.727218 -66.416683) (xy 13.844748 -66.362002)
			(xy 13.965451 -66.314732) (xy 14.088859 -66.275059) (xy 14.214495 -66.243134) (xy 14.341872 -66.219082)
			(xy 14.470498 -66.202995) (xy 14.599876 -66.194936) (xy 14.66469 -66.194432) (xy 14.729504 -66.194936)
			(xy 14.858882 -66.202995) (xy 14.987508 -66.219082) (xy 15.114885 -66.243134) (xy 15.240521 -66.275059)
			(xy 15.363929 -66.314732) (xy 15.484632 -66.362002) (xy 15.602162 -66.416683) (xy 15.716066 -66.478566)
			(xy 15.825902 -66.547411) (xy 15.931245 -66.62295) (xy 16.031688 -66.704893) (xy 16.126843 -66.792922)
			(xy 16.216341 -66.886696) (xy 16.299836 -66.985853) (xy 16.377005 -67.090009) (xy 16.447549 -67.198761)
			(xy 16.511196 -67.311689) (xy 16.567699 -67.428354) (xy 16.61684 -67.548307) (xy 16.658428 -67.671083)
			(xy 16.692303 -67.796207) (xy 16.718333 -67.923195) (xy 16.736418 -68.051556) (xy 16.746488 -68.180792)
			(xy 16.748504 -68.310405) (xy 16.742458 -68.439892) (xy 16.728374 -68.568753) (xy 16.706305 -68.696489)
			(xy 16.676338 -68.822606) (xy 16.638589 -68.946616) (xy 16.593202 -69.068039) (xy 16.540355 -69.186406)
			(xy 16.480251 -69.301258) (xy 16.413123 -69.412151) (xy 16.339231 -69.518657) (xy 16.25886 -69.620363)
			(xy 16.172322 -69.716875) (xy 16.07995 -69.80782) (xy 15.982104 -69.892847) (xy 15.879161 -69.971627)
			(xy 15.771519 -70.043854) (xy 15.659595 -70.109249) (xy 15.543822 -70.16756) (xy 15.424648 -70.21856)
			(xy 15.302534 -70.262052) (xy 15.177951 -70.297869) (xy 15.051384 -70.325871) (xy 14.92332 -70.34595)
			(xy 14.794256 -70.358029) (xy 14.66469 -70.36206) (xy 14.535124 -70.358029) (xy 14.40606 -70.34595)
			(xy 14.277996 -70.325871) (xy 14.151429 -70.297869) (xy 14.026846 -70.262052) (xy 13.904732 -70.21856)
			(xy 13.785558 -70.16756) (xy 13.669785 -70.109249) (xy 13.557861 -70.043854) (xy 13.450219 -69.971627)
			(xy 13.347276 -69.892847) (xy 13.24943 -69.80782) (xy 13.157058 -69.716875) (xy 13.07052 -69.620363)
			(xy 12.990149 -69.518657) (xy 12.916257 -69.412151) (xy 12.849129 -69.301258) (xy 12.789025 -69.186406)
			(xy 12.736178 -69.068039) (xy 12.690791 -68.946616) (xy 12.653042 -68.822606) (xy 12.623075 -68.696489)
			(xy 12.601006 -68.568753) (xy 12.586922 -68.439892) (xy 12.580876 -68.310405) (xy 5.318504 -68.310405)
			(xy 5.312458 -68.439892) (xy 5.298374 -68.568753) (xy 5.276305 -68.696489) (xy 5.246338 -68.822606)
			(xy 5.208589 -68.946616) (xy 5.163202 -69.068039) (xy 5.110355 -69.186406) (xy 5.050251 -69.301258)
			(xy 4.983123 -69.412151) (xy 4.909231 -69.518657) (xy 4.82886 -69.620363) (xy 4.742322 -69.716875)
			(xy 4.64995 -69.80782) (xy 4.552104 -69.892847) (xy 4.449161 -69.971627) (xy 4.341519 -70.043854)
			(xy 4.229595 -70.109249) (xy 4.113822 -70.16756) (xy 3.994648 -70.21856) (xy 3.872534 -70.262052)
			(xy 3.747951 -70.297869) (xy 3.621384 -70.325871) (xy 3.49332 -70.34595) (xy 3.364256 -70.358029)
			(xy 3.23469 -70.36206) (xy 3.105124 -70.358029) (xy 2.97606 -70.34595) (xy 2.847996 -70.325871) (xy 2.721429 -70.297869)
			(xy 2.596846 -70.262052) (xy 2.474732 -70.21856) (xy 2.355558 -70.16756) (xy 2.239785 -70.109249)
			(xy 2.127861 -70.043854) (xy 2.020219 -69.971627) (xy 1.917276 -69.892847) (xy 1.81943 -69.80782)
			(xy 1.727058 -69.716875) (xy 1.64052 -69.620363) (xy 1.560149 -69.518657) (xy 1.486257 -69.412151)
			(xy 1.419129 -69.301258) (xy 1.359025 -69.186406) (xy 1.306178 -69.068039) (xy 1.260791 -68.946616)
			(xy 1.223042 -68.822606) (xy 1.193075 -68.696489) (xy 1.171006 -68.568753) (xy 1.156922 -68.439892)
			(xy 1.150876 -68.310405) (xy 0.509016 -68.310405) (xy 0.509016 -95.651062) (xy 26.679126 -95.651062)
			(xy 26.679126 -95.591126) (xy 26.686949 -95.531704) (xy 26.702462 -95.473811) (xy 26.725398 -95.418438)
			(xy 26.755365 -95.366532) (xy 26.791852 -95.318982) (xy 26.834232 -95.276602) (xy 26.881782 -95.240115)
			(xy 26.933688 -95.210148) (xy 26.989061 -95.187212) (xy 27.046954 -95.171699) (xy 27.106376 -95.163876)
			(xy 27.136344 -95.163386) (xy 27.166312 -95.163876) (xy 27.225734 -95.171699) (xy 27.283627 -95.187212)
			(xy 27.339 -95.210148) (xy 27.390906 -95.240115) (xy 27.438456 -95.276602) (xy 27.480836 -95.318982)
			(xy 27.517323 -95.366532) (xy 27.54729 -95.418438) (xy 27.570226 -95.473811) (xy 27.585739 -95.531704)
			(xy 27.593562 -95.591126) (xy 27.593562 -95.651062) (xy 27.585739 -95.710484) (xy 27.570226 -95.768377)
			(xy 27.54729 -95.82375) (xy 27.517323 -95.875656) (xy 27.480836 -95.923206) (xy 27.438456 -95.965586)
			(xy 27.390906 -96.002073) (xy 27.339 -96.03204) (xy 27.283627 -96.054976) (xy 27.225734 -96.070489)
			(xy 27.166312 -96.078312) (xy 27.106376 -96.078312) (xy 27.046954 -96.070489) (xy 26.989061 -96.054976)
			(xy 26.933688 -96.03204) (xy 26.881782 -96.002073) (xy 26.834232 -95.965586) (xy 26.791852 -95.923206)
			(xy 26.755365 -95.875656) (xy 26.725398 -95.82375) (xy 26.702462 -95.768377) (xy 26.686949 -95.710484)
			(xy 26.679126 -95.651062) (xy 0.509016 -95.651062) (xy 0.509016 -99.304247) (xy 1.150876 -99.304247)
			(xy 1.152892 -99.174634) (xy 1.162962 -99.045398) (xy 1.181047 -98.917037) (xy 1.207077 -98.790049)
			(xy 1.240952 -98.664925) (xy 1.28254 -98.542149) (xy 1.331681 -98.422196) (xy 1.388184 -98.305531)
			(xy 1.451831 -98.192603) (xy 1.522375 -98.083851) (xy 1.599544 -97.979695) (xy 1.683039 -97.880538)
			(xy 1.772537 -97.786764) (xy 1.867692 -97.698735) (xy 1.968135 -97.616792) (xy 2.073478 -97.541253)
			(xy 2.183314 -97.472408) (xy 2.297218 -97.410525) (xy 2.414748 -97.355844) (xy 2.535451 -97.308574)
			(xy 2.658859 -97.268901) (xy 2.784495 -97.236976) (xy 2.911872 -97.212924) (xy 3.040498 -97.196837)
			(xy 3.169876 -97.188778) (xy 3.23469 -97.188274) (xy 3.299504 -97.188778) (xy 3.428882 -97.196837)
			(xy 3.557508 -97.212924) (xy 3.684885 -97.236976) (xy 3.810521 -97.268901) (xy 3.933929 -97.308574)
			(xy 4.054632 -97.355844) (xy 4.172162 -97.410525) (xy 4.286066 -97.472408) (xy 4.395902 -97.541253)
			(xy 4.501245 -97.616792) (xy 4.601688 -97.698735) (xy 4.696843 -97.786764) (xy 4.786341 -97.880538)
			(xy 4.869836 -97.979695) (xy 4.947005 -98.083851) (xy 5.017549 -98.192603) (xy 5.081196 -98.305531)
			(xy 5.137699 -98.422196) (xy 5.18684 -98.542149) (xy 5.228428 -98.664925) (xy 5.262303 -98.790049)
			(xy 5.288333 -98.917037) (xy 5.306418 -99.045398) (xy 5.316488 -99.174634) (xy 5.318504 -99.304247)
			(xy 12.580876 -99.304247) (xy 12.582892 -99.174634) (xy 12.592962 -99.045398) (xy 12.611047 -98.917037)
			(xy 12.637077 -98.790049) (xy 12.670952 -98.664925) (xy 12.71254 -98.542149) (xy 12.761681 -98.422196)
			(xy 12.818184 -98.305531) (xy 12.881831 -98.192603) (xy 12.952375 -98.083851) (xy 13.029544 -97.979695)
			(xy 13.113039 -97.880538) (xy 13.202537 -97.786764) (xy 13.297692 -97.698735) (xy 13.398135 -97.616792)
			(xy 13.503478 -97.541253) (xy 13.613314 -97.472408) (xy 13.727218 -97.410525) (xy 13.844748 -97.355844)
			(xy 13.965451 -97.308574) (xy 14.088859 -97.268901) (xy 14.214495 -97.236976) (xy 14.341872 -97.212924)
			(xy 14.470498 -97.196837) (xy 14.599876 -97.188778) (xy 14.66469 -97.188274) (xy 14.729504 -97.188778)
			(xy 14.858882 -97.196837) (xy 14.987508 -97.212924) (xy 15.114885 -97.236976) (xy 15.240521 -97.268901)
			(xy 15.363929 -97.308574) (xy 15.484632 -97.355844) (xy 15.602162 -97.410525) (xy 15.716066 -97.472408)
			(xy 15.825902 -97.541253) (xy 15.931245 -97.616792) (xy 16.031688 -97.698735) (xy 16.126843 -97.786764)
			(xy 16.216341 -97.880538) (xy 16.299836 -97.979695) (xy 16.377005 -98.083851) (xy 16.447549 -98.192603)
			(xy 16.511196 -98.305531) (xy 16.567699 -98.422196) (xy 16.61684 -98.542149) (xy 16.658428 -98.664925)
			(xy 16.692303 -98.790049) (xy 16.718333 -98.917037) (xy 16.736418 -99.045398) (xy 16.746488 -99.174634)
			(xy 16.748504 -99.304247) (xy 16.744052 -99.399594) (xy 26.646868 -99.399594) (xy 26.646868 -99.339658)
			(xy 26.654691 -99.280236) (xy 26.670204 -99.222343) (xy 26.69314 -99.16697) (xy 26.723107 -99.115064)
			(xy 26.759594 -99.067514) (xy 26.801974 -99.025134) (xy 26.849524 -98.988647) (xy 26.90143 -98.95868)
			(xy 26.956803 -98.935744) (xy 27.014696 -98.920231) (xy 27.074118 -98.912408) (xy 27.104086 -98.911918)
			(xy 27.134054 -98.912408) (xy 27.193476 -98.920231) (xy 27.251369 -98.935744) (xy 27.306742 -98.95868)
			(xy 27.358648 -98.988647) (xy 27.406198 -99.025134) (xy 27.448578 -99.067514) (xy 27.485065 -99.115064)
			(xy 27.515032 -99.16697) (xy 27.537968 -99.222343) (xy 27.553481 -99.280236) (xy 27.561304 -99.339658)
			(xy 27.561304 -99.399594) (xy 27.553481 -99.459016) (xy 27.537968 -99.516909) (xy 27.515032 -99.572282)
			(xy 27.485065 -99.624188) (xy 27.448578 -99.671738) (xy 27.406198 -99.714118) (xy 27.358648 -99.750605)
			(xy 27.306742 -99.780572) (xy 27.251369 -99.803508) (xy 27.193476 -99.819021) (xy 27.134054 -99.826844)
			(xy 27.074118 -99.826844) (xy 27.014696 -99.819021) (xy 26.956803 -99.803508) (xy 26.90143 -99.780572)
			(xy 26.849524 -99.750605) (xy 26.801974 -99.714118) (xy 26.759594 -99.671738) (xy 26.723107 -99.624188)
			(xy 26.69314 -99.572282) (xy 26.670204 -99.516909) (xy 26.654691 -99.459016) (xy 26.646868 -99.399594)
			(xy 16.744052 -99.399594) (xy 16.742458 -99.433734) (xy 16.728374 -99.562595) (xy 16.706305 -99.690331)
			(xy 16.676338 -99.816448) (xy 16.638589 -99.940458) (xy 16.593202 -100.061881) (xy 16.540355 -100.180248)
			(xy 16.480251 -100.2951) (xy 16.413123 -100.405993) (xy 16.339231 -100.512499) (xy 16.25886 -100.614205)
			(xy 16.172322 -100.710717) (xy 16.07995 -100.801662) (xy 15.982104 -100.886689) (xy 15.879161 -100.965469)
			(xy 15.771519 -101.037696) (xy 15.659595 -101.103091) (xy 15.543822 -101.161402) (xy 15.424648 -101.212402)
			(xy 15.302534 -101.255894) (xy 15.177951 -101.291711) (xy 15.051384 -101.319713) (xy 14.92332 -101.339792)
			(xy 14.794256 -101.351871) (xy 14.66469 -101.355902) (xy 14.535124 -101.351871) (xy 14.40606 -101.339792)
			(xy 14.277996 -101.319713) (xy 14.151429 -101.291711) (xy 14.026846 -101.255894) (xy 13.904732 -101.212402)
			(xy 13.785558 -101.161402) (xy 13.669785 -101.103091) (xy 13.557861 -101.037696) (xy 13.450219 -100.965469)
			(xy 13.347276 -100.886689) (xy 13.24943 -100.801662) (xy 13.157058 -100.710717) (xy 13.07052 -100.614205)
			(xy 12.990149 -100.512499) (xy 12.916257 -100.405993) (xy 12.849129 -100.2951) (xy 12.789025 -100.180248)
			(xy 12.736178 -100.061881) (xy 12.690791 -99.940458) (xy 12.653042 -99.816448) (xy 12.623075 -99.690331)
			(xy 12.601006 -99.562595) (xy 12.586922 -99.433734) (xy 12.580876 -99.304247) (xy 5.318504 -99.304247)
			(xy 5.312458 -99.433734) (xy 5.298374 -99.562595) (xy 5.276305 -99.690331) (xy 5.246338 -99.816448)
			(xy 5.208589 -99.940458) (xy 5.163202 -100.061881) (xy 5.110355 -100.180248) (xy 5.050251 -100.2951)
			(xy 4.983123 -100.405993) (xy 4.909231 -100.512499) (xy 4.82886 -100.614205) (xy 4.742322 -100.710717)
			(xy 4.64995 -100.801662) (xy 4.552104 -100.886689) (xy 4.449161 -100.965469) (xy 4.341519 -101.037696)
			(xy 4.229595 -101.103091) (xy 4.113822 -101.161402) (xy 3.994648 -101.212402) (xy 3.872534 -101.255894)
			(xy 3.747951 -101.291711) (xy 3.621384 -101.319713) (xy 3.49332 -101.339792) (xy 3.364256 -101.351871)
			(xy 3.23469 -101.355902) (xy 3.105124 -101.351871) (xy 2.97606 -101.339792) (xy 2.847996 -101.319713)
			(xy 2.721429 -101.291711) (xy 2.596846 -101.255894) (xy 2.474732 -101.212402) (xy 2.355558 -101.161402)
			(xy 2.239785 -101.103091) (xy 2.127861 -101.037696) (xy 2.020219 -100.965469) (xy 1.917276 -100.886689)
			(xy 1.81943 -100.801662) (xy 1.727058 -100.710717) (xy 1.64052 -100.614205) (xy 1.560149 -100.512499)
			(xy 1.486257 -100.405993) (xy 1.419129 -100.2951) (xy 1.359025 -100.180248) (xy 1.306178 -100.061881)
			(xy 1.260791 -99.940458) (xy 1.223042 -99.816448) (xy 1.193075 -99.690331) (xy 1.171006 -99.562595)
			(xy 1.156922 -99.433734) (xy 1.150876 -99.304247) (xy 0.509016 -99.304247) (xy 0.509016 -126.021084)
			(xy 1.588008 -127.100076) (xy 11.44016 -127.100076) (xy 11.463197 -127.099579) (xy 11.508518 -127.09128)
			(xy 11.551599 -127.074946) (xy 11.591031 -127.051114) (xy 11.625519 -127.020563) (xy 11.653935 -126.984295)
			(xy 11.675347 -126.943498) (xy 11.689053 -126.89951) (xy 11.694604 -126.853772) (xy 11.691819 -126.807782)
			(xy 11.680788 -126.763048) (xy 11.661874 -126.721035) (xy 11.635695 -126.683121) (xy 11.619738 -126.666498)
			(xy 6.387592 -121.434098) (xy 6.387592 -113.993168) (xy 7.984236 -112.396524) (xy 7.984236 -108.962952)
			(xy 7.948676 -108.903262) (xy 7.918196 -108.886498) (xy 7.882758 -108.866555) (xy 7.815595 -108.820701)
			(xy 7.753264 -108.768468) (xy 7.696367 -108.710362) (xy 7.645456 -108.646947) (xy 7.601023 -108.578835)
			(xy 7.563499 -108.506687) (xy 7.533247 -108.4312) (xy 7.51056 -108.353106) (xy 7.495657 -108.27316)
			(xy 7.488682 -108.192136) (xy 7.489704 -108.110819) (xy 7.498712 -108.029997) (xy 7.515619 -107.95045)
			(xy 7.540262 -107.872951) (xy 7.572401 -107.798248) (xy 7.611726 -107.727065) (xy 7.657856 -107.660091)
			(xy 7.710345 -107.597975) (xy 7.768683 -107.541318) (xy 7.832307 -107.490668) (xy 7.900601 -107.446516)
			(xy 7.972903 -107.409288) (xy 8.048514 -107.379347) (xy 8.126701 -107.35698) (xy 8.206707 -107.342406)
			(xy 8.287759 -107.335765) (xy 8.369071 -107.337121) (xy 8.449856 -107.346461) (xy 8.529332 -107.363695)
			(xy 8.568182 -107.375706) (xy 8.589026 -107.381964) (xy 8.632111 -107.38808) (xy 8.675609 -107.386765)
			(xy 8.718246 -107.378059) (xy 8.758776 -107.362214) (xy 8.796014 -107.339696) (xy 8.828871 -107.311162)
			(xy 8.856386 -107.277447) (xy 8.877754 -107.239537) (xy 8.89235 -107.198541) (xy 8.899747 -107.155657)
			(xy 8.90016 -107.133898) (xy 8.90016 -107.11815) (xy 10.474452 -105.544112) (xy 10.474452 -105.264966)
			(xy 11.057636 -104.681782) (xy 11.073597 -104.665143) (xy 11.099818 -104.627223) (xy 11.11877 -104.585196)
			(xy 11.12983 -104.54044) (xy 11.132637 -104.494423) (xy 11.127097 -104.448654) (xy 11.113393 -104.404636)
			(xy 11.091974 -104.363811) (xy 11.063542 -104.327519) (xy 11.029031 -104.29695) (xy 10.989573 -104.273108)
			(xy 10.946461 -104.256774) (xy 10.90111 -104.248483) (xy 10.878058 -104.24795) (xy 8.885936 -104.24795)
			(xy 7.869682 -105.264458) (xy 7.858014 -105.276864) (xy 7.841124 -105.306424) (xy 7.832649 -105.339397)
			(xy 7.833192 -105.373437) (xy 7.837424 -105.389934) (xy 7.848296 -105.428848) (xy 7.863299 -105.508244)
			(xy 7.870477 -105.588727) (xy 7.869762 -105.669525) (xy 7.86116 -105.749868) (xy 7.844754 -105.828986)
			(xy 7.820701 -105.906125) (xy 7.78923 -105.980546) (xy 7.750642 -106.051538) (xy 7.705307 -106.118423)
			(xy 7.653656 -106.180562) (xy 7.596185 -106.237359) (xy 7.533442 -106.288274) (xy 7.466028 -106.332818)
			(xy 7.394586 -106.370566) (xy 7.319799 -106.401158) (xy 7.242382 -106.4243) (xy 7.163076 -106.439773)
			(xy 7.082637 -106.447427) (xy 7.001836 -106.44719) (xy 6.921444 -106.439063) (xy 6.842229 -106.423126)
			(xy 6.76495 -106.399529) (xy 6.690344 -106.368499) (xy 6.619125 -106.330332) (xy 6.551973 -106.285392)
			(xy 6.520434 -106.260138) (xy 6.503158 -106.246554) (xy 6.464907 -106.224924) (xy 6.423505 -106.210195)
			(xy 6.380188 -106.202806) (xy 6.336245 -106.202976) (xy 6.292986 -106.210701) (xy 6.2517 -106.225751)
			(xy 6.232398 -106.236262) (xy 6.232398 -107.474258) (xy 6.265912 -107.497148) (xy 6.328738 -107.548534)
			(xy 6.386222 -107.605834) (xy 6.437807 -107.668496) (xy 6.482998 -107.735915) (xy 6.521359 -107.807442)
			(xy 6.552519 -107.882387) (xy 6.576178 -107.960026) (xy 6.592107 -108.039612) (xy 6.600154 -108.120376)
			(xy 6.60024 -108.20154) (xy 6.592365 -108.282321) (xy 6.576605 -108.361941) (xy 6.553111 -108.43963)
			(xy 6.522111 -108.514641) (xy 6.483903 -108.586249) (xy 6.438855 -108.653765) (xy 6.387403 -108.716536)
			(xy 6.330042 -108.773959) (xy 6.267325 -108.825478) (xy 6.199857 -108.870597) (xy 6.12829 -108.908881)
			(xy 6.053312 -108.939961) (xy 5.975647 -108.963538) (xy 5.896045 -108.979383) (xy 5.815272 -108.987343)
			(xy 5.734108 -108.987343) (xy 5.653335 -108.979383) (xy 5.573733 -108.963538) (xy 5.496068 -108.939961)
			(xy 5.42109 -108.908881) (xy 5.349523 -108.870597) (xy 5.282055 -108.825478) (xy 5.219338 -108.773959)
			(xy 5.161977 -108.716536) (xy 5.110525 -108.653765) (xy 5.065477 -108.586249) (xy 5.027269 -108.514641)
			(xy 4.996269 -108.43963) (xy 4.972775 -108.361941) (xy 4.957015 -108.282321) (xy 4.94914 -108.20154)
			(xy 4.949226 -108.120376) (xy 4.957273 -108.039612) (xy 4.973202 -107.960026) (xy 4.996861 -107.882387)
			(xy 5.028021 -107.807442) (xy 5.066382 -107.735915) (xy 5.111573 -107.668496) (xy 5.163158 -107.605834)
			(xy 5.220642 -107.548534) (xy 5.283468 -107.497148) (xy 5.316982 -107.474258) (xy 5.316982 -106.447844)
			(xy 3.678936 -106.447844) (xy 3.678936 -104.795828) (xy 4.683506 -104.795828) (xy 6.730746 -102.748588)
			(xy 13.701522 -102.748588) (xy 15.719044 -104.76611) (xy 15.719044 -106.090123) (xy 23.296903 -106.090123)
			(xy 23.303161 -106.03449) (xy 23.317481 -105.980369) (xy 23.339556 -105.928921) (xy 23.368912 -105.881252)
			(xy 23.404919 -105.838384) (xy 23.446803 -105.801237) (xy 23.493666 -105.77061) (xy 23.544502 -105.74716)
			(xy 23.598219 -105.73139) (xy 23.653663 -105.723639) (xy 23.709645 -105.724073) (xy 23.764962 -105.732683)
			(xy 23.818428 -105.749284) (xy 23.868894 -105.773519) (xy 23.915277 -105.804869) (xy 23.95658 -105.84266)
			(xy 23.991918 -105.886082) (xy 24.020531 -105.9342) (xy 24.041806 -105.985984) (xy 24.055285 -106.040321)
			(xy 24.06068 -106.096044) (xy 24.057874 -106.151957) (xy 24.046927 -106.20686) (xy 24.028075 -106.259574)
			(xy 24.001722 -106.308967) (xy 23.985474 -106.331766) (xy 23.972027 -106.350969) (xy 23.951534 -106.393123)
			(xy 23.939123 -106.43832) (xy 23.935214 -106.485028) (xy 23.93994 -106.53166) (xy 23.953141 -106.576633)
			(xy 23.974369 -106.618421) (xy 24.002903 -106.655606) (xy 24.037775 -106.686924) (xy 24.077801 -106.711313)
			(xy 24.09952 -106.720132) (xy 24.125536 -106.730475) (xy 24.174412 -106.757783) (xy 24.218772 -106.79194)
			(xy 24.257665 -106.832213) (xy 24.290255 -106.877738) (xy 24.315843 -106.927535) (xy 24.333879 -106.980538)
			(xy 24.343976 -107.035607) (xy 24.345918 -107.09156) (xy 24.339663 -107.147197) (xy 24.325344 -107.201322)
			(xy 24.30327 -107.252774) (xy 24.273914 -107.300448) (xy 24.237907 -107.34332) (xy 24.196021 -107.38047)
			(xy 24.149156 -107.411101) (xy 24.098318 -107.434555) (xy 24.044599 -107.450328) (xy 23.989151 -107.458081)
			(xy 23.933166 -107.457649) (xy 23.877844 -107.44904) (xy 23.824375 -107.43244) (xy 23.773905 -107.408204)
			(xy 23.727519 -107.376854) (xy 23.686212 -107.339061) (xy 23.65087 -107.295638) (xy 23.622254 -107.247517)
			(xy 23.600977 -107.19573) (xy 23.587495 -107.141391) (xy 23.5821 -107.085664) (xy 23.584905 -107.029747)
			(xy 23.595851 -106.974841) (xy 23.614703 -106.922123) (xy 23.641057 -106.872726) (xy 23.657306 -106.849926)
			(xy 23.670771 -106.830734) (xy 23.691266 -106.788579) (xy 23.703678 -106.743378) (xy 23.707587 -106.696668)
			(xy 23.702859 -106.650034) (xy 23.689656 -106.605058) (xy 23.668425 -106.563268) (xy 23.639887 -106.526083)
			(xy 23.605011 -106.494765) (xy 23.564981 -106.470378) (xy 23.54326 -106.46156) (xy 23.517253 -106.451197)
			(xy 23.468382 -106.423888) (xy 23.424026 -106.38973) (xy 23.385138 -106.349458) (xy 23.352553 -106.303935)
			(xy 23.326969 -106.254139) (xy 23.308936 -106.201139) (xy 23.298842 -106.146073) (xy 23.296903 -106.090123)
			(xy 15.719044 -106.090123) (xy 15.719044 -109.453934) (xy 9.309354 -115.863624) (xy 9.309354 -118.100094)
			(xy 11.599164 -118.100094) (xy 11.599658 -118.000658) (xy 11.607565 -117.801944) (xy 11.623365 -117.603701)
			(xy 11.647034 -117.406243) (xy 11.678535 -117.209883) (xy 11.717818 -117.014929) (xy 11.76482 -116.821692)
			(xy 11.819467 -116.630476) (xy 11.881674 -116.441584) (xy 11.95134 -116.255315) (xy 12.028358 -116.071962)
			(xy 12.112603 -115.891816) (xy 12.203944 -115.715162) (xy 12.302236 -115.542279) (xy 12.407324 -115.373441)
			(xy 12.519041 -115.208913) (xy 12.637211 -115.048958) (xy 12.761646 -114.893827) (xy 12.892151 -114.743765)
			(xy 13.028518 -114.599011) (xy 13.170532 -114.459793) (xy 13.317969 -114.32633) (xy 13.470596 -114.198835)
			(xy 13.62817 -114.077509) (xy 13.790444 -113.962543) (xy 13.957159 -113.854119) (xy 14.128054 -113.752409)
			(xy 14.302857 -113.657574) (xy 14.481292 -113.569763) (xy 14.663077 -113.489115) (xy 14.847925 -113.415759)
			(xy 15.035543 -113.349809) (xy 15.225635 -113.291371) (xy 15.417899 -113.240536) (xy 15.612033 -113.197385)
			(xy 15.807728 -113.161987) (xy 16.004677 -113.134396) (xy 16.202566 -113.114657) (xy 16.401084 -113.102801)
			(xy 16.599916 -113.098848) (xy 16.798748 -113.102801) (xy 16.997266 -113.114657) (xy 17.195155 -113.134396)
			(xy 17.392104 -113.161987) (xy 17.587799 -113.197385) (xy 17.781933 -113.240536) (xy 17.974197 -113.291371)
			(xy 18.164289 -113.349809) (xy 18.351907 -113.415759) (xy 18.536755 -113.489115) (xy 18.71854 -113.569763)
			(xy 18.896975 -113.657574) (xy 19.071778 -113.752409) (xy 19.242673 -113.854119) (xy 19.409388 -113.962543)
			(xy 19.571662 -114.077509) (xy 19.729236 -114.198835) (xy 19.881863 -114.32633) (xy 20.0293 -114.459793)
			(xy 20.171314 -114.599011) (xy 20.307681 -114.743765) (xy 20.438186 -114.893827) (xy 20.562621 -115.048958)
			(xy 20.680791 -115.208913) (xy 20.792508 -115.373441) (xy 20.897596 -115.542279) (xy 20.995888 -115.715162)
			(xy 21.087229 -115.891816) (xy 21.171474 -116.071962) (xy 21.248492 -116.255315) (xy 21.318158 -116.441584)
			(xy 21.380365 -116.630476) (xy 21.435012 -116.821692) (xy 21.482014 -117.014929) (xy 21.521297 -117.209883)
			(xy 21.552798 -117.406243) (xy 21.576467 -117.603701) (xy 21.592267 -117.801944) (xy 21.600174 -118.000658)
			(xy 21.600668 -118.100094) (xy 21.600174 -118.19953) (xy 21.592267 -118.398244) (xy 21.576467 -118.596487)
			(xy 21.552798 -118.793945) (xy 21.521297 -118.990305) (xy 21.482014 -119.185259) (xy 21.435012 -119.378496)
			(xy 21.380365 -119.569712) (xy 21.318158 -119.758604) (xy 21.248492 -119.944873) (xy 21.171474 -120.128226)
			(xy 21.087229 -120.308372) (xy 20.995888 -120.485026) (xy 20.897596 -120.657909) (xy 20.792508 -120.826747)
			(xy 20.680791 -120.991275) (xy 20.562621 -121.15123) (xy 20.438186 -121.306361) (xy 20.307681 -121.456423)
			(xy 20.171314 -121.601177) (xy 20.0293 -121.740395) (xy 19.881863 -121.873858) (xy 19.729236 -122.001353)
			(xy 19.571662 -122.122679) (xy 19.409388 -122.237645) (xy 19.242673 -122.346069) (xy 19.071778 -122.447779)
			(xy 18.896975 -122.542614) (xy 18.71854 -122.630425) (xy 18.536755 -122.711073) (xy 18.351907 -122.784429)
			(xy 18.164289 -122.850379) (xy 17.974197 -122.908817) (xy 17.781933 -122.959652) (xy 17.587799 -123.002803)
			(xy 17.392104 -123.038201) (xy 17.195155 -123.065792) (xy 16.997266 -123.085531) (xy 16.798748 -123.097387)
			(xy 16.599916 -123.101341) (xy 16.401084 -123.097387) (xy 16.202566 -123.085531) (xy 16.004677 -123.065792)
			(xy 15.807728 -123.038201) (xy 15.612033 -123.002803) (xy 15.417899 -122.959652) (xy 15.225635 -122.908817)
			(xy 15.035543 -122.850379) (xy 14.847925 -122.784429) (xy 14.663077 -122.711073) (xy 14.481292 -122.630425)
			(xy 14.302857 -122.542614) (xy 14.128054 -122.447779) (xy 13.957159 -122.346069) (xy 13.790444 -122.237645)
			(xy 13.62817 -122.122679) (xy 13.470596 -122.001353) (xy 13.317969 -121.873858) (xy 13.170532 -121.740395)
			(xy 13.028518 -121.601177) (xy 12.892151 -121.456423) (xy 12.761646 -121.306361) (xy 12.637211 -121.15123)
			(xy 12.519041 -120.991275) (xy 12.407324 -120.826747) (xy 12.302236 -120.657909) (xy 12.203944 -120.485026)
			(xy 12.112603 -120.308372) (xy 12.028358 -120.128226) (xy 11.95134 -119.944873) (xy 11.881674 -119.758604)
			(xy 11.819467 -119.569712) (xy 11.76482 -119.378496) (xy 11.717818 -119.185259) (xy 11.678535 -118.990305)
			(xy 11.647034 -118.793945) (xy 11.623365 -118.596487) (xy 11.607565 -118.398244) (xy 11.599658 -118.19953)
			(xy 11.599164 -118.100094) (xy 9.309354 -118.100094) (xy 9.309354 -120.052846) (xy 21.865336 -132.608828)
			(xy 21.865336 -141.366748) (xy 20.046696 -143.185388) (xy 20.046696 -184.27344) (xy 26.727132 -184.27344)
			(xy 26.727132 -184.213504) (xy 26.734955 -184.154082) (xy 26.750468 -184.096189) (xy 26.773404 -184.040816)
			(xy 26.803371 -183.98891) (xy 26.839858 -183.94136) (xy 26.882238 -183.89898) (xy 26.929788 -183.862493)
			(xy 26.981694 -183.832526) (xy 27.037067 -183.80959) (xy 27.09496 -183.794077) (xy 27.154382 -183.786254)
			(xy 27.18435 -183.785764) (xy 27.214318 -183.786254) (xy 27.27374 -183.794077) (xy 27.331633 -183.80959)
			(xy 27.387006 -183.832526) (xy 27.438912 -183.862493) (xy 27.486462 -183.89898) (xy 27.528842 -183.94136)
			(xy 27.565329 -183.98891) (xy 27.595296 -184.040816) (xy 27.618232 -184.096189) (xy 27.633745 -184.154082)
			(xy 27.641568 -184.213504) (xy 27.641568 -184.27344) (xy 27.633745 -184.332862) (xy 27.618232 -184.390755)
			(xy 27.595296 -184.446128) (xy 27.565329 -184.498034) (xy 27.528842 -184.545584) (xy 27.486462 -184.587964)
			(xy 27.438912 -184.624451) (xy 27.387006 -184.654418) (xy 27.331633 -184.677354) (xy 27.27374 -184.692867)
			(xy 27.214318 -184.70069) (xy 27.154382 -184.70069) (xy 27.09496 -184.692867) (xy 27.037067 -184.677354)
			(xy 26.981694 -184.654418) (xy 26.929788 -184.624451) (xy 26.882238 -184.587964) (xy 26.839858 -184.545584)
			(xy 26.803371 -184.498034) (xy 26.773404 -184.446128) (xy 26.750468 -184.390755) (xy 26.734955 -184.332862)
			(xy 26.727132 -184.27344) (xy 20.046696 -184.27344) (xy 20.046696 -186.775594) (xy 26.764724 -186.775594)
			(xy 26.764724 -186.715658) (xy 26.772547 -186.656236) (xy 26.78806 -186.598343) (xy 26.810996 -186.54297)
			(xy 26.840963 -186.491064) (xy 26.87745 -186.443514) (xy 26.91983 -186.401134) (xy 26.96738 -186.364647)
			(xy 27.019286 -186.33468) (xy 27.074659 -186.311744) (xy 27.132552 -186.296231) (xy 27.191974 -186.288408)
			(xy 27.221942 -186.287918) (xy 27.25191 -186.288408) (xy 27.311332 -186.296231) (xy 27.369225 -186.311744)
			(xy 27.424598 -186.33468) (xy 27.476504 -186.364647) (xy 27.524054 -186.401134) (xy 27.566434 -186.443514)
			(xy 27.602921 -186.491064) (xy 27.632888 -186.54297) (xy 27.655824 -186.598343) (xy 27.671337 -186.656236)
			(xy 27.67916 -186.715658) (xy 27.67916 -186.775594) (xy 27.671337 -186.835016) (xy 27.655824 -186.892909)
			(xy 27.632888 -186.948282) (xy 27.602921 -187.000188) (xy 27.566434 -187.047738) (xy 27.524054 -187.090118)
			(xy 27.476504 -187.126605) (xy 27.424598 -187.156572) (xy 27.369225 -187.179508) (xy 27.311332 -187.195021)
			(xy 27.25191 -187.202844) (xy 27.191974 -187.202844) (xy 27.132552 -187.195021) (xy 27.074659 -187.179508)
			(xy 27.019286 -187.156572) (xy 26.96738 -187.126605) (xy 26.91983 -187.090118) (xy 26.87745 -187.047738)
			(xy 26.840963 -187.000188) (xy 26.810996 -186.948282) (xy 26.78806 -186.892909) (xy 26.772547 -186.835016)
			(xy 26.764724 -186.775594) (xy 20.046696 -186.775594) (xy 20.046696 -194.85864) (xy 11.434826 -203.47051)
			(xy 11.434826 -206.33182) (xy 9.084564 -208.682082) (xy 9.083548 -208.701894) (xy 9.081102 -208.740008)
			(xy 9.068228 -208.81529) (xy 9.046425 -208.888488) (xy 9.016008 -208.958545) (xy 8.977414 -209.024453)
			(xy 8.95477 -209.055208) (xy 8.94196 -209.072758) (xy 8.921897 -209.111294) (xy 8.908682 -209.152681)
			(xy 8.902701 -209.195713) (xy 8.904128 -209.239135) (xy 8.91292 -209.281682) (xy 8.928823 -209.322113)
			(xy 8.951372 -209.359249) (xy 8.97991 -209.392008) (xy 9.013604 -209.419434) (xy 9.051474 -209.440729)
			(xy 9.092414 -209.45527) (xy 9.135231 -209.462635) (xy 9.156954 -209.463132) (xy 9.482582 -209.463132)
			(xy 12.476988 -212.457284) (xy 19.82089 -212.457284) (xy 21.853652 -210.424776) (xy 21.853652 -208.617058)
			(xy 21.853193 -208.594569) (xy 21.845322 -208.550286) (xy 21.829781 -208.508079) (xy 21.807054 -208.469266)
			(xy 21.777851 -208.435058) (xy 21.743084 -208.406524) (xy 21.703838 -208.384554) (xy 21.661337 -208.369834)
			(xy 21.61691 -208.362824) (xy 21.571942 -208.363741) (xy 21.527837 -208.372559) (xy 21.485973 -208.389001)
			(xy 21.447656 -208.412554) (xy 21.414082 -208.442482) (xy 21.386299 -208.477853) (xy 21.365175 -208.517561)
			(xy 21.357844 -208.538826) (xy 21.32672 -208.633461) (xy 21.257904 -208.820442) (xy 21.181696 -209.004534)
			(xy 21.098216 -209.185444) (xy 21.007596 -209.362885) (xy 20.90998 -209.536576) (xy 20.805524 -209.706241)
			(xy 20.694392 -209.87161) (xy 20.576762 -210.032422) (xy 20.45282 -210.188421) (xy 20.322762 -210.33936)
			(xy 20.186796 -210.484998) (xy 20.045136 -210.625105) (xy 19.898009 -210.759459) (xy 19.745647 -210.887845)
			(xy 19.588291 -211.010061) (xy 19.426193 -211.125912) (xy 19.259609 -211.235215) (xy 19.088803 -211.337796)
			(xy 18.914047 -211.433492) (xy 18.735619 -211.522151) (xy 18.5538 -211.603633) (xy 18.36888 -211.677808)
			(xy 18.181152 -211.744559) (xy 17.990915 -211.803779) (xy 17.798469 -211.855375) (xy 17.604121 -211.899265)
			(xy 17.40818 -211.935379) (xy 17.210955 -211.96366) (xy 17.01276 -211.984062) (xy 16.81391 -211.996554)
			(xy 16.614721 -212.001116) (xy 16.415507 -211.99774) (xy 16.216586 -211.986432) (xy 16.018274 -211.967209)
			(xy 15.820884 -211.940103) (xy 15.624731 -211.905156) (xy 15.430126 -211.862424) (xy 15.237377 -211.811974)
			(xy 15.04679 -211.753887) (xy 14.858668 -211.688255) (xy 14.67331 -211.615182) (xy 14.49101 -211.534783)
			(xy 14.312056 -211.447188) (xy 14.136734 -211.352533) (xy 13.965321 -211.250971) (xy 13.798089 -211.142662)
			(xy 13.635304 -211.027777) (xy 13.477224 -210.9065) (xy 13.3241 -210.779023) (xy 13.176176 -210.645548)
			(xy 13.033685 -210.506286) (xy 12.896854 -210.36146) (xy 12.7659 -210.211298) (xy 12.641032 -210.05604)
			(xy 12.522447 -209.895931) (xy 12.410333 -209.731225) (xy 12.304868 -209.562185) (xy 12.20622 -209.389078)
			(xy 12.114546 -209.212179) (xy 12.02999 -209.03177) (xy 11.952688 -208.848135) (xy 11.882761 -208.661567)
			(xy 11.820321 -208.472362) (xy 11.765466 -208.28082) (xy 11.718285 -208.087245) (xy 11.678851 -207.891944)
			(xy 11.647228 -207.695228) (xy 11.623465 -207.497408) (xy 11.6076 -207.298799) (xy 11.599659 -207.099715)
			(xy 11.599164 -207.000094) (xy 11.599649 -206.900469) (xy 11.607572 -206.701376) (xy 11.623418 -206.502756)
			(xy 11.647164 -206.304926) (xy 11.678772 -206.108198) (xy 11.71819 -205.912886) (xy 11.765357 -205.719298)
			(xy 11.820198 -205.527744) (xy 11.882626 -205.338525) (xy 11.952541 -205.151944) (xy 12.029833 -204.968295)
			(xy 12.114379 -204.787871) (xy 12.206044 -204.610958) (xy 12.304684 -204.437837) (xy 12.410142 -204.268782)
			(xy 12.522249 -204.104063) (xy 12.64083 -203.943939) (xy 12.765694 -203.788666) (xy 12.896644 -203.63849)
			(xy 13.033472 -203.493649) (xy 13.175961 -203.354374) (xy 13.323885 -203.220885) (xy 13.477009 -203.093394)
			(xy 13.635089 -202.972103) (xy 13.797876 -202.857206) (xy 13.96511 -202.748884) (xy 14.136526 -202.64731)
			(xy 14.311852 -202.552645) (xy 14.490809 -202.465038) (xy 14.673114 -202.384629) (xy 14.858478 -202.311546)
			(xy 15.046606 -202.245904) (xy 15.237198 -202.187809) (xy 15.429954 -202.137351) (xy 15.624567 -202.094611)
			(xy 15.820728 -202.059658) (xy 16.018125 -202.032546) (xy 16.216446 -202.013318) (xy 16.415375 -202.002005)
			(xy 16.614597 -201.998625) (xy 16.813795 -202.003184) (xy 17.012654 -202.015674) (xy 17.210857 -202.036074)
			(xy 17.408091 -202.064354) (xy 17.604041 -202.100468) (xy 17.798398 -202.144358) (xy 17.990852 -202.195956)
			(xy 18.181097 -202.255178) (xy 18.368833 -202.321932) (xy 18.553761 -202.396111) (xy 18.735587 -202.477597)
			(xy 18.914023 -202.566261) (xy 19.088786 -202.661962) (xy 19.259598 -202.764549) (xy 19.426188 -202.873859)
			(xy 19.588292 -202.989717) (xy 19.745652 -203.111941) (xy 19.898018 -203.240336) (xy 20.04515 -203.374698)
			(xy 20.186812 -203.514814) (xy 20.322781 -203.660462) (xy 20.45284 -203.81141) (xy 20.576783 -203.967419)
			(xy 20.694414 -204.128242) (xy 20.805545 -204.293622) (xy 20.91 -204.463298) (xy 21.007614 -204.637)
			(xy 21.098231 -204.814452) (xy 21.181708 -204.995373) (xy 21.257912 -205.179476) (xy 21.326722 -205.366467)
			(xy 21.357844 -205.461108) (xy 21.3652 -205.482364) (xy 21.386315 -205.522076) (xy 21.414091 -205.55745)
			(xy 21.447659 -205.587383) (xy 21.485973 -205.61094) (xy 21.527834 -205.627385) (xy 21.571937 -205.636205)
			(xy 21.616904 -205.637124) (xy 21.66133 -205.630113) (xy 21.703829 -205.615392) (xy 21.743072 -205.59342)
			(xy 21.777836 -205.564883) (xy 21.807033 -205.530673) (xy 21.829753 -205.491857) (xy 21.845285 -205.449648)
			(xy 21.853146 -205.405365) (xy 21.853652 -205.382876) (xy 21.853652 -192.878964) (xy 23.86711 -190.865506)
			(xy 23.87219 -190.82131) (xy 23.876089 -190.791366) (xy 23.890756 -190.73279) (xy 23.913002 -190.676651)
			(xy 23.942438 -190.623927) (xy 23.978554 -190.575533) (xy 24.020722 -190.53231) (xy 24.06821 -190.49501)
			(xy 24.120191 -190.46428) (xy 24.175762 -190.440655) (xy 24.233959 -190.424545) (xy 24.293769 -190.41623)
			(xy 24.354153 -190.415855) (xy 24.414061 -190.423426) (xy 24.472453 -190.438812) (xy 24.528314 -190.461745)
			(xy 24.580673 -190.491826) (xy 24.62862 -190.528534) (xy 24.671322 -190.571229) (xy 24.708037 -190.619171)
			(xy 24.738126 -190.671526) (xy 24.761067 -190.727383) (xy 24.776461 -190.785773) (xy 24.784041 -190.84568)
			(xy 24.783675 -190.906064) (xy 24.775369 -190.965876) (xy 24.759267 -191.024074) (xy 24.73565 -191.07965)
			(xy 24.704928 -191.131635) (xy 24.667635 -191.179128) (xy 24.624418 -191.221302) (xy 24.576029 -191.257426)
			(xy 24.523309 -191.28687) (xy 24.467174 -191.309123) (xy 24.4086 -191.3238) (xy 24.378666 -191.327786)
			(xy 24.33447 -191.332866) (xy 22.51456 -193.152776) (xy 22.514814 -193.428112) (xy 22.515298 -193.444765)
			(xy 22.523902 -193.476939) (xy 22.540547 -193.505787) (xy 22.564095 -193.52934) (xy 22.59294 -193.545989)
			(xy 22.625113 -193.554599) (xy 22.658418 -193.554582) (xy 22.690582 -193.545938) (xy 22.71941 -193.529259)
			(xy 22.731476 -193.517774) (xy 26.490168 -189.759336) (xy 26.491438 -189.759336) (xy 26.51357 -189.758862)
			(xy 26.557166 -189.751201) (xy 26.598775 -189.736099) (xy 26.637136 -189.714015) (xy 26.671089 -189.685616)
			(xy 26.699606 -189.651762) (xy 26.721824 -189.613478) (xy 26.73707 -189.571922) (xy 26.744884 -189.528353)
			(xy 26.745027 -189.484089) (xy 26.737496 -189.44047) (xy 26.730452 -189.419484) (xy 26.720728 -189.390856)
			(xy 26.708036 -189.331743) (xy 26.703237 -189.271473) (xy 26.706413 -189.211096) (xy 26.717509 -189.151662)
			(xy 26.736332 -189.094206) (xy 26.762555 -189.039728) (xy 26.795722 -188.989176) (xy 26.835254 -188.94343)
			(xy 26.880464 -188.903286) (xy 26.930565 -188.869443) (xy 26.984685 -188.842489) (xy 27.041882 -188.822894)
			(xy 27.101161 -188.810999) (xy 27.16149 -188.807011) (xy 27.221819 -188.810999) (xy 27.281098 -188.822894)
			(xy 27.338295 -188.842489) (xy 27.392415 -188.869443) (xy 27.442516 -188.903286) (xy 27.487726 -188.94343)
			(xy 27.527258 -188.989176) (xy 27.560425 -189.039728) (xy 27.586648 -189.094206) (xy 27.605471 -189.151662)
			(xy 27.616567 -189.211096) (xy 27.619743 -189.271473) (xy 27.614944 -189.331743) (xy 27.602252 -189.390856)
			(xy 27.592528 -189.419484) (xy 27.585503 -189.440471) (xy 27.577993 -189.484083) (xy 27.578152 -189.528336)
			(xy 27.585975 -189.571893) (xy 27.601224 -189.613436) (xy 27.62344 -189.651709) (xy 27.651949 -189.685555)
			(xy 27.685891 -189.713951) (xy 27.724239 -189.736038) (xy 27.765833 -189.751148) (xy 27.809415 -189.758824)
			(xy 27.831542 -189.759336) (xy 29.372814 -189.759336) (xy 29.395908 -189.758829) (xy 29.441335 -189.750481)
			(xy 29.484507 -189.734063) (xy 29.524001 -189.710115) (xy 29.558519 -189.679425) (xy 29.586923 -189.643003)
			(xy 29.608279 -189.602049) (xy 29.621885 -189.557911) (xy 29.627291 -189.51204) (xy 29.62432 -189.465948)
			(xy 29.61307 -189.421151) (xy 29.603954 -189.399926) (xy 29.586101 -189.359524) (xy 29.557176 -189.276056)
			(xy 29.536207 -189.190245) (xy 29.523377 -189.102844) (xy 29.5188 -189.014626) (xy 29.522517 -188.926368)
			(xy 29.534494 -188.838846) (xy 29.554626 -188.752834) (xy 29.582735 -188.669089) (xy 29.618575 -188.588349)
			(xy 29.661828 -188.511326) (xy 29.712113 -188.438698) (xy 29.768988 -188.371107) (xy 29.831951 -188.309147)
			(xy 29.900448 -188.253365) (xy 29.973873 -188.204252) (xy 30.051581 -188.162241) (xy 30.132886 -188.127703)
			(xy 30.217072 -188.100942) (xy 30.303396 -188.082194) (xy 30.391099 -188.071624) (xy 30.479405 -188.069325)
			(xy 30.567539 -188.075318) (xy 30.654722 -188.08955) (xy 30.740186 -188.111894) (xy 30.823178 -188.142156)
			(xy 30.863286 -188.16066) (xy 30.884527 -188.170165) (xy 30.929491 -188.182132) (xy 30.975882 -188.185714)
			(xy 31.02215 -188.180791) (xy 31.066749 -188.167529) (xy 31.108189 -188.146369) (xy 31.145084 -188.11802)
			(xy 31.176203 -188.083429) (xy 31.200505 -188.04375) (xy 31.217179 -188.000311) (xy 31.225666 -187.954562)
			(xy 31.226252 -187.931298) (xy 31.226252 -187.548774) (xy 31.225736 -187.525498) (xy 31.21727 -187.479723)
			(xy 31.200608 -187.436255) (xy 31.176307 -187.39655) (xy 31.14518 -187.361936) (xy 31.108268 -187.33357)
			(xy 31.066808 -187.312402) (xy 31.022185 -187.299141) (xy 30.975893 -187.294229) (xy 30.929481 -187.297832)
			(xy 30.884502 -187.309828) (xy 30.863286 -187.319412) (xy 30.824186 -187.337456) (xy 30.743346 -187.367151)
			(xy 30.66013 -187.38933) (xy 30.575235 -187.403808) (xy 30.489371 -187.410462) (xy 30.403259 -187.409237)
			(xy 30.31762 -187.400144) (xy 30.23317 -187.383259) (xy 30.150619 -187.358722) (xy 30.070657 -187.326741)
			(xy 29.993953 -187.287581) (xy 29.921152 -187.241573) (xy 29.852863 -187.1891) (xy 29.789657 -187.130604)
			(xy 29.732065 -187.066573) (xy 29.680569 -186.997544) (xy 29.6356 -186.924096) (xy 29.597535 -186.846844)
			(xy 29.566694 -186.766435) (xy 29.543333 -186.683543) (xy 29.52765 -186.598862) (xy 29.519775 -186.513102)
			(xy 29.519775 -186.426981) (xy 29.52765 -186.341221) (xy 29.543332 -186.25654) (xy 29.566692 -186.173648)
			(xy 29.597534 -186.093239) (xy 29.635598 -186.015987) (xy 29.680567 -185.942539) (xy 29.732063 -185.87351)
			(xy 29.789655 -185.809479) (xy 29.85286 -185.750982) (xy 29.921149 -185.698509) (xy 29.99395 -185.6525)
			(xy 30.070653 -185.613341) (xy 30.150616 -185.581359) (xy 30.233167 -185.556822) (xy 30.317616 -185.539936)
			(xy 30.403256 -185.530843) (xy 30.489368 -185.529618) (xy 30.575231 -185.536272) (xy 30.660127 -185.550749)
			(xy 30.743343 -185.572928) (xy 30.824182 -185.602623) (xy 30.863286 -185.62066) (xy 30.884527 -185.630165)
			(xy 30.929491 -185.642132) (xy 30.975882 -185.645714) (xy 31.02215 -185.640791) (xy 31.066749 -185.627529)
			(xy 31.108189 -185.606369) (xy 31.145084 -185.57802) (xy 31.176203 -185.543429) (xy 31.200505 -185.50375)
			(xy 31.217179 -185.460311) (xy 31.225666 -185.414562) (xy 31.226252 -185.391298) (xy 31.226252 -185.008774)
			(xy 31.225736 -184.985498) (xy 31.21727 -184.939723) (xy 31.200608 -184.896255) (xy 31.176307 -184.85655)
			(xy 31.14518 -184.821936) (xy 31.108268 -184.79357) (xy 31.066808 -184.772402) (xy 31.022185 -184.759141)
			(xy 30.975893 -184.754229) (xy 30.929481 -184.757832) (xy 30.884502 -184.769828) (xy 30.863286 -184.779412)
			(xy 30.824186 -184.797456) (xy 30.743346 -184.827151) (xy 30.66013 -184.84933) (xy 30.575235 -184.863808)
			(xy 30.489371 -184.870462) (xy 30.403259 -184.869237) (xy 30.31762 -184.860144) (xy 30.23317 -184.843259)
			(xy 30.150619 -184.818722) (xy 30.070657 -184.786741) (xy 29.993953 -184.747581) (xy 29.921152 -184.701573)
			(xy 29.852863 -184.6491) (xy 29.789657 -184.590604) (xy 29.732065 -184.526573) (xy 29.680569 -184.457544)
			(xy 29.6356 -184.384096) (xy 29.597535 -184.306844) (xy 29.566694 -184.226435) (xy 29.543333 -184.143543)
			(xy 29.52765 -184.058862) (xy 29.519775 -183.973102) (xy 29.519775 -183.886981) (xy 29.52765 -183.801221)
			(xy 29.543332 -183.71654) (xy 29.566692 -183.633648) (xy 29.597534 -183.553239) (xy 29.635598 -183.475987)
			(xy 29.680567 -183.402539) (xy 29.732063 -183.33351) (xy 29.789655 -183.269479) (xy 29.85286 -183.210982)
			(xy 29.921149 -183.158509) (xy 29.99395 -183.1125) (xy 30.070653 -183.073341) (xy 30.150616 -183.041359)
			(xy 30.233167 -183.016822) (xy 30.317616 -182.999936) (xy 30.403256 -182.990843) (xy 30.489368 -182.989618)
			(xy 30.575231 -182.996272) (xy 30.660127 -183.010749) (xy 30.743343 -183.032928) (xy 30.824182 -183.062623)
			(xy 30.863286 -183.08066) (xy 30.884527 -183.090165) (xy 30.929491 -183.102132) (xy 30.975882 -183.105714)
			(xy 31.02215 -183.100791) (xy 31.066749 -183.087529) (xy 31.108189 -183.066369) (xy 31.145084 -183.03802)
			(xy 31.176203 -183.003429) (xy 31.200505 -182.96375) (xy 31.217179 -182.920311) (xy 31.225666 -182.874562)
			(xy 31.226252 -182.851298) (xy 31.226252 -182.624222) (xy 30.907736 -182.305706) (xy 30.894647 -182.293438)
			(xy 30.863265 -182.276089) (xy 30.828293 -182.268167) (xy 30.792498 -182.270299) (xy 30.775402 -182.275734)
			(xy 30.733602 -182.290096) (xy 30.647925 -182.311828) (xy 30.560587 -182.325423) (xy 30.472358 -182.330763)
			(xy 30.384017 -182.327799) (xy 30.296345 -182.316558) (xy 30.210114 -182.297139) (xy 30.126086 -182.269714)
			(xy 30.045003 -182.234524) (xy 29.96758 -182.191881) (xy 29.8945 -182.142159) (xy 29.826409 -182.0858)
			(xy 29.763907 -182.023299) (xy 29.707546 -181.955208) (xy 29.657824 -181.882129) (xy 29.61518 -181.804706)
			(xy 29.579989 -181.723623) (xy 29.552563 -181.639595) (xy 29.533143 -181.553365) (xy 29.521902 -181.465692)
			(xy 29.518937 -181.377352) (xy 29.524276 -181.289123) (xy 29.53787 -181.201784) (xy 29.559601 -181.116107)
			(xy 29.573982 -181.074314) (xy 29.579389 -181.057215) (xy 29.581493 -181.021431) (xy 29.573571 -180.986472)
			(xy 29.556247 -180.955091) (xy 29.54401 -180.94198) (xy 22.483064 -173.88078) (xy 22.483064 -111.364014)
			(xy 24.913336 -108.933742) (xy 24.913336 -104.003602) (xy 27.590496 -101.326188) (xy 29.35859 -101.326188)
			(xy 29.381329 -101.325684) (xy 29.426083 -101.317592) (xy 29.468681 -101.301663) (xy 29.507764 -101.278407)
			(xy 29.542083 -101.248566) (xy 29.570544 -101.213093) (xy 29.592236 -101.173121) (xy 29.606468 -101.129926)
			(xy 29.612785 -101.084888) (xy 29.610985 -101.039445) (xy 29.601125 -100.995048) (xy 29.592778 -100.97389)
			(xy 29.577538 -100.935282) (xy 29.571421 -100.920176) (xy 29.552751 -100.893476) (xy 29.527931 -100.87237)
			(xy 29.498578 -100.858233) (xy 29.466603 -100.851984) (xy 29.434087 -100.85403) (xy 29.403147 -100.864239)
			(xy 29.375798 -100.881946) (xy 29.364432 -100.893626) (xy 29.345726 -100.913418) (xy 29.303682 -100.948029)
			(xy 29.257144 -100.97631) (xy 29.207058 -100.997688) (xy 29.154441 -101.011728) (xy 29.100363 -101.018145)
			(xy 29.045922 -101.016807) (xy 28.992224 -101.007744) (xy 28.94036 -100.991138) (xy 28.891384 -100.967327)
			(xy 28.846291 -100.936795) (xy 28.805997 -100.900162) (xy 28.77132 -100.858172) (xy 28.742965 -100.811679)
			(xy 28.721508 -100.761627) (xy 28.707386 -100.709032) (xy 28.700884 -100.654964) (xy 28.702135 -100.600521)
			(xy 28.711114 -100.546809) (xy 28.727639 -100.494919) (xy 28.739084 -100.470208) (xy 28.751784 -100.444046)
			(xy 28.751784 -94.307152) (xy 23.200868 -88.756236) (xy 23.200868 -12.7127) (xy 25.393142 -10.520426)
			(xy 25.402794 -10.492994) (xy 25.412286 -10.46711) (xy 25.437662 -10.418167) (xy 25.469818 -10.373387)
			(xy 25.508087 -10.333702) (xy 25.551669 -10.299939) (xy 25.599657 -10.272801) (xy 25.651052 -10.252854)
			(xy 25.704784 -10.240514) (xy 25.759732 -10.236036) (xy 25.814752 -10.239515) (xy 25.868698 -10.250878)
			(xy 25.920447 -10.269889) (xy 25.968921 -10.29615) (xy 26.013109 -10.329116) (xy 26.052091 -10.3681)
			(xy 26.085056 -10.412289) (xy 26.111316 -10.460763) (xy 26.130325 -10.512512) (xy 26.141686 -10.566459)
			(xy 26.145164 -10.621479) (xy 26.140685 -10.676427) (xy 26.128342 -10.730158) (xy 26.108394 -10.781553)
			(xy 26.081255 -10.829541) (xy 26.047491 -10.873122) (xy 26.007805 -10.911389) (xy 25.963023 -10.943544)
			(xy 25.91408 -10.968918) (xy 25.888188 -10.978388) (xy 25.860756 -10.98804) (xy 25.810972 -11.037824)
			(xy 25.79961 -11.049971) (xy 25.783004 -11.078774) (xy 25.77441 -11.110892) (xy 25.774415 -11.14414)
			(xy 25.783016 -11.176256) (xy 25.79963 -11.205055) (xy 25.823126 -11.228579) (xy 25.851905 -11.245226)
			(xy 25.884011 -11.253866) (xy 25.900634 -11.254486) (xy 26.73096 -11.254486) (xy 27.852116 -10.133584)
			(xy 27.852116 -9.391904) (xy 27.851605 -9.368753) (xy 27.843219 -9.323218) (xy 27.826724 -9.279954)
			(xy 27.802665 -9.240395) (xy 27.771839 -9.205847) (xy 27.735264 -9.177455) (xy 27.694152 -9.156157)
			(xy 27.649862 -9.142658) (xy 27.603859 -9.137405) (xy 27.557667 -9.140572) (xy 27.512811 -9.152053)
			(xy 27.470778 -9.171469) (xy 27.451558 -9.184386) (xy 27.426498 -9.201488) (xy 27.372758 -9.229645)
			(xy 27.315768 -9.250456) (xy 27.256529 -9.263557) (xy 27.196079 -9.268719) (xy 27.135477 -9.26585)
			(xy 27.075784 -9.255002) (xy 27.018048 -9.236363) (xy 26.963279 -9.210262) (xy 26.912438 -9.177155)
			(xy 26.866416 -9.137622) (xy 26.826019 -9.092357) (xy 26.791955 -9.042152) (xy 26.764821 -8.987888)
			(xy 26.745092 -8.930515) (xy 26.733115 -8.871038) (xy 26.729099 -8.810501) (xy 26.733115 -8.749964)
			(xy 26.745092 -8.690488) (xy 26.76482 -8.633114) (xy 26.791954 -8.57885) (xy 26.826017 -8.528645)
			(xy 26.866414 -8.483379) (xy 26.912436 -8.443847) (xy 26.963277 -8.410739) (xy 27.018046 -8.384638)
			(xy 27.075782 -8.365999) (xy 27.135474 -8.35515) (xy 27.196077 -8.352281) (xy 27.256527 -8.357442)
			(xy 27.315766 -8.370543) (xy 27.372755 -8.391354) (xy 27.426496 -8.419511) (xy 27.451558 -8.43661)
			(xy 27.470765 -8.449548) (xy 27.512803 -8.468967) (xy 27.557662 -8.480449) (xy 27.603859 -8.483616)
			(xy 27.649866 -8.478363) (xy 27.69416 -8.464863) (xy 27.735276 -8.443563) (xy 27.771854 -8.415167)
			(xy 27.802684 -8.380616) (xy 27.826744 -8.341053) (xy 27.843241 -8.297785) (xy 27.851627 -8.252245)
			(xy 27.852116 -8.229092) (xy 27.852116 -7.243064) (xy 27.85167 -7.221343) (xy 27.844278 -7.178533)
			(xy 27.829716 -7.137604) (xy 27.808408 -7.099745) (xy 27.780973 -7.066061) (xy 27.748211 -7.037531)
			(xy 27.711076 -7.014987) (xy 27.670649 -6.999083) (xy 27.628106 -6.990285) (xy 27.584687 -6.988847)
			(xy 27.541655 -6.994811) (xy 27.500264 -7.008005) (xy 27.461719 -7.028043) (xy 27.444192 -7.04088)
			(xy 27.420095 -7.058582) (xy 27.368183 -7.08825) (xy 27.312848 -7.110905) (xy 27.255035 -7.12616)
			(xy 27.195728 -7.133756) (xy 27.135936 -7.133564) (xy 27.076678 -7.125587) (xy 27.018964 -7.109961)
			(xy 26.963777 -7.086951) (xy 26.912056 -7.05695) (xy 26.864683 -7.020468) (xy 26.822464 -6.978128)
			(xy 26.786119 -6.930651) (xy 26.756266 -6.878844) (xy 26.733415 -6.823591) (xy 26.717954 -6.765832)
			(xy 26.710147 -6.706552) (xy 26.710127 -6.646759) (xy 26.717894 -6.587474) (xy 26.733315 -6.529705)
			(xy 26.756129 -6.474436) (xy 26.785946 -6.422609) (xy 26.822259 -6.375106) (xy 26.864449 -6.332737)
			(xy 26.911797 -6.296224) (xy 26.963497 -6.266188) (xy 27.018669 -6.24314) (xy 27.076373 -6.227475)
			(xy 27.135625 -6.219457) (xy 27.195417 -6.219224) (xy 27.254729 -6.22678) (xy 27.312553 -6.241997)
			(xy 27.367902 -6.264614) (xy 27.419835 -6.294247) (xy 27.467466 -6.33039) (xy 27.509985 -6.37243)
			(xy 27.546666 -6.419648) (xy 27.576886 -6.471241) (xy 27.588972 -6.49859) (xy 27.598232 -6.519227)
			(xy 27.622936 -6.557113) (xy 27.65395 -6.590033) (xy 27.690299 -6.616948) (xy 27.730834 -6.63701)
			(xy 27.774279 -6.649586) (xy 27.819263 -6.654279) (xy 27.864368 -6.650943) (xy 27.908172 -6.639681)
			(xy 27.949294 -6.620849) (xy 27.986437 -6.595042) (xy 28.002738 -6.579362) (xy 29.570172 -5.011928)
			(xy 29.586428 -4.9403) (xy 29.573982 -4.905756) (xy 29.559991 -4.865074) (xy 29.538624 -4.781734)
			(xy 29.52496 -4.696791) (xy 29.519113 -4.610954) (xy 29.521132 -4.524942) (xy 29.530999 -4.439475)
			(xy 29.548633 -4.355266) (xy 29.573886 -4.27302) (xy 29.606547 -4.193425) (xy 29.646342 -4.117146)
			(xy 29.692939 -4.044821) (xy 29.745948 -3.977056) (xy 29.804926 -3.914416) (xy 29.869379 -3.857427)
			(xy 29.938769 -3.806563) (xy 30.012516 -3.762251) (xy 30.090002 -3.724861) (xy 30.170579 -3.694706)
			(xy 30.253575 -3.672038) (xy 30.338294 -3.657046) (xy 30.424029 -3.649856) (xy 30.510062 -3.650529)
			(xy 30.595673 -3.659058) (xy 30.680148 -3.675372) (xy 30.762779 -3.699334) (xy 30.842876 -3.730745)
			(xy 30.919768 -3.769342) (xy 30.992813 -3.814801) (xy 31.061399 -3.866743) (xy 31.124954 -3.924733)
			(xy 31.182946 -3.988287) (xy 31.234889 -4.056873) (xy 31.28035 -4.129917) (xy 31.318948 -4.206808)
			(xy 31.35036 -4.286904) (xy 31.374324 -4.369535) (xy 31.39064 -4.454009) (xy 31.39917 -4.53962) (xy 31.399844 -4.625653)
			(xy 31.392656 -4.711388) (xy 31.377666 -4.796108) (xy 31.355 -4.879103) (xy 31.324846 -4.959682)
			(xy 31.287458 -5.037169) (xy 31.243147 -5.110916) (xy 31.192285 -5.180307) (xy 31.135296 -5.244761)
			(xy 31.072658 -5.303741) (xy 31.004893 -5.356751) (xy 30.93257 -5.403349) (xy 30.856292 -5.443146)
			(xy 30.776697 -5.475808) (xy 30.694452 -5.501062) (xy 30.610243 -5.518698) (xy 30.524775 -5.528567)
			(xy 30.438764 -5.530587) (xy 30.352927 -5.524742) (xy 30.267983 -5.511079) (xy 30.184643 -5.489714)
			(xy 30.143958 -5.475732) (xy 30.126858 -5.470318) (xy 30.091068 -5.468202) (xy 30.0561 -5.476117)
			(xy 30.024709 -5.493437) (xy 30.011624 -5.505704) (xy 28.513024 -7.00405) (xy 28.513024 -7.173484)
			(xy 29.519874 -7.173484) (xy 29.519874 -7.086584) (xy 29.527892 -7.000055) (xy 29.54386 -6.914635)
			(xy 29.567641 -6.831053) (xy 29.599033 -6.750021) (xy 29.637767 -6.672232) (xy 29.683514 -6.598348)
			(xy 29.735883 -6.529001) (xy 29.794427 -6.464781) (xy 29.858647 -6.406237) (xy 29.927994 -6.353868)
			(xy 30.001878 -6.308121) (xy 30.079667 -6.269387) (xy 30.160699 -6.237995) (xy 30.244281 -6.214214)
			(xy 30.329701 -6.198246) (xy 30.41623 -6.190228) (xy 30.45968 -6.189726) (xy 30.50313 -6.190228)
			(xy 30.589659 -6.198246) (xy 30.675079 -6.214214) (xy 30.758661 -6.237995) (xy 30.839693 -6.269387)
			(xy 30.917482 -6.308121) (xy 30.991366 -6.353868) (xy 31.060713 -6.406237) (xy 31.124933 -6.464781)
			(xy 31.183477 -6.529001) (xy 31.235846 -6.598348) (xy 31.281593 -6.672232) (xy 31.320327 -6.750021)
			(xy 31.351719 -6.831053) (xy 31.3755 -6.914635) (xy 31.391468 -7.000055) (xy 31.399486 -7.086584)
			(xy 31.399486 -7.173484) (xy 34.599874 -7.173484) (xy 34.599874 -7.086584) (xy 34.607892 -7.000055)
			(xy 34.62386 -6.914635) (xy 34.647641 -6.831053) (xy 34.679033 -6.750021) (xy 34.717767 -6.672232)
			(xy 34.763514 -6.598348) (xy 34.815883 -6.529001) (xy 34.874427 -6.464781) (xy 34.938647 -6.406237)
			(xy 35.007994 -6.353868) (xy 35.081878 -6.308121) (xy 35.159667 -6.269387) (xy 35.240699 -6.237995)
			(xy 35.324281 -6.214214) (xy 35.409701 -6.198246) (xy 35.49623 -6.190228) (xy 35.53968 -6.189726)
			(xy 35.58313 -6.190228) (xy 35.669659 -6.198246) (xy 35.755079 -6.214214) (xy 35.838661 -6.237995)
			(xy 35.919693 -6.269387) (xy 35.997482 -6.308121) (xy 36.071366 -6.353868) (xy 36.140713 -6.406237)
			(xy 36.204933 -6.464781) (xy 36.263477 -6.529001) (xy 36.315846 -6.598348) (xy 36.361593 -6.672232)
			(xy 36.400327 -6.750021) (xy 36.431719 -6.831053) (xy 36.4555 -6.914635) (xy 36.471468 -7.000055)
			(xy 36.479486 -7.086584) (xy 36.479486 -7.173484) (xy 36.471468 -7.260013) (xy 36.4555 -7.345433)
			(xy 36.431719 -7.429015) (xy 36.400327 -7.510047) (xy 36.361593 -7.587836) (xy 36.315846 -7.66172)
			(xy 36.263477 -7.731067) (xy 36.204933 -7.795287) (xy 36.140713 -7.853831) (xy 36.071366 -7.9062)
			(xy 35.997482 -7.951947) (xy 35.919693 -7.990681) (xy 35.838661 -8.022073) (xy 35.755079 -8.045854)
			(xy 35.669659 -8.061822) (xy 35.58313 -8.06984) (xy 35.49623 -8.06984) (xy 35.409701 -8.061822) (xy 35.324281 -8.045854)
			(xy 35.240699 -8.022073) (xy 35.159667 -7.990681) (xy 35.081878 -7.951947) (xy 35.007994 -7.9062)
			(xy 34.938647 -7.853831) (xy 34.874427 -7.795287) (xy 34.815883 -7.731067) (xy 34.763514 -7.66172)
			(xy 34.717767 -7.587836) (xy 34.679033 -7.510047) (xy 34.647641 -7.429015) (xy 34.62386 -7.345433)
			(xy 34.607892 -7.260013) (xy 34.599874 -7.173484) (xy 31.399486 -7.173484) (xy 31.391468 -7.260013)
			(xy 31.3755 -7.345433) (xy 31.351719 -7.429015) (xy 31.320327 -7.510047) (xy 31.281593 -7.587836)
			(xy 31.235846 -7.66172) (xy 31.183477 -7.731067) (xy 31.124933 -7.795287) (xy 31.060713 -7.853831)
			(xy 30.991366 -7.9062) (xy 30.917482 -7.951947) (xy 30.839693 -7.990681) (xy 30.758661 -8.022073)
			(xy 30.675079 -8.045854) (xy 30.589659 -8.061822) (xy 30.50313 -8.06984) (xy 30.41623 -8.06984) (xy 30.329701 -8.061822)
			(xy 30.244281 -8.045854) (xy 30.160699 -8.022073) (xy 30.079667 -7.990681) (xy 30.001878 -7.951947)
			(xy 29.927994 -7.9062) (xy 29.858647 -7.853831) (xy 29.794427 -7.795287) (xy 29.735883 -7.731067)
			(xy 29.683514 -7.66172) (xy 29.637767 -7.587836) (xy 29.599033 -7.510047) (xy 29.567641 -7.429015)
			(xy 29.54386 -7.345433) (xy 29.527892 -7.260013) (xy 29.519874 -7.173484) (xy 28.513024 -7.173484)
			(xy 28.513024 -10.407396) (xy 27.004772 -11.915648) (xy 26.044652 -11.915648) (xy 24.241252 -13.719048)
			(xy 24.241252 -17.0053) (xy 24.241761 -17.028346) (xy 24.250086 -17.073679) (xy 24.266445 -17.11677)
			(xy 24.290302 -17.156207) (xy 24.320876 -17.190698) (xy 24.357165 -17.219114) (xy 24.397982 -17.240525)
			(xy 24.441989 -17.254229) (xy 24.487745 -17.259777) (xy 24.533752 -17.256988) (xy 24.578503 -17.245953)
			(xy 24.620532 -17.227034) (xy 24.658464 -17.200849) (xy 24.675084 -17.184878) (xy 26.134822 -15.724886)
			(xy 26.144474 -15.697454) (xy 26.153962 -15.671567) (xy 26.179332 -15.622617) (xy 26.211484 -15.577829)
			(xy 26.249749 -15.538136) (xy 26.29333 -15.504366) (xy 26.341318 -15.477221) (xy 26.392715 -15.457267)
			(xy 26.446448 -15.44492) (xy 26.501399 -15.440437) (xy 26.556423 -15.443912) (xy 26.610374 -15.455272)
			(xy 26.662127 -15.47428) (xy 26.710605 -15.500541) (xy 26.754798 -15.533507) (xy 26.793784 -15.572492)
			(xy 26.826751 -15.616683) (xy 26.853014 -15.66516) (xy 26.872024 -15.716913) (xy 26.883386 -15.770863)
			(xy 26.886863 -15.825887) (xy 26.882382 -15.880838) (xy 26.870037 -15.934572) (xy 26.850085 -15.985969)
			(xy 26.822942 -16.033959) (xy 26.789173 -16.077541) (xy 26.749482 -16.115807) (xy 26.704695 -16.147961)
			(xy 26.655746 -16.173332) (xy 26.629868 -16.182848) (xy 26.602436 -16.1925) (xy 24.728932 -18.06575)
			(xy 24.728932 -18.631916) (xy 24.729443 -18.654955) (xy 24.737769 -18.700276) (xy 24.754127 -18.743354)
			(xy 24.777981 -18.782778) (xy 24.80855 -18.817257) (xy 24.844833 -18.845662) (xy 24.885641 -18.867063)
			(xy 24.929638 -18.880757) (xy 24.975383 -18.886298) (xy 25.021377 -18.883503) (xy 25.066114 -18.872464)
			(xy 25.108129 -18.853543) (xy 25.146046 -18.827359) (xy 25.162764 -18.811494) (xy 27.961844 -16.01216)
			(xy 27.961844 -15.431008) (xy 27.961375 -15.408655) (xy 27.953555 -15.364638) (xy 27.938155 -15.322667)
			(xy 27.91565 -15.284038) (xy 27.886735 -15.249942) (xy 27.8523 -15.221431) (xy 27.813408 -15.199383)
			(xy 27.771259 -15.184479) (xy 27.727153 -15.177179) (xy 27.704796 -15.177008) (xy 27.677305 -15.176896)
			(xy 27.622801 -15.169733) (xy 27.569888 -15.154823) (xy 27.519663 -15.132473) (xy 27.473166 -15.103146)
			(xy 27.431358 -15.06745) (xy 27.395107 -15.026123) (xy 27.365162 -14.980022) (xy 27.342143 -14.9301)
			(xy 27.326527 -14.877391) (xy 27.318638 -14.822987) (xy 27.318638 -14.768013) (xy 27.326527 -14.713609)
			(xy 27.342143 -14.6609) (xy 27.365162 -14.610978) (xy 27.395107 -14.564877) (xy 27.431358 -14.52355)
			(xy 27.473166 -14.487854) (xy 27.519663 -14.458527) (xy 27.569888 -14.436177) (xy 27.622801 -14.421267)
			(xy 27.677305 -14.414104) (xy 27.704796 -14.413992) (xy 27.727156 -14.413795) (xy 27.77127 -14.40651)
			(xy 27.813429 -14.391617) (xy 27.852331 -14.369577) (xy 27.886776 -14.341069) (xy 27.915701 -14.306974)
			(xy 27.938214 -14.268344) (xy 27.953619 -14.22637) (xy 27.961441 -14.182348) (xy 27.961844 -14.159992)
			(xy 27.961844 -13.243306) (xy 27.961306 -13.219851) (xy 27.9527 -13.173738) (xy 27.935781 -13.129987)
			(xy 27.911121 -13.090083) (xy 27.879559 -13.05538) (xy 27.842165 -13.027057) (xy 27.80021 -13.006076)
			(xy 27.755118 -12.993148) (xy 27.708419 -12.988713) (xy 27.661699 -12.992921) (xy 27.616544 -13.005629)
			(xy 27.574487 -13.026406) (xy 27.555444 -13.040106) (xy 27.530576 -13.058139) (xy 27.476946 -13.088093)
			(xy 27.419791 -13.110601) (xy 27.360138 -13.12526) (xy 27.29906 -13.131806) (xy 27.237655 -13.13012)
			(xy 27.177028 -13.120233) (xy 27.118269 -13.102323) (xy 27.062435 -13.076713) (xy 27.010529 -13.043862)
			(xy 26.963486 -13.004361) (xy 26.922151 -12.958921) (xy 26.887267 -12.908359) (xy 26.859462 -12.853584)
			(xy 26.839237 -12.795582) (xy 26.826954 -12.735394) (xy 26.822834 -12.674105) (xy 26.826952 -12.612815)
			(xy 26.839234 -12.552628) (xy 26.859459 -12.494625) (xy 26.887262 -12.439849) (xy 26.922145 -12.389286)
			(xy 26.963479 -12.343846) (xy 27.010521 -12.304344) (xy 27.062426 -12.271492) (xy 27.11826 -12.24588)
			(xy 27.177019 -12.227969) (xy 27.237646 -12.218081) (xy 27.29905 -12.216394) (xy 27.360128 -12.222938)
			(xy 27.419782 -12.237596) (xy 27.476938 -12.260103) (xy 27.530568 -12.290056) (xy 27.555444 -12.308078)
			(xy 27.574526 -12.321714) (xy 27.61657 -12.342486) (xy 27.661711 -12.355192) (xy 27.708416 -12.359399)
			(xy 27.755101 -12.354966) (xy 27.80018 -12.342042) (xy 27.842123 -12.321066) (xy 27.879504 -12.292751)
			(xy 27.911056 -12.258058) (xy 27.935707 -12.218164) (xy 27.952619 -12.174425) (xy 27.96122 -12.128326)
			(xy 27.961844 -12.104878) (xy 27.961844 -11.809222) (xy 29.172408 -10.598912) (xy 29.47416 -10.598912)
			(xy 29.497161 -10.598418) (xy 29.542412 -10.590147) (xy 29.585435 -10.573866) (xy 29.624826 -10.550108)
			(xy 29.659299 -10.519649) (xy 29.687726 -10.483483) (xy 29.709181 -10.442792) (xy 29.722962 -10.398904)
			(xy 29.728619 -10.353252) (xy 29.725968 -10.307328) (xy 29.715095 -10.26263) (xy 29.696355 -10.220619)
			(xy 29.68371 -10.201402) (xy 29.659572 -10.165265) (xy 29.617294 -10.089334) (xy 29.582202 -10.009826)
			(xy 29.554594 -9.927419) (xy 29.534708 -9.842816) (xy 29.522712 -9.75674) (xy 29.518709 -9.669924)
			(xy 29.522732 -9.583109) (xy 29.534748 -9.497036) (xy 29.554655 -9.412438) (xy 29.582281 -9.330038)
			(xy 29.617392 -9.250538) (xy 29.659688 -9.174616) (xy 29.708808 -9.102921) (xy 29.764333 -9.036063)
			(xy 29.82579 -8.974613) (xy 29.892654 -8.919096) (xy 29.964355 -8.869984) (xy 30.040282 -8.827697)
			(xy 30.119786 -8.792595) (xy 30.20219 -8.764978) (xy 30.28679 -8.745082) (xy 30.372865 -8.733076)
			(xy 30.45968 -8.729063) (xy 30.546495 -8.733076) (xy 30.63257 -8.745082) (xy 30.71717 -8.764978)
			(xy 30.799574 -8.792595) (xy 30.879078 -8.827697) (xy 30.955005 -8.869984) (xy 31.026706 -8.919096)
			(xy 31.09357 -8.974613) (xy 31.155027 -9.036063) (xy 31.210552 -9.102921) (xy 31.259672 -9.174616)
			(xy 31.301968 -9.250538) (xy 31.337079 -9.330038) (xy 31.364705 -9.412438) (xy 31.384612 -9.497036)
			(xy 31.396628 -9.583109) (xy 31.400651 -9.669924) (xy 31.396648 -9.75674) (xy 31.384652 -9.842816)
			(xy 31.364766 -9.927419) (xy 31.337158 -10.009826) (xy 31.302066 -10.089334) (xy 31.259788 -10.165265)
			(xy 31.23565 -10.201402) (xy 31.223068 -10.220655) (xy 31.204336 -10.262656) (xy 31.193468 -10.307343)
			(xy 31.190819 -10.353255) (xy 31.196475 -10.398895) (xy 31.210252 -10.442772) (xy 31.231699 -10.483453)
			(xy 31.260118 -10.519611) (xy 31.294578 -10.550065) (xy 31.333957 -10.57382) (xy 31.376967 -10.590102)
			(xy 31.422206 -10.598377) (xy 31.4452 -10.598912) (xy 34.07156 -10.598912) (xy 34.606484 -10.063988)
			(xy 34.618158 -10.051508) (xy 34.635005 -10.021791) (xy 34.643362 -9.988669) (xy 34.64263 -9.954516)
			(xy 34.638234 -9.938004) (xy 34.62627 -9.896021) (xy 34.609253 -9.810392) (xy 34.600247 -9.723554)
			(xy 34.599327 -9.636256) (xy 34.606501 -9.549248) (xy 34.621709 -9.463279) (xy 34.644819 -9.37909)
			(xy 34.675632 -9.297405) (xy 34.713883 -9.218927) (xy 34.759242 -9.144332) (xy 34.81132 -9.074262)
			(xy 34.869668 -9.009321) (xy 34.933783 -8.950066) (xy 35.003114 -8.897008) (xy 35.077064 -8.850605)
			(xy 35.154996 -8.811255) (xy 35.23624 -8.779296) (xy 35.320096 -8.755006) (xy 35.405842 -8.738591)
			(xy 35.492741 -8.730194) (xy 35.580044 -8.729887) (xy 35.666999 -8.737672) (xy 35.752859 -8.753483)
			(xy 35.836884 -8.777183) (xy 35.918351 -8.808568) (xy 35.996558 -8.847369) (xy 36.070833 -8.893251)
			(xy 36.140536 -8.945819) (xy 36.205066 -9.004621) (xy 36.263869 -9.069151) (xy 36.316439 -9.138853)
			(xy 36.362322 -9.213127) (xy 36.401125 -9.291333) (xy 36.432512 -9.372799) (xy 36.456213 -9.456824)
			(xy 36.472026 -9.542683) (xy 36.479813 -9.629639) (xy 36.479507 -9.716942) (xy 36.471112 -9.80384)
			(xy 36.454698 -9.889587) (xy 36.430409 -9.973444) (xy 36.398453 -10.054688) (xy 36.359104 -10.132621)
			(xy 36.312702 -10.206572) (xy 36.259645 -10.275904) (xy 36.200392 -10.34002) (xy 36.135451 -10.398369)
			(xy 36.065382 -10.450448) (xy 35.990788 -10.495809) (xy 35.912311 -10.534061) (xy 35.830627 -10.564876)
			(xy 35.746438 -10.587987) (xy 35.660469 -10.603196) (xy 35.573462 -10.610373) (xy 35.486163 -10.609454)
			(xy 35.399325 -10.600449) (xy 35.313696 -10.583435) (xy 35.27171 -10.57148) (xy 35.255189 -10.567126)
			(xy 35.221046 -10.566392) (xy 35.18793 -10.57474) (xy 35.158214 -10.591571) (xy 35.145726 -10.60323)
			(xy 34.387536 -11.36142) (xy 31.495492 -11.36142) (xy 31.473337 -11.361902) (xy 31.429699 -11.36959)
			(xy 31.388057 -11.384731) (xy 31.349672 -11.406866) (xy 31.315709 -11.435323) (xy 31.287197 -11.469241)
			(xy 31.265001 -11.507591) (xy 31.249794 -11.54921) (xy 31.242037 -11.592835) (xy 31.241966 -11.637145)
			(xy 31.249581 -11.680795) (xy 31.264654 -11.722463) (xy 31.275274 -11.741912) (xy 31.296335 -11.779586)
			(xy 31.332262 -11.858072) (xy 31.360846 -11.93952) (xy 31.381845 -12.023244) (xy 31.395083 -12.108541)
			(xy 31.400449 -12.194691) (xy 31.39871 -12.253484) (xy 34.599874 -12.253484) (xy 34.599874 -12.166584)
			(xy 34.607892 -12.080055) (xy 34.62386 -11.994635) (xy 34.647641 -11.911053) (xy 34.679033 -11.830021)
			(xy 34.717767 -11.752232) (xy 34.763514 -11.678348) (xy 34.815883 -11.609001) (xy 34.874427 -11.544781)
			(xy 34.938647 -11.486237) (xy 35.007994 -11.433868) (xy 35.081878 -11.388121) (xy 35.159667 -11.349387)
			(xy 35.240699 -11.317995) (xy 35.324281 -11.294214) (xy 35.409701 -11.278246) (xy 35.49623 -11.270228)
			(xy 35.53968 -11.269726) (xy 35.58313 -11.270228) (xy 35.669659 -11.278246) (xy 35.755079 -11.294214)
			(xy 35.838661 -11.317995) (xy 35.919693 -11.349387) (xy 35.997482 -11.388121) (xy 36.071366 -11.433868)
			(xy 36.140713 -11.486237) (xy 36.204933 -11.544781) (xy 36.263477 -11.609001) (xy 36.315846 -11.678348)
			(xy 36.361593 -11.752232) (xy 36.400327 -11.830021) (xy 36.431719 -11.911053) (xy 36.4555 -11.994635)
			(xy 36.471468 -12.080055) (xy 36.479486 -12.166584) (xy 36.479486 -12.253484) (xy 36.471468 -12.340013)
			(xy 36.4555 -12.425433) (xy 36.431719 -12.509015) (xy 36.400327 -12.590047) (xy 36.361593 -12.667836)
			(xy 36.315846 -12.74172) (xy 36.263477 -12.811067) (xy 36.204933 -12.875287) (xy 36.140713 -12.933831)
			(xy 36.071366 -12.9862) (xy 35.997482 -13.031947) (xy 35.919693 -13.070681) (xy 35.838661 -13.102073)
			(xy 35.755079 -13.125854) (xy 35.669659 -13.141822) (xy 35.58313 -13.14984) (xy 35.49623 -13.14984)
			(xy 35.409701 -13.141822) (xy 35.324281 -13.125854) (xy 35.240699 -13.102073) (xy 35.159667 -13.070681)
			(xy 35.081878 -13.031947) (xy 35.007994 -12.9862) (xy 34.938647 -12.933831) (xy 34.874427 -12.875287)
			(xy 34.815883 -12.811067) (xy 34.763514 -12.74172) (xy 34.717767 -12.667836) (xy 34.679033 -12.590047)
			(xy 34.647641 -12.509015) (xy 34.62386 -12.425433) (xy 34.607892 -12.340013) (xy 34.599874 -12.253484)
			(xy 31.39871 -12.253484) (xy 31.397897 -12.280971) (xy 31.387448 -12.366654) (xy 31.369191 -12.451019)
			(xy 31.34328 -12.533356) (xy 31.309932 -12.612972) (xy 31.269428 -12.689196) (xy 31.222109 -12.761388)
			(xy 31.168373 -12.828939) (xy 31.108672 -12.891282) (xy 31.04351 -12.947891) (xy 30.973434 -12.998291)
			(xy 30.899034 -13.042056) (xy 30.820936 -13.078818) (xy 30.739798 -13.108269) (xy 30.656302 -13.13016)
			(xy 30.571152 -13.144308) (xy 30.485063 -13.150592) (xy 30.398761 -13.14896) (xy 30.312971 -13.139426)
			(xy 30.228416 -13.12207) (xy 30.145808 -13.097038) (xy 30.065841 -13.064541) (xy 29.989189 -13.024853)
			(xy 29.916496 -12.978306) (xy 29.848375 -12.925294) (xy 29.785399 -12.866262) (xy 29.728098 -12.801707)
			(xy 29.676955 -12.732173) (xy 29.632398 -12.658244) (xy 29.594805 -12.580543) (xy 29.56449 -12.499723)
			(xy 29.541709 -12.416466) (xy 29.526655 -12.331471) (xy 29.519453 -12.245454) (xy 29.520164 -12.15914)
			(xy 29.528782 -12.073253) (xy 29.545235 -11.988518) (xy 29.569384 -11.905647) (xy 29.601026 -11.825338)
			(xy 29.639895 -11.748267) (xy 29.685663 -11.675082) (xy 29.737946 -11.6064) (xy 29.766768 -11.574272)
			(xy 29.800042 -11.53795) (xy 29.800042 -11.48842) (xy 29.799501 -11.471768) (xy 29.790888 -11.439597)
			(xy 29.774242 -11.410751) (xy 29.750698 -11.387196) (xy 29.72186 -11.370536) (xy 29.689694 -11.361907)
			(xy 29.673042 -11.36142) (xy 29.488384 -11.36142) (xy 28.72486 -12.125198) (xy 28.72486 -14.793484)
			(xy 29.519874 -14.793484) (xy 29.519874 -14.706584) (xy 29.527892 -14.620055) (xy 29.54386 -14.534635)
			(xy 29.567641 -14.451053) (xy 29.599033 -14.370021) (xy 29.637767 -14.292232) (xy 29.683514 -14.218348)
			(xy 29.735883 -14.149001) (xy 29.794427 -14.084781) (xy 29.858647 -14.026237) (xy 29.927994 -13.973868)
			(xy 30.001878 -13.928121) (xy 30.079667 -13.889387) (xy 30.160699 -13.857995) (xy 30.244281 -13.834214)
			(xy 30.329701 -13.818246) (xy 30.41623 -13.810228) (xy 30.45968 -13.809726) (xy 30.50313 -13.810228)
			(xy 30.589659 -13.818246) (xy 30.675079 -13.834214) (xy 30.758661 -13.857995) (xy 30.839693 -13.889387)
			(xy 30.917482 -13.928121) (xy 30.991366 -13.973868) (xy 31.060713 -14.026237) (xy 31.124933 -14.084781)
			(xy 31.183477 -14.149001) (xy 31.235846 -14.218348) (xy 31.281593 -14.292232) (xy 31.320327 -14.370021)
			(xy 31.351719 -14.451053) (xy 31.3755 -14.534635) (xy 31.391468 -14.620055) (xy 31.399486 -14.706584)
			(xy 31.399486 -14.793484) (xy 34.599874 -14.793484) (xy 34.599874 -14.706584) (xy 34.607892 -14.620055)
			(xy 34.62386 -14.534635) (xy 34.647641 -14.451053) (xy 34.679033 -14.370021) (xy 34.717767 -14.292232)
			(xy 34.763514 -14.218348) (xy 34.815883 -14.149001) (xy 34.874427 -14.084781) (xy 34.938647 -14.026237)
			(xy 35.007994 -13.973868) (xy 35.081878 -13.928121) (xy 35.159667 -13.889387) (xy 35.240699 -13.857995)
			(xy 35.324281 -13.834214) (xy 35.409701 -13.818246) (xy 35.49623 -13.810228) (xy 35.53968 -13.809726)
			(xy 35.58313 -13.810228) (xy 35.669659 -13.818246) (xy 35.755079 -13.834214) (xy 35.838661 -13.857995)
			(xy 35.919693 -13.889387) (xy 35.997482 -13.928121) (xy 36.071366 -13.973868) (xy 36.140713 -14.026237)
			(xy 36.204933 -14.084781) (xy 36.263477 -14.149001) (xy 36.315846 -14.218348) (xy 36.361593 -14.292232)
			(xy 36.400327 -14.370021) (xy 36.431719 -14.451053) (xy 36.4555 -14.534635) (xy 36.471468 -14.620055)
			(xy 36.479486 -14.706584) (xy 36.479486 -14.793484) (xy 36.471468 -14.880013) (xy 36.4555 -14.965433)
			(xy 36.431719 -15.049015) (xy 36.400327 -15.130047) (xy 36.361593 -15.207836) (xy 36.315846 -15.28172)
			(xy 36.263477 -15.351067) (xy 36.204933 -15.415287) (xy 36.140713 -15.473831) (xy 36.071366 -15.5262)
			(xy 35.997482 -15.571947) (xy 35.919693 -15.610681) (xy 35.838661 -15.642073) (xy 35.755079 -15.665854)
			(xy 35.669659 -15.681822) (xy 35.58313 -15.68984) (xy 35.49623 -15.68984) (xy 35.409701 -15.681822)
			(xy 35.324281 -15.665854) (xy 35.240699 -15.642073) (xy 35.159667 -15.610681) (xy 35.081878 -15.571947)
			(xy 35.007994 -15.5262) (xy 34.938647 -15.473831) (xy 34.874427 -15.415287) (xy 34.815883 -15.351067)
			(xy 34.763514 -15.28172) (xy 34.717767 -15.207836) (xy 34.679033 -15.130047) (xy 34.647641 -15.049015)
			(xy 34.62386 -14.965433) (xy 34.607892 -14.880013) (xy 34.599874 -14.793484) (xy 31.399486 -14.793484)
			(xy 31.391468 -14.880013) (xy 31.3755 -14.965433) (xy 31.351719 -15.049015) (xy 31.320327 -15.130047)
			(xy 31.281593 -15.207836) (xy 31.235846 -15.28172) (xy 31.183477 -15.351067) (xy 31.124933 -15.415287)
			(xy 31.060713 -15.473831) (xy 30.991366 -15.5262) (xy 30.917482 -15.571947) (xy 30.839693 -15.610681)
			(xy 30.758661 -15.642073) (xy 30.675079 -15.665854) (xy 30.589659 -15.681822) (xy 30.50313 -15.68984)
			(xy 30.41623 -15.68984) (xy 30.329701 -15.681822) (xy 30.244281 -15.665854) (xy 30.160699 -15.642073)
			(xy 30.079667 -15.610681) (xy 30.001878 -15.571947) (xy 29.927994 -15.5262) (xy 29.858647 -15.473831)
			(xy 29.794427 -15.415287) (xy 29.735883 -15.351067) (xy 29.683514 -15.28172) (xy 29.637767 -15.207836)
			(xy 29.599033 -15.130047) (xy 29.567641 -15.049015) (xy 29.54386 -14.965433) (xy 29.527892 -14.880013)
			(xy 29.519874 -14.793484) (xy 28.72486 -14.793484) (xy 28.72486 -16.328136) (xy 27.413712 -17.63903)
			(xy 27.398097 -17.655331) (xy 27.372315 -17.692379) (xy 27.353486 -17.733399) (xy 27.342202 -17.777102)
			(xy 27.338819 -17.822111) (xy 27.343443 -17.867009) (xy 27.355928 -17.910383) (xy 27.375882 -17.950869)
			(xy 27.402677 -17.987191) (xy 27.435468 -18.018207) (xy 27.454098 -18.030952) (xy 27.477765 -18.047084)
			(xy 27.520421 -18.085306) (xy 27.556866 -18.12949) (xy 27.586278 -18.178636) (xy 27.597608 -18.204942)
			(xy 27.606702 -18.225767) (xy 27.63116 -18.264058) (xy 27.662039 -18.297389) (xy 27.698354 -18.324696)
			(xy 27.738946 -18.345109) (xy 27.782522 -18.357976) (xy 27.827692 -18.362887) (xy 27.873016 -18.359686)
			(xy 27.917047 -18.348475) (xy 27.958382 -18.329611) (xy 27.995702 -18.303695) (xy 28.012136 -18.288)
			(xy 28.03017 -18.27022) (xy 29.511498 -18.27022) (xy 29.533244 -18.269774) (xy 29.576101 -18.26237)
			(xy 29.617071 -18.247776) (xy 29.654958 -18.22642) (xy 29.688656 -18.198925) (xy 29.717181 -18.166094)
			(xy 29.739699 -18.128886) (xy 29.755553 -18.088387) (xy 29.76428 -18.04578) (xy 29.765626 -18.002309)
			(xy 29.75955 -17.959244) (xy 29.746231 -17.917842) (xy 29.726057 -17.879312) (xy 29.713174 -17.861788)
			(xy 29.687064 -17.826888) (xy 29.640694 -17.753077) (xy 29.601354 -17.675292) (xy 29.569382 -17.5942)
			(xy 29.545052 -17.510497) (xy 29.528574 -17.424901) (xy 29.520088 -17.338148) (xy 29.519668 -17.250981)
			(xy 29.527317 -17.16415) (xy 29.542969 -17.0784) (xy 29.566491 -16.994466) (xy 29.59768 -16.913069)
			(xy 29.636268 -16.834908) (xy 29.681924 -16.760654) (xy 29.734257 -16.690944) (xy 29.792816 -16.626377)
			(xy 29.8571 -16.567507) (xy 29.926557 -16.514839) (xy 30.00059 -16.468825) (xy 30.078564 -16.429861)
			(xy 30.159809 -16.39828) (xy 30.243629 -16.374354) (xy 30.329303 -16.358289) (xy 30.416096 -16.350221)
			(xy 30.503264 -16.350221) (xy 30.590057 -16.358289) (xy 30.675731 -16.374354) (xy 30.759551 -16.39828)
			(xy 30.840796 -16.429861) (xy 30.91877 -16.468825) (xy 30.992803 -16.514839) (xy 31.06226 -16.567507)
			(xy 31.126544 -16.626377) (xy 31.185103 -16.690944) (xy 31.237436 -16.760654) (xy 31.283092 -16.834908)
			(xy 31.32168 -16.913069) (xy 31.352869 -16.994466) (xy 31.376391 -17.0784) (xy 31.392043 -17.16415)
			(xy 31.399692 -17.250981) (xy 31.399272 -17.338148) (xy 31.390786 -17.424901) (xy 31.374308 -17.510497)
			(xy 31.349978 -17.5942) (xy 31.318006 -17.675292) (xy 31.278666 -17.753077) (xy 31.232296 -17.826888)
			(xy 31.206186 -17.861788) (xy 31.193319 -17.879322) (xy 31.173143 -17.917845) (xy 31.159821 -17.959242)
			(xy 31.153744 -18.002302) (xy 31.155088 -18.045769) (xy 31.163814 -18.088372) (xy 31.179668 -18.128866)
			(xy 31.202186 -18.166069) (xy 31.230711 -18.198895) (xy 31.264409 -18.226383) (xy 31.302296 -18.247731)
			(xy 31.343264 -18.262316) (xy 31.386118 -18.269711) (xy 31.407862 -18.27022) (xy 34.591498 -18.27022)
			(xy 34.613244 -18.269774) (xy 34.656101 -18.26237) (xy 34.697071 -18.247776) (xy 34.734958 -18.22642)
			(xy 34.768656 -18.198925) (xy 34.797181 -18.166094) (xy 34.819699 -18.128886) (xy 34.835553 -18.088387)
			(xy 34.84428 -18.04578) (xy 34.845626 -18.002309) (xy 34.83955 -17.959244) (xy 34.826231 -17.917842)
			(xy 34.806057 -17.879312) (xy 34.793174 -17.861788) (xy 34.767447 -17.827418) (xy 34.721667 -17.754782)
			(xy 34.682699 -17.678276) (xy 34.650869 -17.598535) (xy 34.626441 -17.516224) (xy 34.609619 -17.43203)
			(xy 34.600543 -17.346652) (xy 34.599289 -17.260802) (xy 34.605867 -17.175195) (xy 34.620222 -17.090545)
			(xy 34.642236 -17.007556) (xy 34.671723 -16.926919) (xy 34.70844 -16.849307) (xy 34.752079 -16.775366)
			(xy 34.802278 -16.705711) (xy 34.858619 -16.640922) (xy 34.920631 -16.58154) (xy 34.987799 -16.52806)
			(xy 35.059563 -16.480925) (xy 35.135326 -16.44053) (xy 35.214456 -16.40721) (xy 35.296294 -16.381243)
			(xy 35.380159 -16.362845) (xy 35.465351 -16.35217) (xy 35.551162 -16.349307) (xy 35.636877 -16.354279)
			(xy 35.721782 -16.367044) (xy 35.805169 -16.387498) (xy 35.886344 -16.415468) (xy 35.964631 -16.450723)
			(xy 36.039378 -16.492968) (xy 36.109962 -16.541853) (xy 36.175795 -16.596968) (xy 36.23633 -16.657856)
			(xy 36.29106 -16.72401) (xy 36.339532 -16.794878) (xy 36.381341 -16.86987) (xy 36.416139 -16.948361)
			(xy 36.443636 -17.029698) (xy 36.45408 -17.07134) (xy 36.462462 -17.106138) (xy 36.487862 -17.131538)
			(xy 36.49997 -17.142996) (xy 36.528805 -17.159706) (xy 36.560988 -17.168357) (xy 36.594314 -17.168357)
			(xy 36.626497 -17.159706) (xy 36.655332 -17.142996) (xy 36.66744 -17.131538) (xy 36.750752 -17.04848)
			(xy 36.750752 -6.268466) (xy 35.961574 -5.479542) (xy 35.889946 -5.463286) (xy 35.855402 -5.475732)
			(xy 35.81472 -5.489721) (xy 35.731379 -5.511082) (xy 35.646436 -5.524741) (xy 35.5606 -5.530583)
			(xy 35.474589 -5.528559) (xy 35.389123 -5.518687) (xy 35.304916 -5.501049) (xy 35.222672 -5.475791)
			(xy 35.143079 -5.443127) (xy 35.066804 -5.403328) (xy 34.994482 -5.356727) (xy 34.926721 -5.303715)
			(xy 34.864085 -5.244735) (xy 34.807099 -5.180279) (xy 34.75624 -5.110887) (xy 34.711932 -5.037139)
			(xy 34.674546 -4.959651) (xy 34.644396 -4.879073) (xy 34.621732 -4.796077) (xy 34.606745 -4.711358)
			(xy 34.599559 -4.625624) (xy 34.600236 -4.539592) (xy 34.608769 -4.453982) (xy 34.625087 -4.369509)
			(xy 34.649053 -4.28688) (xy 34.680468 -4.206785) (xy 34.719068 -4.129896) (xy 34.76453 -4.056854)
			(xy 34.816475 -3.98827) (xy 34.874468 -3.924719) (xy 34.938023 -3.866731) (xy 35.006611 -3.814791)
			(xy 35.079656 -3.769334) (xy 35.156548 -3.73074) (xy 35.236645 -3.699331) (xy 35.319276 -3.675371)
			(xy 35.40375 -3.659059) (xy 35.489361 -3.650532) (xy 35.575393 -3.649862) (xy 35.661126 -3.657054)
			(xy 35.745844 -3.672047) (xy 35.828839 -3.694717) (xy 35.909415 -3.724873) (xy 35.986899 -3.762265)
			(xy 36.060644 -3.806578) (xy 36.130033 -3.857442) (xy 36.194484 -3.914433) (xy 36.25346 -3.977073)
			(xy 36.306467 -4.044839) (xy 36.353063 -4.117163) (xy 36.392856 -4.193442) (xy 36.425515 -4.273037)
			(xy 36.450766 -4.355283) (xy 36.468398 -4.439491) (xy 36.478264 -4.524958) (xy 36.480282 -4.610969)
			(xy 36.474433 -4.696804) (xy 36.460768 -4.781747) (xy 36.439401 -4.865086) (xy 36.425378 -4.905756)
			(xy 36.419968 -4.922856) (xy 36.417857 -4.958645) (xy 36.425771 -4.993611) (xy 36.443088 -5.025002)
			(xy 36.45535 -5.03809) (xy 37.41166 -5.994654) (xy 37.41166 -6.881047) (xy 39.818567 -6.881047) (xy 39.824576 -6.765126)
			(xy 39.838567 -6.649897) (xy 39.860475 -6.535907) (xy 39.890195 -6.4237) (xy 39.927585 -6.313811)
			(xy 39.972468 -6.206764) (xy 40.024629 -6.103068) (xy 40.08382 -6.003218) (xy 40.149759 -5.907689)
			(xy 40.222131 -5.816938) (xy 40.300592 -5.731395) (xy 40.384767 -5.651469) (xy 40.474256 -5.577542)
			(xy 40.568632 -5.509964) (xy 40.667446 -5.449058) (xy 40.770226 -5.395115) (xy 40.876483 -5.348391)
			(xy 40.98571 -5.30911) (xy 41.097387 -5.277458) (xy 41.210982 -5.253585) (xy 41.325953 -5.237607)
			(xy 41.441752 -5.229599) (xy 41.49979 -5.229098) (xy 41.557828 -5.229599) (xy 41.673627 -5.237607)
			(xy 41.788598 -5.253585) (xy 41.902193 -5.277458) (xy 42.01387 -5.30911) (xy 42.123097 -5.348391)
			(xy 42.229354 -5.395115) (xy 42.332134 -5.449058) (xy 42.430948 -5.509964) (xy 42.474432 -5.541101)
			(xy 63.647829 -5.541101) (xy 63.653878 -5.465531) (xy 63.667925 -5.391033) (xy 63.689811 -5.31845)
			(xy 63.719288 -5.248604) (xy 63.756023 -5.182287) (xy 63.799598 -5.120251) (xy 63.84952 -5.063198)
			(xy 63.905224 -5.011774) (xy 63.966079 -4.966563) (xy 64.031394 -4.928076) (xy 64.10043 -4.89675)
			(xy 64.172405 -4.87294) (xy 64.246503 -4.856915) (xy 64.321884 -4.848856) (xy 64.35979 -4.848352)
			(xy 64.397696 -4.848856) (xy 64.473077 -4.856915) (xy 64.547175 -4.87294) (xy 64.61915 -4.89675)
			(xy 64.688186 -4.928076) (xy 64.753501 -4.966563) (xy 64.814356 -5.011774) (xy 64.87006 -5.063198)
			(xy 64.919982 -5.120251) (xy 64.963557 -5.182287) (xy 65.000292 -5.248604) (xy 65.029769 -5.31845)
			(xy 65.051655 -5.391033) (xy 65.065702 -5.465531) (xy 65.071751 -5.541101) (xy 66.187829 -5.541101)
			(xy 66.193878 -5.465531) (xy 66.207925 -5.391033) (xy 66.229811 -5.31845) (xy 66.259288 -5.248604)
			(xy 66.296023 -5.182287) (xy 66.339598 -5.120251) (xy 66.38952 -5.063198) (xy 66.445224 -5.011774)
			(xy 66.506079 -4.966563) (xy 66.571394 -4.928076) (xy 66.64043 -4.89675) (xy 66.712405 -4.87294)
			(xy 66.786503 -4.856915) (xy 66.861884 -4.848856) (xy 66.89979 -4.848352) (xy 66.937696 -4.848856)
			(xy 67.013077 -4.856915) (xy 67.087175 -4.87294) (xy 67.15915 -4.89675) (xy 67.228186 -4.928076)
			(xy 67.293501 -4.966563) (xy 67.354356 -5.011774) (xy 67.41006 -5.063198) (xy 67.459982 -5.120251)
			(xy 67.503557 -5.182287) (xy 67.540292 -5.248604) (xy 67.569769 -5.31845) (xy 67.591655 -5.391033)
			(xy 67.605702 -5.465531) (xy 67.611751 -5.541101) (xy 68.727829 -5.541101) (xy 68.733878 -5.465531)
			(xy 68.747925 -5.391033) (xy 68.769811 -5.31845) (xy 68.799288 -5.248604) (xy 68.836023 -5.182287)
			(xy 68.879598 -5.120251) (xy 68.92952 -5.063198) (xy 68.985224 -5.011774) (xy 69.046079 -4.966563)
			(xy 69.111394 -4.928076) (xy 69.18043 -4.89675) (xy 69.252405 -4.87294) (xy 69.326503 -4.856915)
			(xy 69.401884 -4.848856) (xy 69.43979 -4.848352) (xy 69.477696 -4.848856) (xy 69.553077 -4.856915)
			(xy 69.627175 -4.87294) (xy 69.69915 -4.89675) (xy 69.768186 -4.928076) (xy 69.833501 -4.966563)
			(xy 69.894356 -5.011774) (xy 69.95006 -5.063198) (xy 69.999982 -5.120251) (xy 70.043557 -5.182287)
			(xy 70.080292 -5.248604) (xy 70.109769 -5.31845) (xy 70.131655 -5.391033) (xy 70.145702 -5.465531)
			(xy 70.151751 -5.541101) (xy 71.267829 -5.541101) (xy 71.273878 -5.465531) (xy 71.287925 -5.391033)
			(xy 71.309811 -5.31845) (xy 71.339288 -5.248604) (xy 71.376023 -5.182287) (xy 71.419598 -5.120251)
			(xy 71.46952 -5.063198) (xy 71.525224 -5.011774) (xy 71.586079 -4.966563) (xy 71.651394 -4.928076)
			(xy 71.72043 -4.89675) (xy 71.792405 -4.87294) (xy 71.866503 -4.856915) (xy 71.941884 -4.848856)
			(xy 71.97979 -4.848352) (xy 72.017696 -4.848856) (xy 72.093077 -4.856915) (xy 72.167175 -4.87294)
			(xy 72.23915 -4.89675) (xy 72.308186 -4.928076) (xy 72.373501 -4.966563) (xy 72.434356 -5.011774)
			(xy 72.49006 -5.063198) (xy 72.539982 -5.120251) (xy 72.583557 -5.182287) (xy 72.620292 -5.248604)
			(xy 72.649769 -5.31845) (xy 72.671655 -5.391033) (xy 72.685702 -5.465531) (xy 72.691751 -5.541101)
			(xy 73.807829 -5.541101) (xy 73.813878 -5.465531) (xy 73.827925 -5.391033) (xy 73.849811 -5.31845)
			(xy 73.879288 -5.248604) (xy 73.916023 -5.182287) (xy 73.959598 -5.120251) (xy 74.00952 -5.063198)
			(xy 74.065224 -5.011774) (xy 74.126079 -4.966563) (xy 74.191394 -4.928076) (xy 74.26043 -4.89675)
			(xy 74.332405 -4.87294) (xy 74.406503 -4.856915) (xy 74.481884 -4.848856) (xy 74.51979 -4.848352)
			(xy 74.557696 -4.848856) (xy 74.633077 -4.856915) (xy 74.707175 -4.87294) (xy 74.77915 -4.89675)
			(xy 74.848186 -4.928076) (xy 74.913501 -4.966563) (xy 74.974356 -5.011774) (xy 75.03006 -5.063198)
			(xy 75.079982 -5.120251) (xy 75.123557 -5.182287) (xy 75.160292 -5.248604) (xy 75.189769 -5.31845)
			(xy 75.211655 -5.391033) (xy 75.225702 -5.465531) (xy 75.231751 -5.541101) (xy 76.347829 -5.541101)
			(xy 76.353878 -5.465531) (xy 76.367925 -5.391033) (xy 76.389811 -5.31845) (xy 76.419288 -5.248604)
			(xy 76.456023 -5.182287) (xy 76.499598 -5.120251) (xy 76.54952 -5.063198) (xy 76.605224 -5.011774)
			(xy 76.666079 -4.966563) (xy 76.731394 -4.928076) (xy 76.80043 -4.89675) (xy 76.872405 -4.87294)
			(xy 76.946503 -4.856915) (xy 77.021884 -4.848856) (xy 77.05979 -4.848352) (xy 77.097696 -4.848856)
			(xy 77.173077 -4.856915) (xy 77.247175 -4.87294) (xy 77.31915 -4.89675) (xy 77.388186 -4.928076)
			(xy 77.453501 -4.966563) (xy 77.514356 -5.011774) (xy 77.57006 -5.063198) (xy 77.619982 -5.120251)
			(xy 77.663557 -5.182287) (xy 77.700292 -5.248604) (xy 77.729769 -5.31845) (xy 77.751655 -5.391033)
			(xy 77.765702 -5.465531) (xy 77.771751 -5.541101) (xy 78.887829 -5.541101) (xy 78.893878 -5.465531)
			(xy 78.907925 -5.391033) (xy 78.929811 -5.31845) (xy 78.959288 -5.248604) (xy 78.996023 -5.182287)
			(xy 79.039598 -5.120251) (xy 79.08952 -5.063198) (xy 79.145224 -5.011774) (xy 79.206079 -4.966563)
			(xy 79.271394 -4.928076) (xy 79.34043 -4.89675) (xy 79.412405 -4.87294) (xy 79.486503 -4.856915)
			(xy 79.561884 -4.848856) (xy 79.59979 -4.848352) (xy 79.637696 -4.848856) (xy 79.713077 -4.856915)
			(xy 79.787175 -4.87294) (xy 79.85915 -4.89675) (xy 79.928186 -4.928076) (xy 79.993501 -4.966563)
			(xy 80.054356 -5.011774) (xy 80.11006 -5.063198) (xy 80.159982 -5.120251) (xy 80.203557 -5.182287)
			(xy 80.240292 -5.248604) (xy 80.269769 -5.31845) (xy 80.291655 -5.391033) (xy 80.305702 -5.465531)
			(xy 80.311751 -5.541101) (xy 81.427829 -5.541101) (xy 81.433878 -5.465531) (xy 81.447925 -5.391033)
			(xy 81.469811 -5.31845) (xy 81.499288 -5.248604) (xy 81.536023 -5.182287) (xy 81.579598 -5.120251)
			(xy 81.62952 -5.063198) (xy 81.685224 -5.011774) (xy 81.746079 -4.966563) (xy 81.811394 -4.928076)
			(xy 81.88043 -4.89675) (xy 81.952405 -4.87294) (xy 82.026503 -4.856915) (xy 82.101884 -4.848856)
			(xy 82.13979 -4.848352) (xy 82.177696 -4.848856) (xy 82.253077 -4.856915) (xy 82.327175 -4.87294)
			(xy 82.39915 -4.89675) (xy 82.468186 -4.928076) (xy 82.533501 -4.966563) (xy 82.559813 -4.986111)
			(xy 86.197949 -4.986111) (xy 86.203998 -4.910541) (xy 86.218045 -4.836043) (xy 86.239931 -4.76346)
			(xy 86.269408 -4.693614) (xy 86.306143 -4.627297) (xy 86.349718 -4.565261) (xy 86.39964 -4.508208)
			(xy 86.455344 -4.456784) (xy 86.516199 -4.411573) (xy 86.581514 -4.373086) (xy 86.65055 -4.34176)
			(xy 86.722525 -4.31795) (xy 86.796623 -4.301925) (xy 86.872004 -4.293866) (xy 86.90991 -4.293362)
			(xy 86.947816 -4.293866) (xy 87.023197 -4.301925) (xy 87.097295 -4.31795) (xy 87.16927 -4.34176)
			(xy 87.238306 -4.373086) (xy 87.303621 -4.411573) (xy 87.364476 -4.456784) (xy 87.42018 -4.508208)
			(xy 87.470102 -4.565261) (xy 87.513677 -4.627297) (xy 87.550412 -4.693614) (xy 87.579889 -4.76346)
			(xy 87.601775 -4.836043) (xy 87.615822 -4.910541) (xy 87.621871 -4.986111) (xy 88.737949 -4.986111)
			(xy 88.743998 -4.910541) (xy 88.758045 -4.836043) (xy 88.779931 -4.76346) (xy 88.809408 -4.693614)
			(xy 88.846143 -4.627297) (xy 88.889718 -4.565261) (xy 88.93964 -4.508208) (xy 88.995344 -4.456784)
			(xy 89.056199 -4.411573) (xy 89.121514 -4.373086) (xy 89.19055 -4.34176) (xy 89.262525 -4.31795)
			(xy 89.336623 -4.301925) (xy 89.412004 -4.293866) (xy 89.44991 -4.293362) (xy 89.487816 -4.293866)
			(xy 89.563197 -4.301925) (xy 89.637295 -4.31795) (xy 89.70927 -4.34176) (xy 89.778306 -4.373086)
			(xy 89.843621 -4.411573) (xy 89.904476 -4.456784) (xy 89.96018 -4.508208) (xy 90.010102 -4.565261)
			(xy 90.053677 -4.627297) (xy 90.090412 -4.693614) (xy 90.119889 -4.76346) (xy 90.141775 -4.836043)
			(xy 90.155822 -4.910541) (xy 90.161871 -4.986111) (xy 91.277949 -4.986111) (xy 91.283998 -4.910541)
			(xy 91.298045 -4.836043) (xy 91.319931 -4.76346) (xy 91.349408 -4.693614) (xy 91.386143 -4.627297)
			(xy 91.429718 -4.565261) (xy 91.47964 -4.508208) (xy 91.535344 -4.456784) (xy 91.596199 -4.411573)
			(xy 91.661514 -4.373086) (xy 91.73055 -4.34176) (xy 91.802525 -4.31795) (xy 91.876623 -4.301925)
			(xy 91.952004 -4.293866) (xy 91.98991 -4.293362) (xy 92.027816 -4.293866) (xy 92.103197 -4.301925)
			(xy 92.177295 -4.31795) (xy 92.24927 -4.34176) (xy 92.318306 -4.373086) (xy 92.383621 -4.411573)
			(xy 92.444476 -4.456784) (xy 92.50018 -4.508208) (xy 92.550102 -4.565261) (xy 92.593677 -4.627297)
			(xy 92.630412 -4.693614) (xy 92.659889 -4.76346) (xy 92.681775 -4.836043) (xy 92.695822 -4.910541)
			(xy 92.701871 -4.986111) (xy 92.699852 -5.061895) (xy 92.68979 -5.137035) (xy 92.671798 -5.21068)
			(xy 92.64608 -5.281996) (xy 92.612928 -5.350173) (xy 92.572716 -5.414441) (xy 92.525901 -5.47407)
			(xy 92.473013 -5.528386) (xy 92.414651 -5.576772) (xy 92.351476 -5.61868) (xy 92.284205 -5.653636)
			(xy 92.2136 -5.681243) (xy 92.140459 -5.701189) (xy 92.065614 -5.713248) (xy 91.98991 -5.717283)
			(xy 91.914206 -5.713248) (xy 91.839361 -5.701189) (xy 91.76622 -5.681243) (xy 91.695615 -5.653636)
			(xy 91.628344 -5.61868) (xy 91.565169 -5.576772) (xy 91.506807 -5.528386) (xy 91.453919 -5.47407)
			(xy 91.407104 -5.414441) (xy 91.366892 -5.350173) (xy 91.33374 -5.281996) (xy 91.308022 -5.21068)
			(xy 91.29003 -5.137035) (xy 91.279968 -5.061895) (xy 91.277949 -4.986111) (xy 90.161871 -4.986111)
			(xy 90.159852 -5.061895) (xy 90.14979 -5.137035) (xy 90.131798 -5.21068) (xy 90.10608 -5.281996)
			(xy 90.072928 -5.350173) (xy 90.032716 -5.414441) (xy 89.985901 -5.47407) (xy 89.933013 -5.528386)
			(xy 89.874651 -5.576772) (xy 89.811476 -5.61868) (xy 89.744205 -5.653636) (xy 89.6736 -5.681243)
			(xy 89.600459 -5.701189) (xy 89.525614 -5.713248) (xy 89.44991 -5.717283) (xy 89.374206 -5.713248)
			(xy 89.299361 -5.701189) (xy 89.22622 -5.681243) (xy 89.155615 -5.653636) (xy 89.088344 -5.61868)
			(xy 89.025169 -5.576772) (xy 88.966807 -5.528386) (xy 88.913919 -5.47407) (xy 88.867104 -5.414441)
			(xy 88.826892 -5.350173) (xy 88.79374 -5.281996) (xy 88.768022 -5.21068) (xy 88.75003 -5.137035)
			(xy 88.739968 -5.061895) (xy 88.737949 -4.986111) (xy 87.621871 -4.986111) (xy 87.619852 -5.061895)
			(xy 87.60979 -5.137035) (xy 87.591798 -5.21068) (xy 87.56608 -5.281996) (xy 87.532928 -5.350173)
			(xy 87.492716 -5.414441) (xy 87.445901 -5.47407) (xy 87.393013 -5.528386) (xy 87.334651 -5.576772)
			(xy 87.271476 -5.61868) (xy 87.204205 -5.653636) (xy 87.1336 -5.681243) (xy 87.060459 -5.701189)
			(xy 86.985614 -5.713248) (xy 86.90991 -5.717283) (xy 86.834206 -5.713248) (xy 86.759361 -5.701189)
			(xy 86.68622 -5.681243) (xy 86.615615 -5.653636) (xy 86.548344 -5.61868) (xy 86.485169 -5.576772)
			(xy 86.426807 -5.528386) (xy 86.373919 -5.47407) (xy 86.327104 -5.414441) (xy 86.286892 -5.350173)
			(xy 86.25374 -5.281996) (xy 86.228022 -5.21068) (xy 86.21003 -5.137035) (xy 86.199968 -5.061895)
			(xy 86.197949 -4.986111) (xy 82.559813 -4.986111) (xy 82.594356 -5.011774) (xy 82.65006 -5.063198)
			(xy 82.699982 -5.120251) (xy 82.743557 -5.182287) (xy 82.780292 -5.248604) (xy 82.809769 -5.31845)
			(xy 82.831655 -5.391033) (xy 82.845702 -5.465531) (xy 82.851751 -5.541101) (xy 82.849732 -5.616885)
			(xy 82.83967 -5.692025) (xy 82.821678 -5.76567) (xy 82.79596 -5.836986) (xy 82.762808 -5.905163)
			(xy 82.722596 -5.969431) (xy 82.675781 -6.02906) (xy 82.622893 -6.083376) (xy 82.564531 -6.131762)
			(xy 82.501356 -6.17367) (xy 82.434085 -6.208626) (xy 82.36348 -6.236233) (xy 82.290588 -6.256111)
			(xy 84.927949 -6.256111) (xy 84.933998 -6.180541) (xy 84.948045 -6.106043) (xy 84.969931 -6.03346)
			(xy 84.999408 -5.963614) (xy 85.036143 -5.897297) (xy 85.079718 -5.835261) (xy 85.12964 -5.778208)
			(xy 85.185344 -5.726784) (xy 85.246199 -5.681573) (xy 85.311514 -5.643086) (xy 85.38055 -5.61176)
			(xy 85.452525 -5.58795) (xy 85.526623 -5.571925) (xy 85.602004 -5.563866) (xy 85.63991 -5.563362)
			(xy 85.677816 -5.563866) (xy 85.753197 -5.571925) (xy 85.827295 -5.58795) (xy 85.89927 -5.61176)
			(xy 85.968306 -5.643086) (xy 86.033621 -5.681573) (xy 86.094476 -5.726784) (xy 86.15018 -5.778208)
			(xy 86.200102 -5.835261) (xy 86.243677 -5.897297) (xy 86.280412 -5.963614) (xy 86.309889 -6.03346)
			(xy 86.331775 -6.106043) (xy 86.345822 -6.180541) (xy 86.351871 -6.256111) (xy 87.467949 -6.256111)
			(xy 87.473998 -6.180541) (xy 87.488045 -6.106043) (xy 87.509931 -6.03346) (xy 87.539408 -5.963614)
			(xy 87.576143 -5.897297) (xy 87.619718 -5.835261) (xy 87.66964 -5.778208) (xy 87.725344 -5.726784)
			(xy 87.786199 -5.681573) (xy 87.851514 -5.643086) (xy 87.92055 -5.61176) (xy 87.992525 -5.58795)
			(xy 88.066623 -5.571925) (xy 88.142004 -5.563866) (xy 88.17991 -5.563362) (xy 88.217816 -5.563866)
			(xy 88.293197 -5.571925) (xy 88.367295 -5.58795) (xy 88.43927 -5.61176) (xy 88.508306 -5.643086)
			(xy 88.573621 -5.681573) (xy 88.634476 -5.726784) (xy 88.69018 -5.778208) (xy 88.740102 -5.835261)
			(xy 88.783677 -5.897297) (xy 88.820412 -5.963614) (xy 88.849889 -6.03346) (xy 88.871775 -6.106043)
			(xy 88.885822 -6.180541) (xy 88.891871 -6.256111) (xy 90.007949 -6.256111) (xy 90.013998 -6.180541)
			(xy 90.028045 -6.106043) (xy 90.049931 -6.03346) (xy 90.079408 -5.963614) (xy 90.116143 -5.897297)
			(xy 90.159718 -5.835261) (xy 90.20964 -5.778208) (xy 90.265344 -5.726784) (xy 90.326199 -5.681573)
			(xy 90.391514 -5.643086) (xy 90.46055 -5.61176) (xy 90.532525 -5.58795) (xy 90.606623 -5.571925)
			(xy 90.682004 -5.563866) (xy 90.71991 -5.563362) (xy 90.757816 -5.563866) (xy 90.833197 -5.571925)
			(xy 90.907295 -5.58795) (xy 90.97927 -5.61176) (xy 91.048306 -5.643086) (xy 91.113621 -5.681573)
			(xy 91.174476 -5.726784) (xy 91.23018 -5.778208) (xy 91.280102 -5.835261) (xy 91.323677 -5.897297)
			(xy 91.360412 -5.963614) (xy 91.389889 -6.03346) (xy 91.411775 -6.106043) (xy 91.425822 -6.180541)
			(xy 91.431871 -6.256111) (xy 91.429852 -6.331895) (xy 91.41979 -6.407035) (xy 91.401798 -6.48068)
			(xy 91.37608 -6.551996) (xy 91.342928 -6.620173) (xy 91.302716 -6.684441) (xy 91.255901 -6.74407)
			(xy 91.203013 -6.798386) (xy 91.144651 -6.846772) (xy 91.081476 -6.88868) (xy 91.014205 -6.923636)
			(xy 90.9436 -6.951243) (xy 90.870459 -6.971189) (xy 90.795614 -6.983248) (xy 90.71991 -6.987283)
			(xy 90.644206 -6.983248) (xy 90.569361 -6.971189) (xy 90.49622 -6.951243) (xy 90.425615 -6.923636)
			(xy 90.358344 -6.88868) (xy 90.295169 -6.846772) (xy 90.236807 -6.798386) (xy 90.183919 -6.74407)
			(xy 90.137104 -6.684441) (xy 90.096892 -6.620173) (xy 90.06374 -6.551996) (xy 90.038022 -6.48068)
			(xy 90.02003 -6.407035) (xy 90.009968 -6.331895) (xy 90.007949 -6.256111) (xy 88.891871 -6.256111)
			(xy 88.889852 -6.331895) (xy 88.87979 -6.407035) (xy 88.861798 -6.48068) (xy 88.83608 -6.551996)
			(xy 88.802928 -6.620173) (xy 88.762716 -6.684441) (xy 88.715901 -6.74407) (xy 88.663013 -6.798386)
			(xy 88.604651 -6.846772) (xy 88.541476 -6.88868) (xy 88.474205 -6.923636) (xy 88.4036 -6.951243)
			(xy 88.330459 -6.971189) (xy 88.255614 -6.983248) (xy 88.17991 -6.987283) (xy 88.104206 -6.983248)
			(xy 88.029361 -6.971189) (xy 87.95622 -6.951243) (xy 87.885615 -6.923636) (xy 87.818344 -6.88868)
			(xy 87.755169 -6.846772) (xy 87.696807 -6.798386) (xy 87.643919 -6.74407) (xy 87.597104 -6.684441)
			(xy 87.556892 -6.620173) (xy 87.52374 -6.551996) (xy 87.498022 -6.48068) (xy 87.48003 -6.407035)
			(xy 87.469968 -6.331895) (xy 87.467949 -6.256111) (xy 86.351871 -6.256111) (xy 86.349852 -6.331895)
			(xy 86.33979 -6.407035) (xy 86.321798 -6.48068) (xy 86.29608 -6.551996) (xy 86.262928 -6.620173)
			(xy 86.222716 -6.684441) (xy 86.175901 -6.74407) (xy 86.123013 -6.798386) (xy 86.064651 -6.846772)
			(xy 86.001476 -6.88868) (xy 85.934205 -6.923636) (xy 85.8636 -6.951243) (xy 85.790459 -6.971189)
			(xy 85.715614 -6.983248) (xy 85.63991 -6.987283) (xy 85.564206 -6.983248) (xy 85.489361 -6.971189)
			(xy 85.41622 -6.951243) (xy 85.345615 -6.923636) (xy 85.278344 -6.88868) (xy 85.215169 -6.846772)
			(xy 85.156807 -6.798386) (xy 85.103919 -6.74407) (xy 85.057104 -6.684441) (xy 85.016892 -6.620173)
			(xy 84.98374 -6.551996) (xy 84.958022 -6.48068) (xy 84.94003 -6.407035) (xy 84.929968 -6.331895)
			(xy 84.927949 -6.256111) (xy 82.290588 -6.256111) (xy 82.290339 -6.256179) (xy 82.215494 -6.268238)
			(xy 82.13979 -6.272273) (xy 82.064086 -6.268238) (xy 81.989241 -6.256179) (xy 81.9161 -6.236233)
			(xy 81.845495 -6.208626) (xy 81.778224 -6.17367) (xy 81.715049 -6.131762) (xy 81.656687 -6.083376)
			(xy 81.603799 -6.02906) (xy 81.556984 -5.969431) (xy 81.516772 -5.905163) (xy 81.48362 -5.836986)
			(xy 81.457902 -5.76567) (xy 81.43991 -5.692025) (xy 81.429848 -5.616885) (xy 81.427829 -5.541101)
			(xy 80.311751 -5.541101) (xy 80.309732 -5.616885) (xy 80.29967 -5.692025) (xy 80.281678 -5.76567)
			(xy 80.25596 -5.836986) (xy 80.222808 -5.905163) (xy 80.182596 -5.969431) (xy 80.135781 -6.02906)
			(xy 80.082893 -6.083376) (xy 80.024531 -6.131762) (xy 79.961356 -6.17367) (xy 79.894085 -6.208626)
			(xy 79.82348 -6.236233) (xy 79.750339 -6.256179) (xy 79.675494 -6.268238) (xy 79.59979 -6.272273)
			(xy 79.524086 -6.268238) (xy 79.449241 -6.256179) (xy 79.3761 -6.236233) (xy 79.305495 -6.208626)
			(xy 79.238224 -6.17367) (xy 79.175049 -6.131762) (xy 79.116687 -6.083376) (xy 79.063799 -6.02906)
			(xy 79.016984 -5.969431) (xy 78.976772 -5.905163) (xy 78.94362 -5.836986) (xy 78.917902 -5.76567)
			(xy 78.89991 -5.692025) (xy 78.889848 -5.616885) (xy 78.887829 -5.541101) (xy 77.771751 -5.541101)
			(xy 77.769732 -5.616885) (xy 77.75967 -5.692025) (xy 77.741678 -5.76567) (xy 77.71596 -5.836986)
			(xy 77.682808 -5.905163) (xy 77.642596 -5.969431) (xy 77.595781 -6.02906) (xy 77.542893 -6.083376)
			(xy 77.484531 -6.131762) (xy 77.421356 -6.17367) (xy 77.354085 -6.208626) (xy 77.28348 -6.236233)
			(xy 77.210339 -6.256179) (xy 77.135494 -6.268238) (xy 77.05979 -6.272273) (xy 76.984086 -6.268238)
			(xy 76.909241 -6.256179) (xy 76.8361 -6.236233) (xy 76.765495 -6.208626) (xy 76.698224 -6.17367)
			(xy 76.635049 -6.131762) (xy 76.576687 -6.083376) (xy 76.523799 -6.02906) (xy 76.476984 -5.969431)
			(xy 76.436772 -5.905163) (xy 76.40362 -5.836986) (xy 76.377902 -5.76567) (xy 76.35991 -5.692025)
			(xy 76.349848 -5.616885) (xy 76.347829 -5.541101) (xy 75.231751 -5.541101) (xy 75.229732 -5.616885)
			(xy 75.21967 -5.692025) (xy 75.201678 -5.76567) (xy 75.17596 -5.836986) (xy 75.142808 -5.905163)
			(xy 75.102596 -5.969431) (xy 75.055781 -6.02906) (xy 75.002893 -6.083376) (xy 74.944531 -6.131762)
			(xy 74.881356 -6.17367) (xy 74.814085 -6.208626) (xy 74.74348 -6.236233) (xy 74.670339 -6.256179)
			(xy 74.595494 -6.268238) (xy 74.51979 -6.272273) (xy 74.444086 -6.268238) (xy 74.369241 -6.256179)
			(xy 74.2961 -6.236233) (xy 74.225495 -6.208626) (xy 74.158224 -6.17367) (xy 74.095049 -6.131762)
			(xy 74.036687 -6.083376) (xy 73.983799 -6.02906) (xy 73.936984 -5.969431) (xy 73.896772 -5.905163)
			(xy 73.86362 -5.836986) (xy 73.837902 -5.76567) (xy 73.81991 -5.692025) (xy 73.809848 -5.616885)
			(xy 73.807829 -5.541101) (xy 72.691751 -5.541101) (xy 72.689732 -5.616885) (xy 72.67967 -5.692025)
			(xy 72.661678 -5.76567) (xy 72.63596 -5.836986) (xy 72.602808 -5.905163) (xy 72.562596 -5.969431)
			(xy 72.515781 -6.02906) (xy 72.462893 -6.083376) (xy 72.404531 -6.131762) (xy 72.341356 -6.17367)
			(xy 72.274085 -6.208626) (xy 72.20348 -6.236233) (xy 72.130339 -6.256179) (xy 72.055494 -6.268238)
			(xy 71.97979 -6.272273) (xy 71.904086 -6.268238) (xy 71.829241 -6.256179) (xy 71.7561 -6.236233)
			(xy 71.685495 -6.208626) (xy 71.618224 -6.17367) (xy 71.555049 -6.131762) (xy 71.496687 -6.083376)
			(xy 71.443799 -6.02906) (xy 71.396984 -5.969431) (xy 71.356772 -5.905163) (xy 71.32362 -5.836986)
			(xy 71.297902 -5.76567) (xy 71.27991 -5.692025) (xy 71.269848 -5.616885) (xy 71.267829 -5.541101)
			(xy 70.151751 -5.541101) (xy 70.149732 -5.616885) (xy 70.13967 -5.692025) (xy 70.121678 -5.76567)
			(xy 70.09596 -5.836986) (xy 70.062808 -5.905163) (xy 70.022596 -5.969431) (xy 69.975781 -6.02906)
			(xy 69.922893 -6.083376) (xy 69.864531 -6.131762) (xy 69.801356 -6.17367) (xy 69.734085 -6.208626)
			(xy 69.66348 -6.236233) (xy 69.590339 -6.256179) (xy 69.515494 -6.268238) (xy 69.43979 -6.272273)
			(xy 69.364086 -6.268238) (xy 69.289241 -6.256179) (xy 69.2161 -6.236233) (xy 69.145495 -6.208626)
			(xy 69.078224 -6.17367) (xy 69.015049 -6.131762) (xy 68.956687 -6.083376) (xy 68.903799 -6.02906)
			(xy 68.856984 -5.969431) (xy 68.816772 -5.905163) (xy 68.78362 -5.836986) (xy 68.757902 -5.76567)
			(xy 68.73991 -5.692025) (xy 68.729848 -5.616885) (xy 68.727829 -5.541101) (xy 67.611751 -5.541101)
			(xy 67.609732 -5.616885) (xy 67.59967 -5.692025) (xy 67.581678 -5.76567) (xy 67.55596 -5.836986)
			(xy 67.522808 -5.905163) (xy 67.482596 -5.969431) (xy 67.435781 -6.02906) (xy 67.382893 -6.083376)
			(xy 67.324531 -6.131762) (xy 67.261356 -6.17367) (xy 67.194085 -6.208626) (xy 67.12348 -6.236233)
			(xy 67.050339 -6.256179) (xy 66.975494 -6.268238) (xy 66.89979 -6.272273) (xy 66.824086 -6.268238)
			(xy 66.749241 -6.256179) (xy 66.6761 -6.236233) (xy 66.605495 -6.208626) (xy 66.538224 -6.17367)
			(xy 66.475049 -6.131762) (xy 66.416687 -6.083376) (xy 66.363799 -6.02906) (xy 66.316984 -5.969431)
			(xy 66.276772 -5.905163) (xy 66.24362 -5.836986) (xy 66.217902 -5.76567) (xy 66.19991 -5.692025)
			(xy 66.189848 -5.616885) (xy 66.187829 -5.541101) (xy 65.071751 -5.541101) (xy 65.069732 -5.616885)
			(xy 65.05967 -5.692025) (xy 65.041678 -5.76567) (xy 65.01596 -5.836986) (xy 64.982808 -5.905163)
			(xy 64.942596 -5.969431) (xy 64.895781 -6.02906) (xy 64.842893 -6.083376) (xy 64.784531 -6.131762)
			(xy 64.721356 -6.17367) (xy 64.654085 -6.208626) (xy 64.58348 -6.236233) (xy 64.510339 -6.256179)
			(xy 64.435494 -6.268238) (xy 64.35979 -6.272273) (xy 64.284086 -6.268238) (xy 64.209241 -6.256179)
			(xy 64.1361 -6.236233) (xy 64.065495 -6.208626) (xy 63.998224 -6.17367) (xy 63.935049 -6.131762)
			(xy 63.876687 -6.083376) (xy 63.823799 -6.02906) (xy 63.776984 -5.969431) (xy 63.736772 -5.905163)
			(xy 63.70362 -5.836986) (xy 63.677902 -5.76567) (xy 63.65991 -5.692025) (xy 63.649848 -5.616885)
			(xy 63.647829 -5.541101) (xy 42.474432 -5.541101) (xy 42.525324 -5.577542) (xy 42.614813 -5.651469)
			(xy 42.698988 -5.731395) (xy 42.777449 -5.816938) (xy 42.849821 -5.907689) (xy 42.91576 -6.003218)
			(xy 42.974951 -6.103068) (xy 43.027112 -6.206764) (xy 43.071995 -6.313811) (xy 43.109385 -6.4237)
			(xy 43.139105 -6.535907) (xy 43.161013 -6.649897) (xy 43.175004 -6.765126) (xy 43.181013 -6.881047)
			(xy 43.179009 -6.997105) (xy 43.169003 -7.112749) (xy 43.151043 -7.227427) (xy 43.125213 -7.340593)
			(xy 43.091638 -7.451707) (xy 43.06342 -7.526111) (xy 86.197949 -7.526111) (xy 86.203998 -7.450541)
			(xy 86.218045 -7.376043) (xy 86.239931 -7.30346) (xy 86.269408 -7.233614) (xy 86.306143 -7.167297)
			(xy 86.349718 -7.105261) (xy 86.39964 -7.048208) (xy 86.455344 -6.996784) (xy 86.516199 -6.951573)
			(xy 86.581514 -6.913086) (xy 86.65055 -6.88176) (xy 86.722525 -6.85795) (xy 86.796623 -6.841925)
			(xy 86.872004 -6.833866) (xy 86.90991 -6.833362) (xy 86.947816 -6.833866) (xy 87.023197 -6.841925)
			(xy 87.097295 -6.85795) (xy 87.16927 -6.88176) (xy 87.238306 -6.913086) (xy 87.303621 -6.951573)
			(xy 87.364476 -6.996784) (xy 87.42018 -7.048208) (xy 87.470102 -7.105261) (xy 87.513677 -7.167297)
			(xy 87.550412 -7.233614) (xy 87.579889 -7.30346) (xy 87.601775 -7.376043) (xy 87.615822 -7.450541)
			(xy 87.621871 -7.526111) (xy 88.737949 -7.526111) (xy 88.743998 -7.450541) (xy 88.758045 -7.376043)
			(xy 88.779931 -7.30346) (xy 88.809408 -7.233614) (xy 88.846143 -7.167297) (xy 88.889718 -7.105261)
			(xy 88.93964 -7.048208) (xy 88.995344 -6.996784) (xy 89.056199 -6.951573) (xy 89.121514 -6.913086)
			(xy 89.19055 -6.88176) (xy 89.262525 -6.85795) (xy 89.336623 -6.841925) (xy 89.412004 -6.833866)
			(xy 89.44991 -6.833362) (xy 89.487816 -6.833866) (xy 89.563197 -6.841925) (xy 89.637295 -6.85795)
			(xy 89.70927 -6.88176) (xy 89.778306 -6.913086) (xy 89.843621 -6.951573) (xy 89.904476 -6.996784)
			(xy 89.96018 -7.048208) (xy 90.010102 -7.105261) (xy 90.053677 -7.167297) (xy 90.090412 -7.233614)
			(xy 90.119889 -7.30346) (xy 90.141775 -7.376043) (xy 90.155822 -7.450541) (xy 90.161871 -7.526111)
			(xy 91.277949 -7.526111) (xy 91.283998 -7.450541) (xy 91.298045 -7.376043) (xy 91.319931 -7.30346)
			(xy 91.349408 -7.233614) (xy 91.386143 -7.167297) (xy 91.429718 -7.105261) (xy 91.47964 -7.048208)
			(xy 91.535344 -6.996784) (xy 91.596199 -6.951573) (xy 91.661514 -6.913086) (xy 91.73055 -6.88176)
			(xy 91.802525 -6.85795) (xy 91.876623 -6.841925) (xy 91.952004 -6.833866) (xy 91.98991 -6.833362)
			(xy 92.027816 -6.833866) (xy 92.103197 -6.841925) (xy 92.177295 -6.85795) (xy 92.24927 -6.88176)
			(xy 92.318306 -6.913086) (xy 92.383621 -6.951573) (xy 92.444476 -6.996784) (xy 92.50018 -7.048208)
			(xy 92.550102 -7.105261) (xy 92.593677 -7.167297) (xy 92.630412 -7.233614) (xy 92.659889 -7.30346)
			(xy 92.681775 -7.376043) (xy 92.695822 -7.450541) (xy 92.701871 -7.526111) (xy 92.699852 -7.601895)
			(xy 92.68979 -7.677035) (xy 92.671798 -7.75068) (xy 92.64608 -7.821996) (xy 92.612928 -7.890173)
			(xy 92.572716 -7.954441) (xy 92.525901 -8.01407) (xy 92.473013 -8.068386) (xy 92.414651 -8.116772)
			(xy 92.351476 -8.15868) (xy 92.284205 -8.193636) (xy 92.2136 -8.221243) (xy 92.177855 -8.230991)
			(xy 93.154757 -8.230991) (xy 93.160779 -8.114808) (xy 93.174802 -7.999317) (xy 93.19676 -7.885069)
			(xy 93.226547 -7.772608) (xy 93.264022 -7.66247) (xy 93.309007 -7.55518) (xy 93.361286 -7.451249)
			(xy 93.420611 -7.351173) (xy 93.486699 -7.255427) (xy 93.559235 -7.16447) (xy 93.637874 -7.078734)
			(xy 93.72224 -6.998627) (xy 93.811932 -6.924531) (xy 93.906522 -6.856801) (xy 94.00556 -6.795757)
			(xy 94.108573 -6.741692) (xy 94.21507 -6.694862) (xy 94.324545 -6.655491) (xy 94.436475 -6.623767)
			(xy 94.550327 -6.599841) (xy 94.665559 -6.583827) (xy 94.781621 -6.5758) (xy 94.83979 -6.575298)
			(xy 94.897959 -6.5758) (xy 95.014021 -6.583827) (xy 95.129253 -6.599841) (xy 95.243105 -6.623767)
			(xy 95.355035 -6.655491) (xy 95.46451 -6.694862) (xy 95.571007 -6.741692) (xy 95.67402 -6.795757)
			(xy 95.773058 -6.856801) (xy 95.867648 -6.924531) (xy 95.95734 -6.998627) (xy 96.041706 -7.078734)
			(xy 96.120345 -7.16447) (xy 96.192881 -7.255427) (xy 96.258969 -7.351173) (xy 96.318294 -7.451249)
			(xy 96.370573 -7.55518) (xy 96.415558 -7.66247) (xy 96.453033 -7.772608) (xy 96.48282 -7.885069)
			(xy 96.504778 -7.999317) (xy 96.518801 -8.114808) (xy 96.524823 -8.230991) (xy 96.522815 -8.347313)
			(xy 96.512786 -8.463219) (xy 96.494785 -8.578156) (xy 96.468897 -8.691579) (xy 96.435246 -8.802944)
			(xy 96.393992 -8.911723) (xy 96.345331 -9.017397) (xy 96.289495 -9.119461) (xy 96.226752 -9.21743)
			(xy 96.157398 -9.310837) (xy 96.081766 -9.399237) (xy 96.000215 -9.482208) (xy 95.913134 -9.559355)
			(xy 95.820938 -9.63031) (xy 95.724066 -9.694736) (xy 95.622981 -9.752325) (xy 95.518163 -9.802802)
			(xy 95.410112 -9.845928) (xy 95.299344 -9.881497) (xy 95.186385 -9.909339) (xy 95.071775 -9.929321)
			(xy 94.95606 -9.941348) (xy 94.83979 -9.945364) (xy 94.72352 -9.941348) (xy 94.607805 -9.929321)
			(xy 94.493195 -9.909339) (xy 94.380236 -9.881497) (xy 94.269468 -9.845928) (xy 94.161417 -9.802802)
			(xy 94.056599 -9.752325) (xy 93.955514 -9.694736) (xy 93.858642 -9.63031) (xy 93.766446 -9.559355)
			(xy 93.679365 -9.482208) (xy 93.597814 -9.399237) (xy 93.522182 -9.310837) (xy 93.452828 -9.21743)
			(xy 93.390085 -9.119461) (xy 93.334249 -9.017397) (xy 93.285588 -8.911723) (xy 93.244334 -8.802944)
			(xy 93.210683 -8.691579) (xy 93.184795 -8.578156) (xy 93.166794 -8.463219) (xy 93.156765 -8.347313)
			(xy 93.154757 -8.230991) (xy 92.177855 -8.230991) (xy 92.140459 -8.241189) (xy 92.065614 -8.253248)
			(xy 91.98991 -8.257283) (xy 91.914206 -8.253248) (xy 91.839361 -8.241189) (xy 91.76622 -8.221243)
			(xy 91.695615 -8.193636) (xy 91.628344 -8.15868) (xy 91.565169 -8.116772) (xy 91.506807 -8.068386)
			(xy 91.453919 -8.01407) (xy 91.407104 -7.954441) (xy 91.366892 -7.890173) (xy 91.33374 -7.821996)
			(xy 91.308022 -7.75068) (xy 91.29003 -7.677035) (xy 91.279968 -7.601895) (xy 91.277949 -7.526111)
			(xy 90.161871 -7.526111) (xy 90.159852 -7.601895) (xy 90.14979 -7.677035) (xy 90.131798 -7.75068)
			(xy 90.10608 -7.821996) (xy 90.072928 -7.890173) (xy 90.032716 -7.954441) (xy 89.985901 -8.01407)
			(xy 89.933013 -8.068386) (xy 89.874651 -8.116772) (xy 89.811476 -8.15868) (xy 89.744205 -8.193636)
			(xy 89.6736 -8.221243) (xy 89.600459 -8.241189) (xy 89.525614 -8.253248) (xy 89.44991 -8.257283)
			(xy 89.374206 -8.253248) (xy 89.299361 -8.241189) (xy 89.22622 -8.221243) (xy 89.155615 -8.193636)
			(xy 89.088344 -8.15868) (xy 89.025169 -8.116772) (xy 88.966807 -8.068386) (xy 88.913919 -8.01407)
			(xy 88.867104 -7.954441) (xy 88.826892 -7.890173) (xy 88.79374 -7.821996) (xy 88.768022 -7.75068)
			(xy 88.75003 -7.677035) (xy 88.739968 -7.601895) (xy 88.737949 -7.526111) (xy 87.621871 -7.526111)
			(xy 87.619852 -7.601895) (xy 87.60979 -7.677035) (xy 87.591798 -7.75068) (xy 87.56608 -7.821996)
			(xy 87.532928 -7.890173) (xy 87.492716 -7.954441) (xy 87.445901 -8.01407) (xy 87.393013 -8.068386)
			(xy 87.334651 -8.116772) (xy 87.271476 -8.15868) (xy 87.204205 -8.193636) (xy 87.1336 -8.221243)
			(xy 87.060459 -8.241189) (xy 86.985614 -8.253248) (xy 86.90991 -8.257283) (xy 86.834206 -8.253248)
			(xy 86.759361 -8.241189) (xy 86.68622 -8.221243) (xy 86.615615 -8.193636) (xy 86.548344 -8.15868)
			(xy 86.485169 -8.116772) (xy 86.426807 -8.068386) (xy 86.373919 -8.01407) (xy 86.327104 -7.954441)
			(xy 86.286892 -7.890173) (xy 86.25374 -7.821996) (xy 86.228022 -7.75068) (xy 86.21003 -7.677035)
			(xy 86.199968 -7.601895) (xy 86.197949 -7.526111) (xy 43.06342 -7.526111) (xy 43.050477 -7.56024)
			(xy 43.001926 -7.665674) (xy 42.946217 -7.767508) (xy 42.883615 -7.865256) (xy 42.814419 -7.958451)
			(xy 42.738957 -8.046651) (xy 42.65759 -8.129434) (xy 42.570706 -8.206407) (xy 42.525601 -8.241121)
			(xy 63.647829 -8.241121) (xy 63.653878 -8.165551) (xy 63.667925 -8.091053) (xy 63.689811 -8.01847)
			(xy 63.719288 -7.948624) (xy 63.756023 -7.882307) (xy 63.799598 -7.820271) (xy 63.84952 -7.763218)
			(xy 63.905224 -7.711794) (xy 63.966079 -7.666583) (xy 64.031394 -7.628096) (xy 64.10043 -7.59677)
			(xy 64.172405 -7.57296) (xy 64.246503 -7.556935) (xy 64.321884 -7.548876) (xy 64.35979 -7.548372)
			(xy 64.397696 -7.548876) (xy 64.473077 -7.556935) (xy 64.547175 -7.57296) (xy 64.61915 -7.59677)
			(xy 64.688186 -7.628096) (xy 64.753501 -7.666583) (xy 64.814356 -7.711794) (xy 64.87006 -7.763218)
			(xy 64.919982 -7.820271) (xy 64.963557 -7.882307) (xy 65.000292 -7.948624) (xy 65.029769 -8.01847)
			(xy 65.051655 -8.091053) (xy 65.065702 -8.165551) (xy 65.071751 -8.241121) (xy 66.187829 -8.241121)
			(xy 66.193878 -8.165551) (xy 66.207925 -8.091053) (xy 66.229811 -8.01847) (xy 66.259288 -7.948624)
			(xy 66.296023 -7.882307) (xy 66.339598 -7.820271) (xy 66.38952 -7.763218) (xy 66.445224 -7.711794)
			(xy 66.506079 -7.666583) (xy 66.571394 -7.628096) (xy 66.64043 -7.59677) (xy 66.712405 -7.57296)
			(xy 66.786503 -7.556935) (xy 66.861884 -7.548876) (xy 66.89979 -7.548372) (xy 66.937696 -7.548876)
			(xy 67.013077 -7.556935) (xy 67.087175 -7.57296) (xy 67.15915 -7.59677) (xy 67.228186 -7.628096)
			(xy 67.293501 -7.666583) (xy 67.354356 -7.711794) (xy 67.41006 -7.763218) (xy 67.459982 -7.820271)
			(xy 67.503557 -7.882307) (xy 67.540292 -7.948624) (xy 67.569769 -8.01847) (xy 67.591655 -8.091053)
			(xy 67.605702 -8.165551) (xy 67.611751 -8.241121) (xy 68.727829 -8.241121) (xy 68.733878 -8.165551)
			(xy 68.747925 -8.091053) (xy 68.769811 -8.01847) (xy 68.799288 -7.948624) (xy 68.836023 -7.882307)
			(xy 68.879598 -7.820271) (xy 68.92952 -7.763218) (xy 68.985224 -7.711794) (xy 69.046079 -7.666583)
			(xy 69.111394 -7.628096) (xy 69.18043 -7.59677) (xy 69.252405 -7.57296) (xy 69.326503 -7.556935)
			(xy 69.401884 -7.548876) (xy 69.43979 -7.548372) (xy 69.477696 -7.548876) (xy 69.553077 -7.556935)
			(xy 69.627175 -7.57296) (xy 69.69915 -7.59677) (xy 69.768186 -7.628096) (xy 69.833501 -7.666583)
			(xy 69.894356 -7.711794) (xy 69.95006 -7.763218) (xy 69.999982 -7.820271) (xy 70.043557 -7.882307)
			(xy 70.080292 -7.948624) (xy 70.109769 -8.01847) (xy 70.131655 -8.091053) (xy 70.145702 -8.165551)
			(xy 70.151751 -8.241121) (xy 71.267829 -8.241121) (xy 71.273878 -8.165551) (xy 71.287925 -8.091053)
			(xy 71.309811 -8.01847) (xy 71.339288 -7.948624) (xy 71.376023 -7.882307) (xy 71.419598 -7.820271)
			(xy 71.46952 -7.763218) (xy 71.525224 -7.711794) (xy 71.586079 -7.666583) (xy 71.651394 -7.628096)
			(xy 71.72043 -7.59677) (xy 71.792405 -7.57296) (xy 71.866503 -7.556935) (xy 71.941884 -7.548876)
			(xy 71.97979 -7.548372) (xy 72.017696 -7.548876) (xy 72.093077 -7.556935) (xy 72.167175 -7.57296)
			(xy 72.23915 -7.59677) (xy 72.308186 -7.628096) (xy 72.373501 -7.666583) (xy 72.434356 -7.711794)
			(xy 72.49006 -7.763218) (xy 72.539982 -7.820271) (xy 72.583557 -7.882307) (xy 72.620292 -7.948624)
			(xy 72.649769 -8.01847) (xy 72.671655 -8.091053) (xy 72.685702 -8.165551) (xy 72.691751 -8.241121)
			(xy 73.807829 -8.241121) (xy 73.813878 -8.165551) (xy 73.827925 -8.091053) (xy 73.849811 -8.01847)
			(xy 73.879288 -7.948624) (xy 73.916023 -7.882307) (xy 73.959598 -7.820271) (xy 74.00952 -7.763218)
			(xy 74.065224 -7.711794) (xy 74.126079 -7.666583) (xy 74.191394 -7.628096) (xy 74.26043 -7.59677)
			(xy 74.332405 -7.57296) (xy 74.406503 -7.556935) (xy 74.481884 -7.548876) (xy 74.51979 -7.548372)
			(xy 74.557696 -7.548876) (xy 74.633077 -7.556935) (xy 74.707175 -7.57296) (xy 74.77915 -7.59677)
			(xy 74.848186 -7.628096) (xy 74.913501 -7.666583) (xy 74.974356 -7.711794) (xy 75.03006 -7.763218)
			(xy 75.079982 -7.820271) (xy 75.123557 -7.882307) (xy 75.160292 -7.948624) (xy 75.189769 -8.01847)
			(xy 75.211655 -8.091053) (xy 75.225702 -8.165551) (xy 75.231751 -8.241121) (xy 76.347829 -8.241121)
			(xy 76.353878 -8.165551) (xy 76.367925 -8.091053) (xy 76.389811 -8.01847) (xy 76.419288 -7.948624)
			(xy 76.456023 -7.882307) (xy 76.499598 -7.820271) (xy 76.54952 -7.763218) (xy 76.605224 -7.711794)
			(xy 76.666079 -7.666583) (xy 76.731394 -7.628096) (xy 76.80043 -7.59677) (xy 76.872405 -7.57296)
			(xy 76.946503 -7.556935) (xy 77.021884 -7.548876) (xy 77.05979 -7.548372) (xy 77.097696 -7.548876)
			(xy 77.173077 -7.556935) (xy 77.247175 -7.57296) (xy 77.31915 -7.59677) (xy 77.388186 -7.628096)
			(xy 77.453501 -7.666583) (xy 77.514356 -7.711794) (xy 77.57006 -7.763218) (xy 77.619982 -7.820271)
			(xy 77.663557 -7.882307) (xy 77.700292 -7.948624) (xy 77.729769 -8.01847) (xy 77.751655 -8.091053)
			(xy 77.765702 -8.165551) (xy 77.771751 -8.241121) (xy 78.887829 -8.241121) (xy 78.893878 -8.165551)
			(xy 78.907925 -8.091053) (xy 78.929811 -8.01847) (xy 78.959288 -7.948624) (xy 78.996023 -7.882307)
			(xy 79.039598 -7.820271) (xy 79.08952 -7.763218) (xy 79.145224 -7.711794) (xy 79.206079 -7.666583)
			(xy 79.271394 -7.628096) (xy 79.34043 -7.59677) (xy 79.412405 -7.57296) (xy 79.486503 -7.556935)
			(xy 79.561884 -7.548876) (xy 79.59979 -7.548372) (xy 79.637696 -7.548876) (xy 79.713077 -7.556935)
			(xy 79.787175 -7.57296) (xy 79.85915 -7.59677) (xy 79.928186 -7.628096) (xy 79.993501 -7.666583)
			(xy 80.054356 -7.711794) (xy 80.11006 -7.763218) (xy 80.159982 -7.820271) (xy 80.203557 -7.882307)
			(xy 80.240292 -7.948624) (xy 80.269769 -8.01847) (xy 80.291655 -8.091053) (xy 80.305702 -8.165551)
			(xy 80.311751 -8.241121) (xy 81.427829 -8.241121) (xy 81.433878 -8.165551) (xy 81.447925 -8.091053)
			(xy 81.469811 -8.01847) (xy 81.499288 -7.948624) (xy 81.536023 -7.882307) (xy 81.579598 -7.820271)
			(xy 81.62952 -7.763218) (xy 81.685224 -7.711794) (xy 81.746079 -7.666583) (xy 81.811394 -7.628096)
			(xy 81.88043 -7.59677) (xy 81.952405 -7.57296) (xy 82.026503 -7.556935) (xy 82.101884 -7.548876)
			(xy 82.13979 -7.548372) (xy 82.177696 -7.548876) (xy 82.253077 -7.556935) (xy 82.327175 -7.57296)
			(xy 82.39915 -7.59677) (xy 82.468186 -7.628096) (xy 82.533501 -7.666583) (xy 82.594356 -7.711794)
			(xy 82.65006 -7.763218) (xy 82.699982 -7.820271) (xy 82.743557 -7.882307) (xy 82.780292 -7.948624)
			(xy 82.809769 -8.01847) (xy 82.831655 -8.091053) (xy 82.845702 -8.165551) (xy 82.851751 -8.241121)
			(xy 82.849732 -8.316905) (xy 82.83967 -8.392045) (xy 82.821678 -8.46569) (xy 82.79596 -8.537006)
			(xy 82.762808 -8.605183) (xy 82.722596 -8.669451) (xy 82.675781 -8.72908) (xy 82.622893 -8.783396)
			(xy 82.607556 -8.796111) (xy 84.927949 -8.796111) (xy 84.933998 -8.720541) (xy 84.948045 -8.646043)
			(xy 84.969931 -8.57346) (xy 84.999408 -8.503614) (xy 85.036143 -8.437297) (xy 85.079718 -8.375261)
			(xy 85.12964 -8.318208) (xy 85.185344 -8.266784) (xy 85.246199 -8.221573) (xy 85.311514 -8.183086)
			(xy 85.38055 -8.15176) (xy 85.452525 -8.12795) (xy 85.526623 -8.111925) (xy 85.602004 -8.103866)
			(xy 85.63991 -8.103362) (xy 85.677816 -8.103866) (xy 85.753197 -8.111925) (xy 85.827295 -8.12795)
			(xy 85.89927 -8.15176) (xy 85.968306 -8.183086) (xy 86.033621 -8.221573) (xy 86.094476 -8.266784)
			(xy 86.15018 -8.318208) (xy 86.200102 -8.375261) (xy 86.243677 -8.437297) (xy 86.280412 -8.503614)
			(xy 86.309889 -8.57346) (xy 86.331775 -8.646043) (xy 86.345822 -8.720541) (xy 86.351871 -8.796111)
			(xy 87.467949 -8.796111) (xy 87.473998 -8.720541) (xy 87.488045 -8.646043) (xy 87.509931 -8.57346)
			(xy 87.539408 -8.503614) (xy 87.576143 -8.437297) (xy 87.619718 -8.375261) (xy 87.66964 -8.318208)
			(xy 87.725344 -8.266784) (xy 87.786199 -8.221573) (xy 87.851514 -8.183086) (xy 87.92055 -8.15176)
			(xy 87.992525 -8.12795) (xy 88.066623 -8.111925) (xy 88.142004 -8.103866) (xy 88.17991 -8.103362)
			(xy 88.217816 -8.103866) (xy 88.293197 -8.111925) (xy 88.367295 -8.12795) (xy 88.43927 -8.15176)
			(xy 88.508306 -8.183086) (xy 88.573621 -8.221573) (xy 88.634476 -8.266784) (xy 88.69018 -8.318208)
			(xy 88.740102 -8.375261) (xy 88.783677 -8.437297) (xy 88.820412 -8.503614) (xy 88.849889 -8.57346)
			(xy 88.871775 -8.646043) (xy 88.885822 -8.720541) (xy 88.891871 -8.796111) (xy 90.007949 -8.796111)
			(xy 90.013998 -8.720541) (xy 90.028045 -8.646043) (xy 90.049931 -8.57346) (xy 90.079408 -8.503614)
			(xy 90.116143 -8.437297) (xy 90.159718 -8.375261) (xy 90.20964 -8.318208) (xy 90.265344 -8.266784)
			(xy 90.326199 -8.221573) (xy 90.391514 -8.183086) (xy 90.46055 -8.15176) (xy 90.532525 -8.12795)
			(xy 90.606623 -8.111925) (xy 90.682004 -8.103866) (xy 90.71991 -8.103362) (xy 90.757816 -8.103866)
			(xy 90.833197 -8.111925) (xy 90.907295 -8.12795) (xy 90.97927 -8.15176) (xy 91.048306 -8.183086)
			(xy 91.113621 -8.221573) (xy 91.174476 -8.266784) (xy 91.23018 -8.318208) (xy 91.280102 -8.375261)
			(xy 91.323677 -8.437297) (xy 91.360412 -8.503614) (xy 91.389889 -8.57346) (xy 91.411775 -8.646043)
			(xy 91.425822 -8.720541) (xy 91.431871 -8.796111) (xy 91.429852 -8.871895) (xy 91.41979 -8.947035)
			(xy 91.401798 -9.02068) (xy 91.37608 -9.091996) (xy 91.342928 -9.160173) (xy 91.302716 -9.224441)
			(xy 91.255901 -9.28407) (xy 91.203013 -9.338386) (xy 91.144651 -9.386772) (xy 91.081476 -9.42868)
			(xy 91.014205 -9.463636) (xy 90.9436 -9.491243) (xy 90.870459 -9.511189) (xy 90.795614 -9.523248)
			(xy 90.71991 -9.527283) (xy 90.644206 -9.523248) (xy 90.569361 -9.511189) (xy 90.49622 -9.491243)
			(xy 90.425615 -9.463636) (xy 90.358344 -9.42868) (xy 90.295169 -9.386772) (xy 90.236807 -9.338386)
			(xy 90.183919 -9.28407) (xy 90.137104 -9.224441) (xy 90.096892 -9.160173) (xy 90.06374 -9.091996)
			(xy 90.038022 -9.02068) (xy 90.02003 -8.947035) (xy 90.009968 -8.871895) (xy 90.007949 -8.796111)
			(xy 88.891871 -8.796111) (xy 88.889852 -8.871895) (xy 88.87979 -8.947035) (xy 88.861798 -9.02068)
			(xy 88.83608 -9.091996) (xy 88.802928 -9.160173) (xy 88.762716 -9.224441) (xy 88.715901 -9.28407)
			(xy 88.663013 -9.338386) (xy 88.604651 -9.386772) (xy 88.541476 -9.42868) (xy 88.474205 -9.463636)
			(xy 88.4036 -9.491243) (xy 88.330459 -9.511189) (xy 88.255614 -9.523248) (xy 88.17991 -9.527283)
			(xy 88.104206 -9.523248) (xy 88.029361 -9.511189) (xy 87.95622 -9.491243) (xy 87.885615 -9.463636)
			(xy 87.818344 -9.42868) (xy 87.755169 -9.386772) (xy 87.696807 -9.338386) (xy 87.643919 -9.28407)
			(xy 87.597104 -9.224441) (xy 87.556892 -9.160173) (xy 87.52374 -9.091996) (xy 87.498022 -9.02068)
			(xy 87.48003 -8.947035) (xy 87.469968 -8.871895) (xy 87.467949 -8.796111) (xy 86.351871 -8.796111)
			(xy 86.349852 -8.871895) (xy 86.33979 -8.947035) (xy 86.321798 -9.02068) (xy 86.29608 -9.091996)
			(xy 86.262928 -9.160173) (xy 86.222716 -9.224441) (xy 86.175901 -9.28407) (xy 86.123013 -9.338386)
			(xy 86.064651 -9.386772) (xy 86.001476 -9.42868) (xy 85.934205 -9.463636) (xy 85.8636 -9.491243)
			(xy 85.790459 -9.511189) (xy 85.715614 -9.523248) (xy 85.63991 -9.527283) (xy 85.564206 -9.523248)
			(xy 85.489361 -9.511189) (xy 85.41622 -9.491243) (xy 85.345615 -9.463636) (xy 85.278344 -9.42868)
			(xy 85.215169 -9.386772) (xy 85.156807 -9.338386) (xy 85.103919 -9.28407) (xy 85.057104 -9.224441)
			(xy 85.016892 -9.160173) (xy 84.98374 -9.091996) (xy 84.958022 -9.02068) (xy 84.94003 -8.947035)
			(xy 84.929968 -8.871895) (xy 84.927949 -8.796111) (xy 82.607556 -8.796111) (xy 82.564531 -8.831782)
			(xy 82.501356 -8.87369) (xy 82.434085 -8.908646) (xy 82.36348 -8.936253) (xy 82.290339 -8.956199)
			(xy 82.215494 -8.968258) (xy 82.13979 -8.972293) (xy 82.064086 -8.968258) (xy 81.989241 -8.956199)
			(xy 81.9161 -8.936253) (xy 81.845495 -8.908646) (xy 81.778224 -8.87369) (xy 81.715049 -8.831782)
			(xy 81.656687 -8.783396) (xy 81.603799 -8.72908) (xy 81.556984 -8.669451) (xy 81.516772 -8.605183)
			(xy 81.48362 -8.537006) (xy 81.457902 -8.46569) (xy 81.43991 -8.392045) (xy 81.429848 -8.316905)
			(xy 81.427829 -8.241121) (xy 80.311751 -8.241121) (xy 80.309732 -8.316905) (xy 80.29967 -8.392045)
			(xy 80.281678 -8.46569) (xy 80.25596 -8.537006) (xy 80.222808 -8.605183) (xy 80.182596 -8.669451)
			(xy 80.135781 -8.72908) (xy 80.082893 -8.783396) (xy 80.024531 -8.831782) (xy 79.961356 -8.87369)
			(xy 79.894085 -8.908646) (xy 79.82348 -8.936253) (xy 79.750339 -8.956199) (xy 79.675494 -8.968258)
			(xy 79.59979 -8.972293) (xy 79.524086 -8.968258) (xy 79.449241 -8.956199) (xy 79.3761 -8.936253)
			(xy 79.305495 -8.908646) (xy 79.238224 -8.87369) (xy 79.175049 -8.831782) (xy 79.116687 -8.783396)
			(xy 79.063799 -8.72908) (xy 79.016984 -8.669451) (xy 78.976772 -8.605183) (xy 78.94362 -8.537006)
			(xy 78.917902 -8.46569) (xy 78.89991 -8.392045) (xy 78.889848 -8.316905) (xy 78.887829 -8.241121)
			(xy 77.771751 -8.241121) (xy 77.769732 -8.316905) (xy 77.75967 -8.392045) (xy 77.741678 -8.46569)
			(xy 77.71596 -8.537006) (xy 77.682808 -8.605183) (xy 77.642596 -8.669451) (xy 77.595781 -8.72908)
			(xy 77.542893 -8.783396) (xy 77.484531 -8.831782) (xy 77.421356 -8.87369) (xy 77.354085 -8.908646)
			(xy 77.28348 -8.936253) (xy 77.210339 -8.956199) (xy 77.135494 -8.968258) (xy 77.05979 -8.972293)
			(xy 76.984086 -8.968258) (xy 76.909241 -8.956199) (xy 76.8361 -8.936253) (xy 76.765495 -8.908646)
			(xy 76.698224 -8.87369) (xy 76.635049 -8.831782) (xy 76.576687 -8.783396) (xy 76.523799 -8.72908)
			(xy 76.476984 -8.669451) (xy 76.436772 -8.605183) (xy 76.40362 -8.537006) (xy 76.377902 -8.46569)
			(xy 76.35991 -8.392045) (xy 76.349848 -8.316905) (xy 76.347829 -8.241121) (xy 75.231751 -8.241121)
			(xy 75.229732 -8.316905) (xy 75.21967 -8.392045) (xy 75.201678 -8.46569) (xy 75.17596 -8.537006)
			(xy 75.142808 -8.605183) (xy 75.102596 -8.669451) (xy 75.055781 -8.72908) (xy 75.002893 -8.783396)
			(xy 74.944531 -8.831782) (xy 74.881356 -8.87369) (xy 74.814085 -8.908646) (xy 74.74348 -8.936253)
			(xy 74.670339 -8.956199) (xy 74.595494 -8.968258) (xy 74.51979 -8.972293) (xy 74.444086 -8.968258)
			(xy 74.369241 -8.956199) (xy 74.2961 -8.936253) (xy 74.225495 -8.908646) (xy 74.158224 -8.87369)
			(xy 74.095049 -8.831782) (xy 74.036687 -8.783396) (xy 73.983799 -8.72908) (xy 73.936984 -8.669451)
			(xy 73.896772 -8.605183) (xy 73.86362 -8.537006) (xy 73.837902 -8.46569) (xy 73.81991 -8.392045)
			(xy 73.809848 -8.316905) (xy 73.807829 -8.241121) (xy 72.691751 -8.241121) (xy 72.689732 -8.316905)
			(xy 72.67967 -8.392045) (xy 72.661678 -8.46569) (xy 72.63596 -8.537006) (xy 72.602808 -8.605183)
			(xy 72.562596 -8.669451) (xy 72.515781 -8.72908) (xy 72.462893 -8.783396) (xy 72.404531 -8.831782)
			(xy 72.341356 -8.87369) (xy 72.274085 -8.908646) (xy 72.20348 -8.936253) (xy 72.130339 -8.956199)
			(xy 72.055494 -8.968258) (xy 71.97979 -8.972293) (xy 71.904086 -8.968258) (xy 71.829241 -8.956199)
			(xy 71.7561 -8.936253) (xy 71.685495 -8.908646) (xy 71.618224 -8.87369) (xy 71.555049 -8.831782)
			(xy 71.496687 -8.783396) (xy 71.443799 -8.72908) (xy 71.396984 -8.669451) (xy 71.356772 -8.605183)
			(xy 71.32362 -8.537006) (xy 71.297902 -8.46569) (xy 71.27991 -8.392045) (xy 71.269848 -8.316905)
			(xy 71.267829 -8.241121) (xy 70.151751 -8.241121) (xy 70.149732 -8.316905) (xy 70.13967 -8.392045)
			(xy 70.121678 -8.46569) (xy 70.09596 -8.537006) (xy 70.062808 -8.605183) (xy 70.022596 -8.669451)
			(xy 69.975781 -8.72908) (xy 69.922893 -8.783396) (xy 69.864531 -8.831782) (xy 69.801356 -8.87369)
			(xy 69.734085 -8.908646) (xy 69.66348 -8.936253) (xy 69.590339 -8.956199) (xy 69.515494 -8.968258)
			(xy 69.43979 -8.972293) (xy 69.364086 -8.968258) (xy 69.289241 -8.956199) (xy 69.2161 -8.936253)
			(xy 69.145495 -8.908646) (xy 69.078224 -8.87369) (xy 69.015049 -8.831782) (xy 68.956687 -8.783396)
			(xy 68.903799 -8.72908) (xy 68.856984 -8.669451) (xy 68.816772 -8.605183) (xy 68.78362 -8.537006)
			(xy 68.757902 -8.46569) (xy 68.73991 -8.392045) (xy 68.729848 -8.316905) (xy 68.727829 -8.241121)
			(xy 67.611751 -8.241121) (xy 67.609732 -8.316905) (xy 67.59967 -8.392045) (xy 67.581678 -8.46569)
			(xy 67.55596 -8.537006) (xy 67.522808 -8.605183) (xy 67.482596 -8.669451) (xy 67.435781 -8.72908)
			(xy 67.382893 -8.783396) (xy 67.324531 -8.831782) (xy 67.261356 -8.87369) (xy 67.194085 -8.908646)
			(xy 67.12348 -8.936253) (xy 67.050339 -8.956199) (xy 66.975494 -8.968258) (xy 66.89979 -8.972293)
			(xy 66.824086 -8.968258) (xy 66.749241 -8.956199) (xy 66.6761 -8.936253) (xy 66.605495 -8.908646)
			(xy 66.538224 -8.87369) (xy 66.475049 -8.831782) (xy 66.416687 -8.783396) (xy 66.363799 -8.72908)
			(xy 66.316984 -8.669451) (xy 66.276772 -8.605183) (xy 66.24362 -8.537006) (xy 66.217902 -8.46569)
			(xy 66.19991 -8.392045) (xy 66.189848 -8.316905) (xy 66.187829 -8.241121) (xy 65.071751 -8.241121)
			(xy 65.069732 -8.316905) (xy 65.05967 -8.392045) (xy 65.041678 -8.46569) (xy 65.01596 -8.537006)
			(xy 64.982808 -8.605183) (xy 64.942596 -8.669451) (xy 64.895781 -8.72908) (xy 64.842893 -8.783396)
			(xy 64.784531 -8.831782) (xy 64.721356 -8.87369) (xy 64.654085 -8.908646) (xy 64.58348 -8.936253)
			(xy 64.510339 -8.956199) (xy 64.435494 -8.968258) (xy 64.35979 -8.972293) (xy 64.284086 -8.968258)
			(xy 64.209241 -8.956199) (xy 64.1361 -8.936253) (xy 64.065495 -8.908646) (xy 63.998224 -8.87369)
			(xy 63.935049 -8.831782) (xy 63.876687 -8.783396) (xy 63.823799 -8.72908) (xy 63.776984 -8.669451)
			(xy 63.736772 -8.605183) (xy 63.70362 -8.537006) (xy 63.677902 -8.46569) (xy 63.65991 -8.392045)
			(xy 63.649848 -8.316905) (xy 63.647829 -8.241121) (xy 42.525601 -8.241121) (xy 42.478719 -8.277202)
			(xy 42.382066 -8.341482) (xy 42.281209 -8.39894) (xy 42.176629 -8.449304) (xy 42.068822 -8.492332)
			(xy 41.958305 -8.52782) (xy 41.845602 -8.555599) (xy 41.731251 -8.575536) (xy 41.615797 -8.587537)
			(xy 41.49979 -8.591543) (xy 41.383783 -8.587537) (xy 41.268329 -8.575536) (xy 41.153978 -8.555599)
			(xy 41.041275 -8.52782) (xy 40.930758 -8.492332) (xy 40.822951 -8.449304) (xy 40.718371 -8.39894)
			(xy 40.617514 -8.341482) (xy 40.520861 -8.277202) (xy 40.428874 -8.206407) (xy 40.34199 -8.129434)
			(xy 40.260623 -8.046651) (xy 40.185161 -7.958451) (xy 40.115965 -7.865256) (xy 40.053363 -7.767508)
			(xy 39.997654 -7.665674) (xy 39.949103 -7.56024) (xy 39.907942 -7.451707) (xy 39.874367 -7.340593)
			(xy 39.848537 -7.227427) (xy 39.830577 -7.112749) (xy 39.820571 -6.997105) (xy 39.818567 -6.881047)
			(xy 37.41166 -6.881047) (xy 37.41166 -11.610949) (xy 64.532756 -11.610949) (xy 64.532756 -11.539627)
			(xy 64.540742 -11.468753) (xy 64.556612 -11.399218) (xy 64.580169 -11.331898) (xy 64.611114 -11.267639)
			(xy 64.64906 -11.207248) (xy 64.693529 -11.151486) (xy 64.743962 -11.101053) (xy 64.799724 -11.056584)
			(xy 64.860115 -11.018638) (xy 64.924374 -10.987693) (xy 64.991694 -10.964136) (xy 65.061229 -10.948266)
			(xy 65.132103 -10.94028) (xy 65.167764 -10.93978) (xy 65.203425 -10.94028) (xy 65.274299 -10.948266)
			(xy 65.343834 -10.964136) (xy 65.411154 -10.987693) (xy 65.475413 -11.018638) (xy 65.535804 -11.056584)
			(xy 65.591566 -11.101053) (xy 65.641999 -11.151486) (xy 65.686468 -11.207248) (xy 65.724414 -11.267639)
			(xy 65.755359 -11.331898) (xy 65.778916 -11.399218) (xy 65.794786 -11.468753) (xy 65.802772 -11.539627)
			(xy 65.802772 -11.610949) (xy 66.447408 -11.610949) (xy 66.447408 -11.539627) (xy 66.455394 -11.468753)
			(xy 66.471264 -11.399218) (xy 66.494821 -11.331898) (xy 66.525766 -11.267639) (xy 66.563712 -11.207248)
			(xy 66.608181 -11.151486) (xy 66.658614 -11.101053) (xy 66.714376 -11.056584) (xy 66.774767 -11.018638)
			(xy 66.839026 -10.987693) (xy 66.906346 -10.964136) (xy 66.975881 -10.948266) (xy 67.046755 -10.94028)
			(xy 67.082416 -10.93978) (xy 67.118077 -10.94028) (xy 67.188951 -10.948266) (xy 67.258486 -10.964136)
			(xy 67.325806 -10.987693) (xy 67.390065 -11.018638) (xy 67.450456 -11.056584) (xy 67.506218 -11.101053)
			(xy 67.556651 -11.151486) (xy 67.60112 -11.207248) (xy 67.639066 -11.267639) (xy 67.670011 -11.331898)
			(xy 67.693568 -11.399218) (xy 67.709438 -11.468753) (xy 67.717424 -11.539627) (xy 67.717424 -11.610949)
			(xy 68.34428 -11.610949) (xy 68.34428 -11.539627) (xy 68.352266 -11.468753) (xy 68.368136 -11.399218)
			(xy 68.391693 -11.331898) (xy 68.422638 -11.267639) (xy 68.460584 -11.207248) (xy 68.505053 -11.151486)
			(xy 68.555486 -11.101053) (xy 68.611248 -11.056584) (xy 68.671639 -11.018638) (xy 68.735898 -10.987693)
			(xy 68.803218 -10.964136) (xy 68.872753 -10.948266) (xy 68.943627 -10.94028) (xy 68.979288 -10.93978)
			(xy 69.014949 -10.94028) (xy 69.085823 -10.948266) (xy 69.155358 -10.964136) (xy 69.222678 -10.987693)
			(xy 69.286937 -11.018638) (xy 69.347328 -11.056584) (xy 69.40309 -11.101053) (xy 69.453523 -11.151486)
			(xy 69.497992 -11.207248) (xy 69.535938 -11.267639) (xy 69.566883 -11.331898) (xy 69.59044 -11.399218)
			(xy 69.60631 -11.468753) (xy 69.614296 -11.539627) (xy 69.614296 -11.610949) (xy 70.422508 -11.610949)
			(xy 70.422508 -11.539627) (xy 70.430494 -11.468753) (xy 70.446364 -11.399218) (xy 70.469921 -11.331898)
			(xy 70.500866 -11.267639) (xy 70.538812 -11.207248) (xy 70.583281 -11.151486) (xy 70.633714 -11.101053)
			(xy 70.689476 -11.056584) (xy 70.749867 -11.018638) (xy 70.814126 -10.987693) (xy 70.881446 -10.964136)
			(xy 70.950981 -10.948266) (xy 71.021855 -10.94028) (xy 71.057516 -10.93978) (xy 71.093177 -10.94028)
			(xy 71.164051 -10.948266) (xy 71.233586 -10.964136) (xy 71.300906 -10.987693) (xy 71.365165 -11.018638)
			(xy 71.425556 -11.056584) (xy 71.481318 -11.101053) (xy 71.531751 -11.151486) (xy 71.57622 -11.207248)
			(xy 71.614166 -11.267639) (xy 71.645111 -11.331898) (xy 71.668668 -11.399218) (xy 71.684538 -11.468753)
			(xy 71.692524 -11.539627) (xy 71.692524 -11.610949) (xy 72.5429 -11.610949) (xy 72.5429 -11.539627)
			(xy 72.550886 -11.468753) (xy 72.566756 -11.399218) (xy 72.590313 -11.331898) (xy 72.621258 -11.267639)
			(xy 72.659204 -11.207248) (xy 72.703673 -11.151486) (xy 72.754106 -11.101053) (xy 72.809868 -11.056584)
			(xy 72.870259 -11.018638) (xy 72.934518 -10.987693) (xy 73.001838 -10.964136) (xy 73.071373 -10.948266)
			(xy 73.142247 -10.94028) (xy 73.177908 -10.93978) (xy 73.213569 -10.94028) (xy 73.284443 -10.948266)
			(xy 73.353978 -10.964136) (xy 73.421298 -10.987693) (xy 73.485557 -11.018638) (xy 73.545948 -11.056584)
			(xy 73.60171 -11.101053) (xy 73.652143 -11.151486) (xy 73.696612 -11.207248) (xy 73.734558 -11.267639)
			(xy 73.765503 -11.331898) (xy 73.78906 -11.399218) (xy 73.80493 -11.468753) (xy 73.812916 -11.539627)
			(xy 73.812916 -11.610949) (xy 73.80493 -11.681823) (xy 73.78906 -11.751358) (xy 73.765503 -11.818678)
			(xy 73.734558 -11.882937) (xy 73.696612 -11.943328) (xy 73.652143 -11.99909) (xy 73.60171 -12.049523)
			(xy 73.545948 -12.093992) (xy 73.485557 -12.131938) (xy 73.421298 -12.162883) (xy 73.353978 -12.18644)
			(xy 73.284443 -12.20231) (xy 73.213569 -12.210296) (xy 73.142247 -12.210296) (xy 73.071373 -12.20231)
			(xy 73.001838 -12.18644) (xy 72.934518 -12.162883) (xy 72.870259 -12.131938) (xy 72.809868 -12.093992)
			(xy 72.754106 -12.049523) (xy 72.703673 -11.99909) (xy 72.659204 -11.943328) (xy 72.621258 -11.882937)
			(xy 72.590313 -11.818678) (xy 72.566756 -11.751358) (xy 72.550886 -11.681823) (xy 72.5429 -11.610949)
			(xy 71.692524 -11.610949) (xy 71.684538 -11.681823) (xy 71.668668 -11.751358) (xy 71.645111 -11.818678)
			(xy 71.614166 -11.882937) (xy 71.57622 -11.943328) (xy 71.531751 -11.99909) (xy 71.481318 -12.049523)
			(xy 71.425556 -12.093992) (xy 71.365165 -12.131938) (xy 71.300906 -12.162883) (xy 71.233586 -12.18644)
			(xy 71.164051 -12.20231) (xy 71.093177 -12.210296) (xy 71.021855 -12.210296) (xy 70.950981 -12.20231)
			(xy 70.881446 -12.18644) (xy 70.814126 -12.162883) (xy 70.749867 -12.131938) (xy 70.689476 -12.093992)
			(xy 70.633714 -12.049523) (xy 70.583281 -11.99909) (xy 70.538812 -11.943328) (xy 70.500866 -11.882937)
			(xy 70.469921 -11.818678) (xy 70.446364 -11.751358) (xy 70.430494 -11.681823) (xy 70.422508 -11.610949)
			(xy 69.614296 -11.610949) (xy 69.60631 -11.681823) (xy 69.59044 -11.751358) (xy 69.566883 -11.818678)
			(xy 69.535938 -11.882937) (xy 69.497992 -11.943328) (xy 69.453523 -11.99909) (xy 69.40309 -12.049523)
			(xy 69.347328 -12.093992) (xy 69.286937 -12.131938) (xy 69.222678 -12.162883) (xy 69.155358 -12.18644)
			(xy 69.085823 -12.20231) (xy 69.014949 -12.210296) (xy 68.943627 -12.210296) (xy 68.872753 -12.20231)
			(xy 68.803218 -12.18644) (xy 68.735898 -12.162883) (xy 68.671639 -12.131938) (xy 68.611248 -12.093992)
			(xy 68.555486 -12.049523) (xy 68.505053 -11.99909) (xy 68.460584 -11.943328) (xy 68.422638 -11.882937)
			(xy 68.391693 -11.818678) (xy 68.368136 -11.751358) (xy 68.352266 -11.681823) (xy 68.34428 -11.610949)
			(xy 67.717424 -11.610949) (xy 67.709438 -11.681823) (xy 67.693568 -11.751358) (xy 67.670011 -11.818678)
			(xy 67.639066 -11.882937) (xy 67.60112 -11.943328) (xy 67.556651 -11.99909) (xy 67.506218 -12.049523)
			(xy 67.450456 -12.093992) (xy 67.390065 -12.131938) (xy 67.325806 -12.162883) (xy 67.258486 -12.18644)
			(xy 67.188951 -12.20231) (xy 67.118077 -12.210296) (xy 67.046755 -12.210296) (xy 66.975881 -12.20231)
			(xy 66.906346 -12.18644) (xy 66.839026 -12.162883) (xy 66.774767 -12.131938) (xy 66.714376 -12.093992)
			(xy 66.658614 -12.049523) (xy 66.608181 -11.99909) (xy 66.563712 -11.943328) (xy 66.525766 -11.882937)
			(xy 66.494821 -11.818678) (xy 66.471264 -11.751358) (xy 66.455394 -11.681823) (xy 66.447408 -11.610949)
			(xy 65.802772 -11.610949) (xy 65.794786 -11.681823) (xy 65.778916 -11.751358) (xy 65.755359 -11.818678)
			(xy 65.724414 -11.882937) (xy 65.686468 -11.943328) (xy 65.641999 -11.99909) (xy 65.591566 -12.049523)
			(xy 65.535804 -12.093992) (xy 65.475413 -12.131938) (xy 65.411154 -12.162883) (xy 65.343834 -12.18644)
			(xy 65.274299 -12.20231) (xy 65.203425 -12.210296) (xy 65.132103 -12.210296) (xy 65.061229 -12.20231)
			(xy 64.991694 -12.18644) (xy 64.924374 -12.162883) (xy 64.860115 -12.131938) (xy 64.799724 -12.093992)
			(xy 64.743962 -12.049523) (xy 64.693529 -11.99909) (xy 64.64906 -11.943328) (xy 64.611114 -11.882937)
			(xy 64.580169 -11.818678) (xy 64.556612 -11.751358) (xy 64.540742 -11.681823) (xy 64.532756 -11.610949)
			(xy 37.41166 -11.610949) (xy 37.41166 -13.092172) (xy 39.562514 -13.092172) (xy 39.562514 -13.032236)
			(xy 39.570337 -12.972814) (xy 39.58585 -12.914921) (xy 39.608786 -12.859548) (xy 39.638753 -12.807642)
			(xy 39.67524 -12.760092) (xy 39.71762 -12.717712) (xy 39.76517 -12.681225) (xy 39.817076 -12.651258)
			(xy 39.872449 -12.628322) (xy 39.930342 -12.612809) (xy 39.989764 -12.604986) (xy 40.019732 -12.604496)
			(xy 40.0497 -12.604986) (xy 40.109122 -12.612809) (xy 40.167015 -12.628322) (xy 40.222388 -12.651258)
			(xy 40.274294 -12.681225) (xy 40.321844 -12.717712) (xy 40.364224 -12.760092) (xy 40.400711 -12.807642)
			(xy 40.430678 -12.859548) (xy 40.453614 -12.914921) (xy 40.469127 -12.972814) (xy 40.47695 -13.032236)
			(xy 40.47695 -13.087854) (xy 83.719144 -13.087854) (xy 83.719144 -13.027918) (xy 83.726967 -12.968496)
			(xy 83.74248 -12.910603) (xy 83.765416 -12.85523) (xy 83.795383 -12.803324) (xy 83.83187 -12.755774)
			(xy 83.87425 -12.713394) (xy 83.9218 -12.676907) (xy 83.973706 -12.64694) (xy 84.029079 -12.624004)
			(xy 84.086972 -12.608491) (xy 84.146394 -12.600668) (xy 84.176362 -12.600178) (xy 84.20633 -12.600668)
			(xy 84.265752 -12.608491) (xy 84.323645 -12.624004) (xy 84.379018 -12.64694) (xy 84.430924 -12.676907)
			(xy 84.478474 -12.713394) (xy 84.520854 -12.755774) (xy 84.557341 -12.803324) (xy 84.587308 -12.85523)
			(xy 84.610244 -12.910603) (xy 84.625757 -12.968496) (xy 84.63358 -13.027918) (xy 84.63358 -13.087854)
			(xy 84.627895 -13.131034) (xy 85.997524 -13.131034) (xy 85.997524 -13.071098) (xy 86.005347 -13.011676)
			(xy 86.02086 -12.953783) (xy 86.043796 -12.89841) (xy 86.073763 -12.846504) (xy 86.11025 -12.798954)
			(xy 86.15263 -12.756574) (xy 86.20018 -12.720087) (xy 86.252086 -12.69012) (xy 86.307459 -12.667184)
			(xy 86.365352 -12.651671) (xy 86.424774 -12.643848) (xy 86.454742 -12.643358) (xy 86.48471 -12.643848)
			(xy 86.544132 -12.651671) (xy 86.602025 -12.667184) (xy 86.657398 -12.69012) (xy 86.709304 -12.720087)
			(xy 86.756854 -12.756574) (xy 86.799234 -12.798954) (xy 86.835721 -12.846504) (xy 86.865688 -12.89841)
			(xy 86.886713 -12.94917) (xy 88.008188 -12.94917) (xy 88.008188 -12.889234) (xy 88.016011 -12.829812)
			(xy 88.031524 -12.771919) (xy 88.05446 -12.716546) (xy 88.084427 -12.66464) (xy 88.120914 -12.61709)
			(xy 88.163294 -12.57471) (xy 88.210844 -12.538223) (xy 88.26275 -12.508256) (xy 88.318123 -12.48532)
			(xy 88.376016 -12.469807) (xy 88.435438 -12.461984) (xy 88.465406 -12.461494) (xy 88.495374 -12.461984)
			(xy 88.554796 -12.469807) (xy 88.612689 -12.48532) (xy 88.668062 -12.508256) (xy 88.719968 -12.538223)
			(xy 88.767518 -12.57471) (xy 88.809898 -12.61709) (xy 88.846385 -12.66464) (xy 88.876352 -12.716546)
			(xy 88.899288 -12.771919) (xy 88.914801 -12.829812) (xy 88.922624 -12.889234) (xy 88.922624 -12.94917)
			(xy 88.914801 -13.008592) (xy 88.899288 -13.066485) (xy 88.876352 -13.121858) (xy 88.846385 -13.173764)
			(xy 88.809898 -13.221314) (xy 88.767518 -13.263694) (xy 88.738483 -13.285974) (xy 90.965256 -13.285974)
			(xy 90.965256 -13.226038) (xy 90.973079 -13.166616) (xy 90.988592 -13.108723) (xy 91.011528 -13.05335)
			(xy 91.041495 -13.001444) (xy 91.077982 -12.953894) (xy 91.120362 -12.911514) (xy 91.167912 -12.875027)
			(xy 91.219818 -12.84506) (xy 91.275191 -12.822124) (xy 91.333084 -12.806611) (xy 91.392506 -12.798788)
			(xy 91.422474 -12.798298) (xy 91.452442 -12.798788) (xy 91.511864 -12.806611) (xy 91.569757 -12.822124)
			(xy 91.62513 -12.84506) (xy 91.677036 -12.875027) (xy 91.724586 -12.911514) (xy 91.766966 -12.953894)
			(xy 91.803453 -13.001444) (xy 91.83342 -13.05335) (xy 91.856356 -13.108723) (xy 91.871869 -13.166616)
			(xy 91.879692 -13.226038) (xy 91.879692 -13.285974) (xy 91.874776 -13.323312) (xy 92.435662 -13.323312)
			(xy 92.435662 -13.263376) (xy 92.443485 -13.203954) (xy 92.458998 -13.146061) (xy 92.481934 -13.090688)
			(xy 92.511901 -13.038782) (xy 92.548388 -12.991232) (xy 92.590768 -12.948852) (xy 92.638318 -12.912365)
			(xy 92.690224 -12.882398) (xy 92.745597 -12.859462) (xy 92.80349 -12.843949) (xy 92.862912 -12.836126)
			(xy 92.89288 -12.835636) (xy 92.922848 -12.836126) (xy 92.98227 -12.843949) (xy 93.040163 -12.859462)
			(xy 93.095536 -12.882398) (xy 93.147442 -12.912365) (xy 93.194992 -12.948852) (xy 93.237372 -12.991232)
			(xy 93.273859 -13.038782) (xy 93.303826 -13.090688) (xy 93.326762 -13.146061) (xy 93.342275 -13.203954)
			(xy 93.350098 -13.263376) (xy 93.350098 -13.2781) (xy 95.87406 -13.2781) (xy 95.87406 -13.218164)
			(xy 95.881883 -13.158742) (xy 95.897396 -13.100849) (xy 95.920332 -13.045476) (xy 95.950299 -12.99357)
			(xy 95.986786 -12.94602) (xy 96.029166 -12.90364) (xy 96.076716 -12.867153) (xy 96.128622 -12.837186)
			(xy 96.183995 -12.81425) (xy 96.241888 -12.798737) (xy 96.30131 -12.790914) (xy 96.331278 -12.790424)
			(xy 96.361246 -12.790914) (xy 96.420668 -12.798737) (xy 96.478561 -12.81425) (xy 96.533934 -12.837186)
			(xy 96.58584 -12.867153) (xy 96.63339 -12.90364) (xy 96.67577 -12.94602) (xy 96.712257 -12.99357)
			(xy 96.742224 -13.045476) (xy 96.76516 -13.100849) (xy 96.780673 -13.158742) (xy 96.788496 -13.218164)
			(xy 96.788496 -13.2781) (xy 96.780673 -13.337522) (xy 96.76516 -13.395415) (xy 96.742224 -13.450788)
			(xy 96.712257 -13.502694) (xy 96.67577 -13.550244) (xy 96.63339 -13.592624) (xy 96.58584 -13.629111)
			(xy 96.533934 -13.659078) (xy 96.478561 -13.682014) (xy 96.420668 -13.697527) (xy 96.361246 -13.70535)
			(xy 96.30131 -13.70535) (xy 96.241888 -13.697527) (xy 96.183995 -13.682014) (xy 96.128622 -13.659078)
			(xy 96.076716 -13.629111) (xy 96.029166 -13.592624) (xy 95.986786 -13.550244) (xy 95.950299 -13.502694)
			(xy 95.920332 -13.450788) (xy 95.897396 -13.395415) (xy 95.881883 -13.337522) (xy 95.87406 -13.2781)
			(xy 93.350098 -13.2781) (xy 93.350098 -13.323312) (xy 93.342275 -13.382734) (xy 93.326762 -13.440627)
			(xy 93.303826 -13.496) (xy 93.273859 -13.547906) (xy 93.237372 -13.595456) (xy 93.194992 -13.637836)
			(xy 93.147442 -13.674323) (xy 93.095536 -13.70429) (xy 93.040163 -13.727226) (xy 92.98227 -13.742739)
			(xy 92.922848 -13.750562) (xy 92.862912 -13.750562) (xy 92.80349 -13.742739) (xy 92.745597 -13.727226)
			(xy 92.690224 -13.70429) (xy 92.638318 -13.674323) (xy 92.590768 -13.637836) (xy 92.548388 -13.595456)
			(xy 92.511901 -13.547906) (xy 92.481934 -13.496) (xy 92.458998 -13.440627) (xy 92.443485 -13.382734)
			(xy 92.435662 -13.323312) (xy 91.874776 -13.323312) (xy 91.871869 -13.345396) (xy 91.856356 -13.403289)
			(xy 91.83342 -13.458662) (xy 91.803453 -13.510568) (xy 91.766966 -13.558118) (xy 91.724586 -13.600498)
			(xy 91.677036 -13.636985) (xy 91.62513 -13.666952) (xy 91.569757 -13.689888) (xy 91.511864 -13.705401)
			(xy 91.452442 -13.713224) (xy 91.392506 -13.713224) (xy 91.333084 -13.705401) (xy 91.275191 -13.689888)
			(xy 91.219818 -13.666952) (xy 91.167912 -13.636985) (xy 91.120362 -13.600498) (xy 91.077982 -13.558118)
			(xy 91.041495 -13.510568) (xy 91.011528 -13.458662) (xy 90.988592 -13.403289) (xy 90.973079 -13.345396)
			(xy 90.965256 -13.285974) (xy 88.738483 -13.285974) (xy 88.719968 -13.300181) (xy 88.668062 -13.330148)
			(xy 88.612689 -13.353084) (xy 88.554796 -13.368597) (xy 88.495374 -13.37642) (xy 88.435438 -13.37642)
			(xy 88.376016 -13.368597) (xy 88.318123 -13.353084) (xy 88.26275 -13.330148) (xy 88.210844 -13.300181)
			(xy 88.163294 -13.263694) (xy 88.120914 -13.221314) (xy 88.084427 -13.173764) (xy 88.05446 -13.121858)
			(xy 88.031524 -13.066485) (xy 88.016011 -13.008592) (xy 88.008188 -12.94917) (xy 86.886713 -12.94917)
			(xy 86.888624 -12.953783) (xy 86.904137 -13.011676) (xy 86.91196 -13.071098) (xy 86.91196 -13.131034)
			(xy 86.904137 -13.190456) (xy 86.888624 -13.248349) (xy 86.865688 -13.303722) (xy 86.835721 -13.355628)
			(xy 86.799234 -13.403178) (xy 86.756854 -13.445558) (xy 86.709304 -13.482045) (xy 86.657398 -13.512012)
			(xy 86.602025 -13.534948) (xy 86.544132 -13.550461) (xy 86.48471 -13.558284) (xy 86.424774 -13.558284)
			(xy 86.365352 -13.550461) (xy 86.307459 -13.534948) (xy 86.252086 -13.512012) (xy 86.20018 -13.482045)
			(xy 86.15263 -13.445558) (xy 86.11025 -13.403178) (xy 86.073763 -13.355628) (xy 86.043796 -13.303722)
			(xy 86.02086 -13.248349) (xy 86.005347 -13.190456) (xy 85.997524 -13.131034) (xy 84.627895 -13.131034)
			(xy 84.625757 -13.147276) (xy 84.610244 -13.205169) (xy 84.587308 -13.260542) (xy 84.557341 -13.312448)
			(xy 84.520854 -13.359998) (xy 84.478474 -13.402378) (xy 84.430924 -13.438865) (xy 84.379018 -13.468832)
			(xy 84.323645 -13.491768) (xy 84.265752 -13.507281) (xy 84.20633 -13.515104) (xy 84.146394 -13.515104)
			(xy 84.086972 -13.507281) (xy 84.029079 -13.491768) (xy 83.973706 -13.468832) (xy 83.9218 -13.438865)
			(xy 83.87425 -13.402378) (xy 83.83187 -13.359998) (xy 83.795383 -13.312448) (xy 83.765416 -13.260542)
			(xy 83.74248 -13.205169) (xy 83.726967 -13.147276) (xy 83.719144 -13.087854) (xy 40.47695 -13.087854)
			(xy 40.47695 -13.092172) (xy 40.469127 -13.151594) (xy 40.453614 -13.209487) (xy 40.430678 -13.26486)
			(xy 40.400711 -13.316766) (xy 40.364224 -13.364316) (xy 40.321844 -13.406696) (xy 40.274294 -13.443183)
			(xy 40.222388 -13.47315) (xy 40.167015 -13.496086) (xy 40.109122 -13.511599) (xy 40.0497 -13.519422)
			(xy 39.989764 -13.519422) (xy 39.930342 -13.511599) (xy 39.872449 -13.496086) (xy 39.817076 -13.47315)
			(xy 39.76517 -13.443183) (xy 39.71762 -13.406696) (xy 39.67524 -13.364316) (xy 39.638753 -13.316766)
			(xy 39.608786 -13.26486) (xy 39.58585 -13.209487) (xy 39.570337 -13.151594) (xy 39.562514 -13.092172)
			(xy 37.41166 -13.092172) (xy 37.41166 -13.991437) (xy 64.532756 -13.991437) (xy 64.532756 -13.920115)
			(xy 64.540742 -13.849241) (xy 64.556612 -13.779706) (xy 64.580169 -13.712386) (xy 64.611114 -13.648127)
			(xy 64.64906 -13.587736) (xy 64.693529 -13.531974) (xy 64.743962 -13.481541) (xy 64.799724 -13.437072)
			(xy 64.860115 -13.399126) (xy 64.924374 -13.368181) (xy 64.991694 -13.344624) (xy 65.061229 -13.328754)
			(xy 65.132103 -13.320768) (xy 65.167764 -13.320268) (xy 65.203425 -13.320768) (xy 65.274299 -13.328754)
			(xy 65.343834 -13.344624) (xy 65.411154 -13.368181) (xy 65.475413 -13.399126) (xy 65.535804 -13.437072)
			(xy 65.591566 -13.481541) (xy 65.641999 -13.531974) (xy 65.686468 -13.587736) (xy 65.724414 -13.648127)
			(xy 65.755359 -13.712386) (xy 65.778916 -13.779706) (xy 65.794786 -13.849241) (xy 65.802772 -13.920115)
			(xy 65.802772 -13.991437) (xy 66.447408 -13.991437) (xy 66.447408 -13.920115) (xy 66.455394 -13.849241)
			(xy 66.471264 -13.779706) (xy 66.494821 -13.712386) (xy 66.525766 -13.648127) (xy 66.563712 -13.587736)
			(xy 66.608181 -13.531974) (xy 66.658614 -13.481541) (xy 66.714376 -13.437072) (xy 66.774767 -13.399126)
			(xy 66.839026 -13.368181) (xy 66.906346 -13.344624) (xy 66.975881 -13.328754) (xy 67.046755 -13.320768)
			(xy 67.082416 -13.320268) (xy 67.118077 -13.320768) (xy 67.188951 -13.328754) (xy 67.258486 -13.344624)
			(xy 67.325806 -13.368181) (xy 67.390065 -13.399126) (xy 67.450456 -13.437072) (xy 67.506218 -13.481541)
			(xy 67.556651 -13.531974) (xy 67.60112 -13.587736) (xy 67.639066 -13.648127) (xy 67.670011 -13.712386)
			(xy 67.693568 -13.779706) (xy 67.709438 -13.849241) (xy 67.717424 -13.920115) (xy 67.717424 -13.991437)
			(xy 68.34428 -13.991437) (xy 68.34428 -13.920115) (xy 68.352266 -13.849241) (xy 68.368136 -13.779706)
			(xy 68.391693 -13.712386) (xy 68.422638 -13.648127) (xy 68.460584 -13.587736) (xy 68.505053 -13.531974)
			(xy 68.555486 -13.481541) (xy 68.611248 -13.437072) (xy 68.671639 -13.399126) (xy 68.735898 -13.368181)
			(xy 68.803218 -13.344624) (xy 68.872753 -13.328754) (xy 68.943627 -13.320768) (xy 68.979288 -13.320268)
			(xy 69.014949 -13.320768) (xy 69.085823 -13.328754) (xy 69.155358 -13.344624) (xy 69.222678 -13.368181)
			(xy 69.286937 -13.399126) (xy 69.347328 -13.437072) (xy 69.40309 -13.481541) (xy 69.453523 -13.531974)
			(xy 69.497992 -13.587736) (xy 69.535938 -13.648127) (xy 69.566883 -13.712386) (xy 69.59044 -13.779706)
			(xy 69.60631 -13.849241) (xy 69.614296 -13.920115) (xy 69.614296 -13.991437) (xy 70.422508 -13.991437)
			(xy 70.422508 -13.920115) (xy 70.430494 -13.849241) (xy 70.446364 -13.779706) (xy 70.469921 -13.712386)
			(xy 70.500866 -13.648127) (xy 70.538812 -13.587736) (xy 70.583281 -13.531974) (xy 70.633714 -13.481541)
			(xy 70.689476 -13.437072) (xy 70.749867 -13.399126) (xy 70.814126 -13.368181) (xy 70.881446 -13.344624)
			(xy 70.950981 -13.328754) (xy 71.021855 -13.320768) (xy 71.057516 -13.320268) (xy 71.093177 -13.320768)
			(xy 71.164051 -13.328754) (xy 71.233586 -13.344624) (xy 71.300906 -13.368181) (xy 71.365165 -13.399126)
			(xy 71.425556 -13.437072) (xy 71.481318 -13.481541) (xy 71.531751 -13.531974) (xy 71.57622 -13.587736)
			(xy 71.614166 -13.648127) (xy 71.645111 -13.712386) (xy 71.668668 -13.779706) (xy 71.684538 -13.849241)
			(xy 71.692524 -13.920115) (xy 71.692524 -13.991437) (xy 72.5429 -13.991437) (xy 72.5429 -13.920115)
			(xy 72.550886 -13.849241) (xy 72.566756 -13.779706) (xy 72.590313 -13.712386) (xy 72.621258 -13.648127)
			(xy 72.659204 -13.587736) (xy 72.703673 -13.531974) (xy 72.754106 -13.481541) (xy 72.809868 -13.437072)
			(xy 72.870259 -13.399126) (xy 72.934518 -13.368181) (xy 73.001838 -13.344624) (xy 73.071373 -13.328754)
			(xy 73.142247 -13.320768) (xy 73.177908 -13.320268) (xy 73.213569 -13.320768) (xy 73.284443 -13.328754)
			(xy 73.353978 -13.344624) (xy 73.421298 -13.368181) (xy 73.485557 -13.399126) (xy 73.545948 -13.437072)
			(xy 73.60171 -13.481541) (xy 73.652143 -13.531974) (xy 73.696612 -13.587736) (xy 73.734558 -13.648127)
			(xy 73.765503 -13.712386) (xy 73.78906 -13.779706) (xy 73.80493 -13.849241) (xy 73.812916 -13.920115)
			(xy 73.812916 -13.991437) (xy 73.80493 -14.062311) (xy 73.78906 -14.131846) (xy 73.765503 -14.199166)
			(xy 73.736543 -14.259302) (xy 84.350588 -14.259302) (xy 84.350588 -14.199366) (xy 84.358411 -14.139944)
			(xy 84.373924 -14.082051) (xy 84.39686 -14.026678) (xy 84.426827 -13.974772) (xy 84.463314 -13.927222)
			(xy 84.505694 -13.884842) (xy 84.553244 -13.848355) (xy 84.60515 -13.818388) (xy 84.660523 -13.795452)
			(xy 84.718416 -13.779939) (xy 84.777838 -13.772116) (xy 84.807806 -13.771626) (xy 84.837774 -13.772116)
			(xy 84.897196 -13.779939) (xy 84.955089 -13.795452) (xy 85.010462 -13.818388) (xy 85.062368 -13.848355)
			(xy 85.109918 -13.884842) (xy 85.152298 -13.927222) (xy 85.188785 -13.974772) (xy 85.218752 -14.026678)
			(xy 85.241688 -14.082051) (xy 85.257201 -14.139944) (xy 85.265024 -14.199366) (xy 85.265024 -14.259302)
			(xy 85.259373 -14.302228) (xy 87.195388 -14.302228) (xy 87.195388 -14.242292) (xy 87.203211 -14.18287)
			(xy 87.218724 -14.124977) (xy 87.24166 -14.069604) (xy 87.271627 -14.017698) (xy 87.308114 -13.970148)
			(xy 87.350494 -13.927768) (xy 87.398044 -13.891281) (xy 87.44995 -13.861314) (xy 87.505323 -13.838378)
			(xy 87.563216 -13.822865) (xy 87.622638 -13.815042) (xy 87.652606 -13.814552) (xy 87.682574 -13.815042)
			(xy 87.741996 -13.822865) (xy 87.799889 -13.838378) (xy 87.855262 -13.861314) (xy 87.907168 -13.891281)
			(xy 87.954718 -13.927768) (xy 87.997098 -13.970148) (xy 88.033585 -14.017698) (xy 88.063552 -14.069604)
			(xy 88.086488 -14.124977) (xy 88.102001 -14.18287) (xy 88.109824 -14.242292) (xy 88.109824 -14.285972)
			(xy 94.082598 -14.285972) (xy 94.082598 -14.226036) (xy 94.090421 -14.166614) (xy 94.105934 -14.108721)
			(xy 94.12887 -14.053348) (xy 94.158837 -14.001442) (xy 94.195324 -13.953892) (xy 94.237704 -13.911512)
			(xy 94.285254 -13.875025) (xy 94.33716 -13.845058) (xy 94.392533 -13.822122) (xy 94.450426 -13.806609)
			(xy 94.509848 -13.798786) (xy 94.539816 -13.798296) (xy 94.569784 -13.798786) (xy 94.629206 -13.806609)
			(xy 94.687099 -13.822122) (xy 94.742472 -13.845058) (xy 94.794378 -13.875025) (xy 94.841928 -13.911512)
			(xy 94.884308 -13.953892) (xy 94.920795 -14.001442) (xy 94.950762 -14.053348) (xy 94.973698 -14.108721)
			(xy 94.989211 -14.166614) (xy 94.997034 -14.226036) (xy 94.997034 -14.285972) (xy 94.989211 -14.345394)
			(xy 94.973698 -14.403287) (xy 94.950762 -14.45866) (xy 94.920795 -14.510566) (xy 94.884308 -14.558116)
			(xy 94.841928 -14.600496) (xy 94.794378 -14.636983) (xy 94.742472 -14.66695) (xy 94.687099 -14.689886)
			(xy 94.629206 -14.705399) (xy 94.569784 -14.713222) (xy 94.509848 -14.713222) (xy 94.450426 -14.705399)
			(xy 94.392533 -14.689886) (xy 94.33716 -14.66695) (xy 94.285254 -14.636983) (xy 94.237704 -14.600496)
			(xy 94.195324 -14.558116) (xy 94.158837 -14.510566) (xy 94.12887 -14.45866) (xy 94.105934 -14.403287)
			(xy 94.090421 -14.345394) (xy 94.082598 -14.285972) (xy 88.109824 -14.285972) (xy 88.109824 -14.302228)
			(xy 88.102001 -14.36165) (xy 88.086488 -14.419543) (xy 88.063552 -14.474916) (xy 88.033585 -14.526822)
			(xy 87.997098 -14.574372) (xy 87.954718 -14.616752) (xy 87.907168 -14.653239) (xy 87.855262 -14.683206)
			(xy 87.799889 -14.706142) (xy 87.741996 -14.721655) (xy 87.682574 -14.729478) (xy 87.622638 -14.729478)
			(xy 87.563216 -14.721655) (xy 87.505323 -14.706142) (xy 87.44995 -14.683206) (xy 87.398044 -14.653239)
			(xy 87.350494 -14.616752) (xy 87.308114 -14.574372) (xy 87.271627 -14.526822) (xy 87.24166 -14.474916)
			(xy 87.218724 -14.419543) (xy 87.203211 -14.36165) (xy 87.195388 -14.302228) (xy 85.259373 -14.302228)
			(xy 85.257201 -14.318724) (xy 85.241688 -14.376617) (xy 85.218752 -14.43199) (xy 85.188785 -14.483896)
			(xy 85.152298 -14.531446) (xy 85.109918 -14.573826) (xy 85.062368 -14.610313) (xy 85.010462 -14.64028)
			(xy 84.955089 -14.663216) (xy 84.897196 -14.678729) (xy 84.837774 -14.686552) (xy 84.777838 -14.686552)
			(xy 84.718416 -14.678729) (xy 84.660523 -14.663216) (xy 84.60515 -14.64028) (xy 84.553244 -14.610313)
			(xy 84.505694 -14.573826) (xy 84.463314 -14.531446) (xy 84.426827 -14.483896) (xy 84.39686 -14.43199)
			(xy 84.373924 -14.376617) (xy 84.358411 -14.318724) (xy 84.350588 -14.259302) (xy 73.736543 -14.259302)
			(xy 73.734558 -14.263425) (xy 73.696612 -14.323816) (xy 73.652143 -14.379578) (xy 73.60171 -14.430011)
			(xy 73.545948 -14.47448) (xy 73.485557 -14.512426) (xy 73.421298 -14.543371) (xy 73.353978 -14.566928)
			(xy 73.284443 -14.582798) (xy 73.213569 -14.590784) (xy 73.142247 -14.590784) (xy 73.071373 -14.582798)
			(xy 73.001838 -14.566928) (xy 72.934518 -14.543371) (xy 72.870259 -14.512426) (xy 72.809868 -14.47448)
			(xy 72.754106 -14.430011) (xy 72.703673 -14.379578) (xy 72.659204 -14.323816) (xy 72.621258 -14.263425)
			(xy 72.590313 -14.199166) (xy 72.566756 -14.131846) (xy 72.550886 -14.062311) (xy 72.5429 -13.991437)
			(xy 71.692524 -13.991437) (xy 71.684538 -14.062311) (xy 71.668668 -14.131846) (xy 71.645111 -14.199166)
			(xy 71.614166 -14.263425) (xy 71.57622 -14.323816) (xy 71.531751 -14.379578) (xy 71.481318 -14.430011)
			(xy 71.425556 -14.47448) (xy 71.365165 -14.512426) (xy 71.300906 -14.543371) (xy 71.233586 -14.566928)
			(xy 71.164051 -14.582798) (xy 71.093177 -14.590784) (xy 71.021855 -14.590784) (xy 70.950981 -14.582798)
			(xy 70.881446 -14.566928) (xy 70.814126 -14.543371) (xy 70.749867 -14.512426) (xy 70.689476 -14.47448)
			(xy 70.633714 -14.430011) (xy 70.583281 -14.379578) (xy 70.538812 -14.323816) (xy 70.500866 -14.263425)
			(xy 70.469921 -14.199166) (xy 70.446364 -14.131846) (xy 70.430494 -14.062311) (xy 70.422508 -13.991437)
			(xy 69.614296 -13.991437) (xy 69.60631 -14.062311) (xy 69.59044 -14.131846) (xy 69.566883 -14.199166)
			(xy 69.535938 -14.263425) (xy 69.497992 -14.323816) (xy 69.453523 -14.379578) (xy 69.40309 -14.430011)
			(xy 69.347328 -14.47448) (xy 69.286937 -14.512426) (xy 69.222678 -14.543371) (xy 69.155358 -14.566928)
			(xy 69.085823 -14.582798) (xy 69.014949 -14.590784) (xy 68.943627 -14.590784) (xy 68.872753 -14.582798)
			(xy 68.803218 -14.566928) (xy 68.735898 -14.543371) (xy 68.671639 -14.512426) (xy 68.611248 -14.47448)
			(xy 68.555486 -14.430011) (xy 68.505053 -14.379578) (xy 68.460584 -14.323816) (xy 68.422638 -14.263425)
			(xy 68.391693 -14.199166) (xy 68.368136 -14.131846) (xy 68.352266 -14.062311) (xy 68.34428 -13.991437)
			(xy 67.717424 -13.991437) (xy 67.709438 -14.062311) (xy 67.693568 -14.131846) (xy 67.670011 -14.199166)
			(xy 67.639066 -14.263425) (xy 67.60112 -14.323816) (xy 67.556651 -14.379578) (xy 67.506218 -14.430011)
			(xy 67.450456 -14.47448) (xy 67.390065 -14.512426) (xy 67.325806 -14.543371) (xy 67.258486 -14.566928)
			(xy 67.188951 -14.582798) (xy 67.118077 -14.590784) (xy 67.046755 -14.590784) (xy 66.975881 -14.582798)
			(xy 66.906346 -14.566928) (xy 66.839026 -14.543371) (xy 66.774767 -14.512426) (xy 66.714376 -14.47448)
			(xy 66.658614 -14.430011) (xy 66.608181 -14.379578) (xy 66.563712 -14.323816) (xy 66.525766 -14.263425)
			(xy 66.494821 -14.199166) (xy 66.471264 -14.131846) (xy 66.455394 -14.062311) (xy 66.447408 -13.991437)
			(xy 65.802772 -13.991437) (xy 65.794786 -14.062311) (xy 65.778916 -14.131846) (xy 65.755359 -14.199166)
			(xy 65.724414 -14.263425) (xy 65.686468 -14.323816) (xy 65.641999 -14.379578) (xy 65.591566 -14.430011)
			(xy 65.535804 -14.47448) (xy 65.475413 -14.512426) (xy 65.411154 -14.543371) (xy 65.343834 -14.566928)
			(xy 65.274299 -14.582798) (xy 65.203425 -14.590784) (xy 65.132103 -14.590784) (xy 65.061229 -14.582798)
			(xy 64.991694 -14.566928) (xy 64.924374 -14.543371) (xy 64.860115 -14.512426) (xy 64.799724 -14.47448)
			(xy 64.743962 -14.430011) (xy 64.693529 -14.379578) (xy 64.64906 -14.323816) (xy 64.611114 -14.263425)
			(xy 64.580169 -14.199166) (xy 64.556612 -14.131846) (xy 64.540742 -14.062311) (xy 64.532756 -13.991437)
			(xy 37.41166 -13.991437) (xy 37.41166 -14.873982) (xy 95.95407 -14.873982) (xy 95.95407 -14.814046)
			(xy 95.961893 -14.754624) (xy 95.977406 -14.696731) (xy 96.000342 -14.641358) (xy 96.030309 -14.589452)
			(xy 96.066796 -14.541902) (xy 96.109176 -14.499522) (xy 96.156726 -14.463035) (xy 96.208632 -14.433068)
			(xy 96.264005 -14.410132) (xy 96.321898 -14.394619) (xy 96.38132 -14.386796) (xy 96.411288 -14.386306)
			(xy 96.441256 -14.386796) (xy 96.500678 -14.394619) (xy 96.558571 -14.410132) (xy 96.613944 -14.433068)
			(xy 96.66585 -14.463035) (xy 96.7134 -14.499522) (xy 96.75578 -14.541902) (xy 96.792267 -14.589452)
			(xy 96.822234 -14.641358) (xy 96.84517 -14.696731) (xy 96.860683 -14.754624) (xy 96.868506 -14.814046)
			(xy 96.868506 -14.873982) (xy 96.860683 -14.933404) (xy 96.84517 -14.991297) (xy 96.822234 -15.04667)
			(xy 96.792267 -15.098576) (xy 96.75578 -15.146126) (xy 96.7134 -15.188506) (xy 96.66585 -15.224993)
			(xy 96.613944 -15.25496) (xy 96.558571 -15.277896) (xy 96.500678 -15.293409) (xy 96.441256 -15.301232)
			(xy 96.38132 -15.301232) (xy 96.321898 -15.293409) (xy 96.264005 -15.277896) (xy 96.208632 -15.25496)
			(xy 96.156726 -15.224993) (xy 96.109176 -15.188506) (xy 96.066796 -15.146126) (xy 96.030309 -15.098576)
			(xy 96.000342 -15.04667) (xy 95.977406 -14.991297) (xy 95.961893 -14.933404) (xy 95.95407 -14.873982)
			(xy 37.41166 -14.873982) (xy 37.41166 -15.665954) (xy 85.45244 -15.665954) (xy 85.45244 -15.606018)
			(xy 85.460263 -15.546596) (xy 85.475776 -15.488703) (xy 85.498712 -15.43333) (xy 85.528679 -15.381424)
			(xy 85.565166 -15.333874) (xy 85.607546 -15.291494) (xy 85.655096 -15.255007) (xy 85.707002 -15.22504)
			(xy 85.762375 -15.202104) (xy 85.820268 -15.186591) (xy 85.87969 -15.178768) (xy 85.909658 -15.178278)
			(xy 85.939626 -15.178768) (xy 85.999048 -15.186591) (xy 86.056941 -15.202104) (xy 86.112314 -15.22504)
			(xy 86.16422 -15.255007) (xy 86.21177 -15.291494) (xy 86.25415 -15.333874) (xy 86.290637 -15.381424)
			(xy 86.320604 -15.43333) (xy 86.34354 -15.488703) (xy 86.359053 -15.546596) (xy 86.366876 -15.606018)
			(xy 86.366876 -15.665954) (xy 86.359053 -15.725376) (xy 86.34354 -15.783269) (xy 86.320604 -15.838642)
			(xy 86.290637 -15.890548) (xy 86.25415 -15.938098) (xy 86.21177 -15.980478) (xy 86.16422 -16.016965)
			(xy 86.112314 -16.046932) (xy 86.056941 -16.069868) (xy 85.999048 -16.085381) (xy 85.939626 -16.093204)
			(xy 85.87969 -16.093204) (xy 85.820268 -16.085381) (xy 85.762375 -16.069868) (xy 85.707002 -16.046932)
			(xy 85.655096 -16.016965) (xy 85.607546 -15.980478) (xy 85.565166 -15.938098) (xy 85.528679 -15.890548)
			(xy 85.498712 -15.838642) (xy 85.475776 -15.783269) (xy 85.460263 -15.725376) (xy 85.45244 -15.665954)
			(xy 37.41166 -15.665954) (xy 37.41166 -16.659707) (xy 64.532756 -16.659707) (xy 64.532756 -16.588385)
			(xy 64.540742 -16.517511) (xy 64.556612 -16.447976) (xy 64.580169 -16.380656) (xy 64.611114 -16.316397)
			(xy 64.64906 -16.256006) (xy 64.693529 -16.200244) (xy 64.743962 -16.149811) (xy 64.799724 -16.105342)
			(xy 64.860115 -16.067396) (xy 64.924374 -16.036451) (xy 64.991694 -16.012894) (xy 65.061229 -15.997024)
			(xy 65.132103 -15.989038) (xy 65.167764 -15.988538) (xy 65.203425 -15.989038) (xy 65.274299 -15.997024)
			(xy 65.343834 -16.012894) (xy 65.411154 -16.036451) (xy 65.475413 -16.067396) (xy 65.535804 -16.105342)
			(xy 65.591566 -16.149811) (xy 65.641999 -16.200244) (xy 65.686468 -16.256006) (xy 65.724414 -16.316397)
			(xy 65.755359 -16.380656) (xy 65.778916 -16.447976) (xy 65.794786 -16.517511) (xy 65.802772 -16.588385)
			(xy 65.802772 -16.659707) (xy 66.447408 -16.659707) (xy 66.447408 -16.588385) (xy 66.455394 -16.517511)
			(xy 66.471264 -16.447976) (xy 66.494821 -16.380656) (xy 66.525766 -16.316397) (xy 66.563712 -16.256006)
			(xy 66.608181 -16.200244) (xy 66.658614 -16.149811) (xy 66.714376 -16.105342) (xy 66.774767 -16.067396)
			(xy 66.839026 -16.036451) (xy 66.906346 -16.012894) (xy 66.975881 -15.997024) (xy 67.046755 -15.989038)
			(xy 67.082416 -15.988538) (xy 67.118077 -15.989038) (xy 67.188951 -15.997024) (xy 67.258486 -16.012894)
			(xy 67.325806 -16.036451) (xy 67.390065 -16.067396) (xy 67.450456 -16.105342) (xy 67.506218 -16.149811)
			(xy 67.556651 -16.200244) (xy 67.60112 -16.256006) (xy 67.639066 -16.316397) (xy 67.670011 -16.380656)
			(xy 67.693568 -16.447976) (xy 67.709438 -16.517511) (xy 67.717424 -16.588385) (xy 67.717424 -16.659707)
			(xy 68.34428 -16.659707) (xy 68.34428 -16.588385) (xy 68.352266 -16.517511) (xy 68.368136 -16.447976)
			(xy 68.391693 -16.380656) (xy 68.422638 -16.316397) (xy 68.460584 -16.256006) (xy 68.505053 -16.200244)
			(xy 68.555486 -16.149811) (xy 68.611248 -16.105342) (xy 68.671639 -16.067396) (xy 68.735898 -16.036451)
			(xy 68.803218 -16.012894) (xy 68.872753 -15.997024) (xy 68.943627 -15.989038) (xy 68.979288 -15.988538)
			(xy 69.014949 -15.989038) (xy 69.085823 -15.997024) (xy 69.155358 -16.012894) (xy 69.222678 -16.036451)
			(xy 69.286937 -16.067396) (xy 69.347328 -16.105342) (xy 69.40309 -16.149811) (xy 69.453523 -16.200244)
			(xy 69.497992 -16.256006) (xy 69.535938 -16.316397) (xy 69.566883 -16.380656) (xy 69.59044 -16.447976)
			(xy 69.60631 -16.517511) (xy 69.614296 -16.588385) (xy 69.614296 -16.659707) (xy 70.422508 -16.659707)
			(xy 70.422508 -16.588385) (xy 70.430494 -16.517511) (xy 70.446364 -16.447976) (xy 70.469921 -16.380656)
			(xy 70.500866 -16.316397) (xy 70.538812 -16.256006) (xy 70.583281 -16.200244) (xy 70.633714 -16.149811)
			(xy 70.689476 -16.105342) (xy 70.749867 -16.067396) (xy 70.814126 -16.036451) (xy 70.881446 -16.012894)
			(xy 70.950981 -15.997024) (xy 71.021855 -15.989038) (xy 71.057516 -15.988538) (xy 71.093177 -15.989038)
			(xy 71.164051 -15.997024) (xy 71.233586 -16.012894) (xy 71.300906 -16.036451) (xy 71.365165 -16.067396)
			(xy 71.425556 -16.105342) (xy 71.481318 -16.149811) (xy 71.531751 -16.200244) (xy 71.57622 -16.256006)
			(xy 71.614166 -16.316397) (xy 71.645111 -16.380656) (xy 71.668668 -16.447976) (xy 71.684538 -16.517511)
			(xy 71.692524 -16.588385) (xy 71.692524 -16.659707) (xy 72.5429 -16.659707) (xy 72.5429 -16.588385)
			(xy 72.550886 -16.517511) (xy 72.566756 -16.447976) (xy 72.590313 -16.380656) (xy 72.621258 -16.316397)
			(xy 72.659204 -16.256006) (xy 72.703673 -16.200244) (xy 72.754106 -16.149811) (xy 72.809868 -16.105342)
			(xy 72.870259 -16.067396) (xy 72.934518 -16.036451) (xy 73.001838 -16.012894) (xy 73.071373 -15.997024)
			(xy 73.142247 -15.989038) (xy 73.177908 -15.988538) (xy 73.213569 -15.989038) (xy 73.284443 -15.997024)
			(xy 73.353978 -16.012894) (xy 73.421298 -16.036451) (xy 73.485557 -16.067396) (xy 73.545948 -16.105342)
			(xy 73.60171 -16.149811) (xy 73.652143 -16.200244) (xy 73.696612 -16.256006) (xy 73.734558 -16.316397)
			(xy 73.765503 -16.380656) (xy 73.78906 -16.447976) (xy 73.80493 -16.517511) (xy 73.812916 -16.588385)
			(xy 73.812916 -16.659707) (xy 73.80493 -16.730581) (xy 73.78906 -16.800116) (xy 73.765503 -16.867436)
			(xy 73.734558 -16.931695) (xy 73.696612 -16.992086) (xy 73.652143 -17.047848) (xy 73.60171 -17.098281)
			(xy 73.545948 -17.14275) (xy 73.485557 -17.180696) (xy 73.421298 -17.211641) (xy 73.353978 -17.235198)
			(xy 73.284443 -17.251068) (xy 73.213569 -17.259054) (xy 73.142247 -17.259054) (xy 73.071373 -17.251068)
			(xy 73.001838 -17.235198) (xy 72.934518 -17.211641) (xy 72.870259 -17.180696) (xy 72.809868 -17.14275)
			(xy 72.754106 -17.098281) (xy 72.703673 -17.047848) (xy 72.659204 -16.992086) (xy 72.621258 -16.931695)
			(xy 72.590313 -16.867436) (xy 72.566756 -16.800116) (xy 72.550886 -16.730581) (xy 72.5429 -16.659707)
			(xy 71.692524 -16.659707) (xy 71.684538 -16.730581) (xy 71.668668 -16.800116) (xy 71.645111 -16.867436)
			(xy 71.614166 -16.931695) (xy 71.57622 -16.992086) (xy 71.531751 -17.047848) (xy 71.481318 -17.098281)
			(xy 71.425556 -17.14275) (xy 71.365165 -17.180696) (xy 71.300906 -17.211641) (xy 71.233586 -17.235198)
			(xy 71.164051 -17.251068) (xy 71.093177 -17.259054) (xy 71.021855 -17.259054) (xy 70.950981 -17.251068)
			(xy 70.881446 -17.235198) (xy 70.814126 -17.211641) (xy 70.749867 -17.180696) (xy 70.689476 -17.14275)
			(xy 70.633714 -17.098281) (xy 70.583281 -17.047848) (xy 70.538812 -16.992086) (xy 70.500866 -16.931695)
			(xy 70.469921 -16.867436) (xy 70.446364 -16.800116) (xy 70.430494 -16.730581) (xy 70.422508 -16.659707)
			(xy 69.614296 -16.659707) (xy 69.60631 -16.730581) (xy 69.59044 -16.800116) (xy 69.566883 -16.867436)
			(xy 69.535938 -16.931695) (xy 69.497992 -16.992086) (xy 69.453523 -17.047848) (xy 69.40309 -17.098281)
			(xy 69.347328 -17.14275) (xy 69.286937 -17.180696) (xy 69.222678 -17.211641) (xy 69.155358 -17.235198)
			(xy 69.085823 -17.251068) (xy 69.014949 -17.259054) (xy 68.943627 -17.259054) (xy 68.872753 -17.251068)
			(xy 68.803218 -17.235198) (xy 68.735898 -17.211641) (xy 68.671639 -17.180696) (xy 68.611248 -17.14275)
			(xy 68.555486 -17.098281) (xy 68.505053 -17.047848) (xy 68.460584 -16.992086) (xy 68.422638 -16.931695)
			(xy 68.391693 -16.867436) (xy 68.368136 -16.800116) (xy 68.352266 -16.730581) (xy 68.34428 -16.659707)
			(xy 67.717424 -16.659707) (xy 67.709438 -16.730581) (xy 67.693568 -16.800116) (xy 67.670011 -16.867436)
			(xy 67.639066 -16.931695) (xy 67.60112 -16.992086) (xy 67.556651 -17.047848) (xy 67.506218 -17.098281)
			(xy 67.450456 -17.14275) (xy 67.390065 -17.180696) (xy 67.325806 -17.211641) (xy 67.258486 -17.235198)
			(xy 67.188951 -17.251068) (xy 67.118077 -17.259054) (xy 67.046755 -17.259054) (xy 66.975881 -17.251068)
			(xy 66.906346 -17.235198) (xy 66.839026 -17.211641) (xy 66.774767 -17.180696) (xy 66.714376 -17.14275)
			(xy 66.658614 -17.098281) (xy 66.608181 -17.047848) (xy 66.563712 -16.992086) (xy 66.525766 -16.931695)
			(xy 66.494821 -16.867436) (xy 66.471264 -16.800116) (xy 66.455394 -16.730581) (xy 66.447408 -16.659707)
			(xy 65.802772 -16.659707) (xy 65.794786 -16.730581) (xy 65.778916 -16.800116) (xy 65.755359 -16.867436)
			(xy 65.724414 -16.931695) (xy 65.686468 -16.992086) (xy 65.641999 -17.047848) (xy 65.591566 -17.098281)
			(xy 65.535804 -17.14275) (xy 65.475413 -17.180696) (xy 65.411154 -17.211641) (xy 65.343834 -17.235198)
			(xy 65.274299 -17.251068) (xy 65.203425 -17.259054) (xy 65.132103 -17.259054) (xy 65.061229 -17.251068)
			(xy 64.991694 -17.235198) (xy 64.924374 -17.211641) (xy 64.860115 -17.180696) (xy 64.799724 -17.14275)
			(xy 64.743962 -17.098281) (xy 64.693529 -17.047848) (xy 64.64906 -16.992086) (xy 64.611114 -16.931695)
			(xy 64.580169 -16.867436) (xy 64.556612 -16.800116) (xy 64.540742 -16.730581) (xy 64.532756 -16.659707)
			(xy 37.41166 -16.659707) (xy 37.41166 -17.322292) (xy 36.991115 -17.742916) (xy 50.87366 -17.742916)
			(xy 52.525676 -17.742916) (xy 52.525676 -19.394424) (xy 50.87366 -19.394424) (xy 50.87366 -17.742916)
			(xy 36.991115 -17.742916) (xy 36.055046 -18.67916) (xy 36.039794 -18.69508) (xy 36.014473 -18.731167)
			(xy 35.995761 -18.771083) (xy 35.984221 -18.81363) (xy 35.9802 -18.85753) (xy 35.983817 -18.901466)
			(xy 35.994965 -18.944117) (xy 36.013309 -18.984203) (xy 36.038297 -19.020521) (xy 36.06918 -19.05198)
			(xy 36.086796 -19.06524) (xy 36.121477 -19.09064) (xy 36.186542 -19.146834) (xy 36.246205 -19.208731)
			(xy 36.299969 -19.275816) (xy 36.347385 -19.347529) (xy 36.388058 -19.423271) (xy 36.421646 -19.502409)
			(xy 36.447871 -19.584283) (xy 36.466512 -19.668209) (xy 36.477415 -19.753486) (xy 36.480488 -19.839402)
			(xy 36.475706 -19.92524) (xy 36.463108 -20.010283) (xy 36.450922 -20.060411) (xy 86.399122 -20.060411)
			(xy 86.401115 -19.860283) (xy 86.411112 -19.660394) (xy 86.429099 -19.461066) (xy 86.455047 -19.262617)
			(xy 86.488914 -19.065365) (xy 86.530646 -18.869626) (xy 86.580175 -18.675713) (xy 86.637424 -18.483938)
			(xy 86.702299 -18.294606) (xy 86.774698 -18.108022) (xy 86.854504 -17.924483) (xy 86.941589 -17.744285)
			(xy 87.035814 -17.567715) (xy 87.137028 -17.395056) (xy 87.245069 -17.226586) (xy 87.359764 -17.062572)
			(xy 87.48093 -16.903279) (xy 87.608371 -16.748962) (xy 87.741885 -16.599866) (xy 87.881257 -16.456232)
			(xy 88.026264 -16.31829) (xy 88.176675 -16.186259) (xy 88.332247 -16.060352) (xy 88.492732 -15.94077)
			(xy 88.657873 -15.827705) (xy 88.827405 -15.721337) (xy 89.001058 -15.621838) (xy 89.178552 -15.529366)
			(xy 89.359604 -15.44407) (xy 89.543924 -15.366086) (xy 89.731216 -15.295538) (xy 89.921181 -15.232541)
			(xy 90.113514 -15.177195) (xy 90.307908 -15.129588) (xy 90.504051 -15.089797) (xy 90.701628 -15.057885)
			(xy 90.900325 -15.033904) (xy 91.099821 -15.017891) (xy 91.299799 -15.009874) (xy 91.399868 -15.009368)
			(xy 91.499937 -15.009864) (xy 91.699915 -15.017861) (xy 91.899414 -15.033853) (xy 92.098112 -15.057814)
			(xy 92.295693 -15.089706) (xy 92.49184 -15.129477) (xy 92.686239 -15.177064) (xy 92.878578 -15.232391)
			(xy 93.068549 -15.295369) (xy 93.255848 -15.365897) (xy 93.440176 -15.443863) (xy 93.621237 -15.529141)
			(xy 93.79874 -15.621594) (xy 93.972403 -15.721076) (xy 94.141946 -15.827426) (xy 94.307099 -15.940475)
			(xy 94.467596 -16.06004) (xy 94.623181 -16.185932) (xy 94.773605 -16.317947) (xy 94.918626 -16.455875)
			(xy 95.058012 -16.599495) (xy 95.191541 -16.748576) (xy 95.242466 -16.810228) (xy 97.324939 -16.810228)
			(xy 97.3289 -16.69678) (xy 97.340766 -16.583884) (xy 97.360478 -16.472091) (xy 97.387941 -16.361945)
			(xy 97.423019 -16.253984) (xy 97.465544 -16.148732) (xy 97.515307 -16.046703) (xy 97.572065 -15.948394)
			(xy 97.635544 -15.854284) (xy 97.705432 -15.764831) (xy 97.78139 -15.680471) (xy 97.863048 -15.601615)
			(xy 97.950007 -15.528647) (xy 98.041845 -15.461923) (xy 98.138113 -15.401768) (xy 98.238343 -15.348475)
			(xy 98.342047 -15.302303) (xy 98.448718 -15.263478) (xy 98.557838 -15.232188) (xy 98.668875 -15.208586)
			(xy 98.781288 -15.192788) (xy 98.894529 -15.184869) (xy 98.951288 -15.184374) (xy 99.008047 -15.184869)
			(xy 99.121288 -15.192788) (xy 99.233701 -15.208586) (xy 99.344738 -15.232188) (xy 99.453858 -15.263478)
			(xy 99.560529 -15.302303) (xy 99.664233 -15.348475) (xy 99.764463 -15.401768) (xy 99.860731 -15.461923)
			(xy 99.952569 -15.528647) (xy 100.039528 -15.601615) (xy 100.121186 -15.680471) (xy 100.197144 -15.764831)
			(xy 100.267032 -15.854284) (xy 100.330511 -15.948394) (xy 100.387269 -16.046703) (xy 100.437032 -16.148732)
			(xy 100.479557 -16.253984) (xy 100.514635 -16.361945) (xy 100.542098 -16.472091) (xy 100.56181 -16.583884)
			(xy 100.573676 -16.69678) (xy 100.577638 -16.810228) (xy 100.573676 -16.923676) (xy 100.56181 -17.036572)
			(xy 100.542098 -17.148365) (xy 100.514635 -17.258511) (xy 100.479557 -17.366472) (xy 100.437032 -17.471724)
			(xy 100.387269 -17.573753) (xy 100.330511 -17.672062) (xy 100.267032 -17.766172) (xy 100.197144 -17.855625)
			(xy 100.121186 -17.939985) (xy 100.039528 -18.018841) (xy 99.952569 -18.091809) (xy 99.860731 -18.158533)
			(xy 99.764463 -18.218688) (xy 99.664233 -18.271981) (xy 99.560529 -18.318153) (xy 99.453858 -18.356978)
			(xy 99.344738 -18.388268) (xy 99.233701 -18.41187) (xy 99.121288 -18.427668) (xy 99.008047 -18.435587)
			(xy 98.894529 -18.435587) (xy 98.781288 -18.427668) (xy 98.668875 -18.41187) (xy 98.557838 -18.388268)
			(xy 98.448718 -18.356978) (xy 98.342047 -18.318153) (xy 98.238343 -18.271981) (xy 98.138113 -18.218688)
			(xy 98.041845 -18.158533) (xy 97.950007 -18.091809) (xy 97.863048 -18.018841) (xy 97.78139 -17.939985)
			(xy 97.705432 -17.855625) (xy 97.635544 -17.766172) (xy 97.572065 -17.672062) (xy 97.515307 -17.573753)
			(xy 97.465544 -17.471724) (xy 97.423019 -17.366472) (xy 97.387941 -17.258511) (xy 97.360478 -17.148365)
			(xy 97.340766 -17.036572) (xy 97.3289 -16.923676) (xy 97.324939 -16.810228) (xy 95.242466 -16.810228)
			(xy 95.318999 -16.902881) (xy 95.44018 -17.062162) (xy 95.554892 -17.226163) (xy 95.66295 -17.394623)
			(xy 95.764182 -17.567272) (xy 95.858425 -17.743832) (xy 95.945528 -17.924022) (xy 96.025353 -18.107552)
			(xy 96.09777 -18.294129) (xy 96.162665 -18.483454) (xy 96.219933 -18.675224) (xy 96.269483 -18.869131)
			(xy 96.311234 -19.064866) (xy 96.345121 -19.262115) (xy 96.371089 -19.460561) (xy 96.379088 -19.549106)
			(xy 97.973878 -19.549106) (xy 97.973878 -19.48917) (xy 97.981701 -19.429748) (xy 97.997214 -19.371855)
			(xy 98.02015 -19.316482) (xy 98.050117 -19.264576) (xy 98.086604 -19.217026) (xy 98.128984 -19.174646)
			(xy 98.176534 -19.138159) (xy 98.22844 -19.108192) (xy 98.283813 -19.085256) (xy 98.341706 -19.069743)
			(xy 98.401128 -19.06192) (xy 98.431096 -19.06143) (xy 98.461064 -19.06192) (xy 98.520486 -19.069743)
			(xy 98.578379 -19.085256) (xy 98.633752 -19.108192) (xy 98.685658 -19.138159) (xy 98.733208 -19.174646)
			(xy 98.775588 -19.217026) (xy 98.812075 -19.264576) (xy 98.842042 -19.316482) (xy 98.864978 -19.371855)
			(xy 98.880491 -19.429748) (xy 98.888314 -19.48917) (xy 98.888314 -19.549106) (xy 98.880491 -19.608528)
			(xy 98.864978 -19.666421) (xy 98.842042 -19.721794) (xy 98.812075 -19.7737) (xy 98.775588 -19.82125)
			(xy 98.733208 -19.86363) (xy 98.685658 -19.900117) (xy 98.633752 -19.930084) (xy 98.578379 -19.95302)
			(xy 98.520486 -19.968533) (xy 98.461064 -19.976356) (xy 98.401128 -19.976356) (xy 98.341706 -19.968533)
			(xy 98.283813 -19.95302) (xy 98.22844 -19.930084) (xy 98.176534 -19.900117) (xy 98.128984 -19.86363)
			(xy 98.086604 -19.82125) (xy 98.050117 -19.7737) (xy 98.02015 -19.721794) (xy 97.997214 -19.666421)
			(xy 97.981701 -19.608528) (xy 97.973878 -19.549106) (xy 96.379088 -19.549106) (xy 96.389096 -19.659888)
			(xy 96.399114 -19.859775) (xy 96.401127 -20.059903) (xy 96.395131 -20.259951) (xy 96.381135 -20.4596)
			(xy 96.359164 -20.658528) (xy 96.32925 -20.856418) (xy 96.291443 -21.052953) (xy 96.245804 -21.247818)
			(xy 96.192404 -21.440701) (xy 96.13133 -21.631293) (xy 96.062679 -21.819288) (xy 95.986561 -22.004387)
			(xy 95.903099 -22.186292) (xy 95.812426 -22.364711) (xy 95.714687 -22.539361) (xy 95.610038 -22.70996)
			(xy 95.498648 -22.876235) (xy 95.380694 -23.03792) (xy 95.256365 -23.194757) (xy 95.125862 -23.346494)
			(xy 94.989391 -23.492888) (xy 94.847173 -23.633704) (xy 94.699435 -23.768718) (xy 94.546413 -23.897713)
			(xy 94.388353 -24.020482) (xy 94.225507 -24.136829) (xy 94.058137 -24.246567) (xy 93.88651 -24.349521)
			(xy 93.710902 -24.445526) (xy 93.531592 -24.534428) (xy 93.34887 -24.616084) (xy 93.163027 -24.690365)
			(xy 92.97436 -24.757151) (xy 92.783173 -24.816334) (xy 92.589771 -24.867821) (xy 92.394464 -24.911529)
			(xy 92.197564 -24.947388) (xy 91.999387 -24.97534) (xy 91.800251 -24.99534) (xy 91.600474 -25.007358)
			(xy 91.400376 -25.011372) (xy 91.200278 -25.007378) (xy 91.000499 -24.995381) (xy 90.801361 -24.975401)
			(xy 90.603182 -24.947469) (xy 90.406278 -24.91163) (xy 90.210967 -24.867942) (xy 90.017559 -24.816475)
			(xy 89.826366 -24.757311) (xy 89.637693 -24.690544) (xy 89.451842 -24.616282) (xy 89.269111 -24.534644)
			(xy 89.089793 -24.445761) (xy 88.914175 -24.349774) (xy 88.742537 -24.246837) (xy 88.575156 -24.137116)
			(xy 88.412298 -24.020785) (xy 88.254226 -23.898032) (xy 88.101191 -23.769053) (xy 87.953439 -23.634055)
			(xy 87.811206 -23.493252) (xy 87.674721 -23.346872) (xy 87.544202 -23.195149) (xy 87.419858 -23.038325)
			(xy 87.301888 -22.876651) (xy 87.19048 -22.710387) (xy 87.085814 -22.539799) (xy 86.988057 -22.36516)
			(xy 86.897366 -22.186749) (xy 86.813885 -22.004853) (xy 86.737749 -21.819762) (xy 86.669079 -21.631773)
			(xy 86.607986 -21.441188) (xy 86.554566 -21.24831) (xy 86.508906 -21.05345) (xy 86.47108 -20.856919)
			(xy 86.441146 -20.659032) (xy 86.419154 -20.460106) (xy 86.405139 -20.260459) (xy 86.399122 -20.060411)
			(xy 36.450922 -20.060411) (xy 36.4428 -20.093821) (xy 36.414952 -20.175157) (xy 36.379795 -20.253611)
			(xy 36.337624 -20.328528) (xy 36.28879 -20.399283) (xy 36.233701 -20.465285) (xy 36.172818 -20.525983)
			(xy 36.106648 -20.580871) (xy 36.035745 -20.629489) (xy 35.960699 -20.671431) (xy 35.882138 -20.706349)
			(xy 35.800718 -20.73395) (xy 35.717119 -20.754003) (xy 35.632038 -20.766341) (xy 35.546185 -20.770862)
			(xy 35.460279 -20.767527) (xy 35.375036 -20.756365) (xy 35.291167 -20.737468) (xy 35.209374 -20.710994)
			(xy 35.130338 -20.677164) (xy 35.054721 -20.636262) (xy 34.983153 -20.588627) (xy 34.916232 -20.534659)
			(xy 34.854516 -20.474807) (xy 34.798521 -20.409572) (xy 34.748715 -20.339498) (xy 34.705514 -20.26517)
			(xy 34.669277 -20.187209) (xy 34.640308 -20.106265) (xy 34.618849 -20.023016) (xy 34.605078 -19.938155)
			(xy 34.599111 -19.852391) (xy 34.600998 -19.766441) (xy 34.610722 -19.681021) (xy 34.628203 -19.596846)
			(xy 34.653294 -19.514618) (xy 34.685787 -19.435024) (xy 34.725409 -19.358728) (xy 34.748216 -19.322288)
			(xy 34.760045 -19.302927) (xy 34.777377 -19.261002) (xy 34.786992 -19.216665) (xy 34.788584 -19.171327)
			(xy 34.782102 -19.126426) (xy 34.767753 -19.083388) (xy 34.745992 -19.043581) (xy 34.717511 -19.008269)
			(xy 34.683214 -18.978573) (xy 34.64419 -18.955437) (xy 34.601679 -18.939595) (xy 34.557031 -18.931552)
			(xy 34.534348 -18.931128) (xy 31.465012 -18.931128) (xy 31.442339 -18.931634) (xy 31.397714 -18.939695)
			(xy 31.355227 -18.955544) (xy 31.316226 -18.97868) (xy 31.281949 -19.008368) (xy 31.253482 -19.043667)
			(xy 31.231729 -19.083456) (xy 31.217381 -19.126473) (xy 31.210891 -19.171353) (xy 31.212467 -19.216672)
			(xy 31.222059 -19.260993) (xy 31.239361 -19.30291) (xy 31.251144 -19.322288) (xy 31.274361 -19.359407)
			(xy 31.314583 -19.437178) (xy 31.347401 -19.518352) (xy 31.372531 -19.602225) (xy 31.389756 -19.688071)
			(xy 31.398925 -19.775146) (xy 31.399961 -19.862697) (xy 31.392853 -19.949965) (xy 31.377663 -20.036194)
			(xy 31.354523 -20.120638) (xy 31.323633 -20.202565) (xy 31.285261 -20.281266) (xy 31.23974 -20.356059)
			(xy 31.187462 -20.426296) (xy 31.128881 -20.491369) (xy 31.064505 -20.550715) (xy 30.994891 -20.603819)
			(xy 30.920642 -20.650222) (xy 30.8424 -20.689522) (xy 30.760844 -20.721378) (xy 30.67668 -20.745515)
			(xy 30.590636 -20.761723) (xy 30.503458 -20.769863) (xy 30.415902 -20.769863) (xy 30.328724 -20.761723)
			(xy 30.24268 -20.745515) (xy 30.158516 -20.721378) (xy 30.07696 -20.689522) (xy 29.998718 -20.650222)
			(xy 29.924469 -20.603819) (xy 29.854855 -20.550715) (xy 29.790479 -20.491369) (xy 29.731898 -20.426296)
			(xy 29.67962 -20.356059) (xy 29.634099 -20.281266) (xy 29.595727 -20.202565) (xy 29.564837 -20.120638)
			(xy 29.541697 -20.036194) (xy 29.526507 -19.949965) (xy 29.519399 -19.862697) (xy 29.520435 -19.775146)
			(xy 29.529604 -19.688071) (xy 29.546829 -19.602225) (xy 29.571959 -19.518352) (xy 29.604777 -19.437178)
			(xy 29.644999 -19.359407) (xy 29.668216 -19.322288) (xy 29.680045 -19.302927) (xy 29.697377 -19.261002)
			(xy 29.706992 -19.216665) (xy 29.708584 -19.171327) (xy 29.702102 -19.126426) (xy 29.687753 -19.083388)
			(xy 29.665992 -19.043581) (xy 29.637511 -19.008269) (xy 29.603214 -18.978573) (xy 29.56419 -18.955437)
			(xy 29.521679 -18.939595) (xy 29.477031 -18.931552) (xy 29.454348 -18.931128) (xy 28.303982 -18.931128)
			(xy 26.039064 -21.196046) (xy 26.039064 -83.78444) (xy 34.548318 -92.29344) (xy 34.563919 -92.308458)
			(xy 34.599258 -92.333481) (xy 34.63833 -92.352146) (xy 34.680003 -92.36391) (xy 34.723068 -92.368433)
			(xy 34.766275 -92.365584) (xy 34.808373 -92.355445) (xy 34.848139 -92.33831) (xy 34.884422 -92.314676)
			(xy 34.900616 -92.300298) (xy 34.93259 -92.271335) (xy 35.000981 -92.218739) (xy 35.073902 -92.17263)
			(xy 35.150741 -92.133395) (xy 35.230852 -92.101364) (xy 35.31356 -92.076807) (xy 35.398169 -92.05993)
			(xy 35.48397 -92.050875) (xy 35.570238 -92.049719) (xy 35.65625 -92.05647) (xy 35.741282 -92.071073)
			(xy 35.824619 -92.093405) (xy 35.905559 -92.123277) (xy 35.983422 -92.160438) (xy 36.057553 -92.204577)
			(xy 36.127329 -92.255321) (xy 36.192163 -92.312244) (xy 36.251509 -92.374867) (xy 36.304869 -92.442663)
			(xy 36.351794 -92.515063) (xy 36.391889 -92.591457) (xy 36.424816 -92.671203) (xy 36.450299 -92.753631)
			(xy 36.468124 -92.838046) (xy 36.478141 -92.923739) (xy 36.480265 -93.009989) (xy 36.474478 -93.096072)
			(xy 36.46083 -93.181262) (xy 36.439435 -93.264844) (xy 36.425378 -93.30563) (xy 36.419964 -93.322731)
			(xy 36.417846 -93.358523) (xy 36.425756 -93.393494) (xy 36.443069 -93.424892) (xy 36.45535 -93.437964)
			(xy 37.232082 -94.21495) (xy 37.248726 -94.230884) (xy 37.286644 -94.257053) (xy 37.328658 -94.27596)
			(xy 37.373391 -94.286986) (xy 37.419379 -94.289769) (xy 37.465115 -94.284218) (xy 37.509103 -94.270515)
			(xy 37.5499 -94.249109) (xy 37.586171 -94.220701) (xy 37.616728 -94.18622) (xy 37.640571 -94.146798)
			(xy 37.656918 -94.103723) (xy 37.665234 -94.058408) (xy 37.66566 -94.035372) (xy 37.66566 -93.228414)
			(xy 35.013138 -90.575892) (xy 33.252664 -90.575892) (xy 26.461212 -83.78444) (xy 26.461212 -23.90648)
			(xy 26.749248 -23.618698) (xy 26.749248 -21.632926) (xy 26.749765 -21.601312) (xy 26.758018 -21.538625)
			(xy 26.774382 -21.477551) (xy 26.798579 -21.419136) (xy 26.830193 -21.364379) (xy 26.868684 -21.314217)
			(xy 26.913393 -21.269508) (xy 26.963555 -21.231017) (xy 27.018312 -21.199403) (xy 27.076727 -21.175206)
			(xy 27.137801 -21.158842) (xy 27.200488 -21.150589) (xy 27.263716 -21.150589) (xy 27.326403 -21.158842)
			(xy 27.387477 -21.175206) (xy 27.445892 -21.199403) (xy 27.500649 -21.231017) (xy 27.550811 -21.269508)
			(xy 27.59552 -21.314217) (xy 27.634011 -21.364379) (xy 27.665625 -21.419136) (xy 27.689822 -21.477551)
			(xy 27.706186 -21.538625) (xy 27.714439 -21.601312) (xy 27.714956 -21.632926) (xy 27.714956 -23.530814)
			(xy 27.715467 -23.553858) (xy 27.723793 -23.599189) (xy 27.740153 -23.642277) (xy 27.76401 -23.681711)
			(xy 27.794583 -23.7162) (xy 27.830871 -23.744614) (xy 27.871686 -23.766023) (xy 27.915691 -23.779726)
			(xy 27.961445 -23.785273) (xy 28.00745 -23.782485) (xy 28.052199 -23.771451) (xy 28.094226 -23.752533)
			(xy 28.132156 -23.72635) (xy 28.148788 -23.710392) (xy 28.684728 -23.174452) (xy 29.399738 -23.174452)
			(xy 29.421451 -23.174014) (xy 29.464247 -23.16664) (xy 29.505166 -23.152095) (xy 29.543015 -23.130804)
			(xy 29.576692 -23.103386) (xy 29.605217 -23.070641) (xy 29.627757 -23.033522) (xy 29.643656 -22.99311)
			(xy 29.652452 -22.950584) (xy 29.653888 -22.907181) (xy 29.647922 -22.864166) (xy 29.634728 -22.822792)
			(xy 29.625036 -22.803358) (xy 29.605293 -22.764238) (xy 29.572325 -22.683044) (xy 29.547053 -22.599134)
			(xy 29.529698 -22.513237) (xy 29.520409 -22.426098) (xy 29.519266 -22.338473) (xy 29.526281 -22.251121)
			(xy 29.541392 -22.164801) (xy 29.564467 -22.080261) (xy 29.595308 -21.998235) (xy 29.633646 -21.919433)
			(xy 29.679148 -21.84454) (xy 29.731421 -21.774204) (xy 29.790011 -21.709037) (xy 29.854409 -21.649603)
			(xy 29.924057 -21.596418) (xy 29.99835 -21.549943) (xy 30.076646 -21.510582) (xy 30.158263 -21.478674)
			(xy 30.242495 -21.454499) (xy 30.328611 -21.438264) (xy 30.415864 -21.430112) (xy 30.503496 -21.430112)
			(xy 30.590749 -21.438264) (xy 30.676865 -21.454499) (xy 30.761097 -21.478674) (xy 30.842714 -21.510582)
			(xy 30.92101 -21.549943) (xy 30.995303 -21.596418) (xy 31.064951 -21.649603) (xy 31.129349 -21.709037)
			(xy 31.187939 -21.774204) (xy 31.240212 -21.84454) (xy 31.285714 -21.919433) (xy 31.324052 -21.998235)
			(xy 31.354893 -22.080261) (xy 31.377968 -22.164801) (xy 31.393079 -22.251121) (xy 31.400094 -22.338473)
			(xy 31.398951 -22.426098) (xy 31.389662 -22.513237) (xy 31.372307 -22.599134) (xy 31.347035 -22.683044)
			(xy 31.314067 -22.764238) (xy 31.294324 -22.803358) (xy 31.284715 -22.822821) (xy 31.271549 -22.864179)
			(xy 31.265604 -22.907173) (xy 31.267053 -22.950551) (xy 31.275853 -22.993053) (xy 31.291749 -23.03344)
			(xy 31.314278 -23.070538) (xy 31.342784 -23.103267) (xy 31.376438 -23.130675) (xy 31.414261 -23.151965)
			(xy 31.455152 -23.166516) (xy 31.497921 -23.173906) (xy 31.519622 -23.174452) (xy 34.479738 -23.174452)
			(xy 34.501451 -23.174014) (xy 34.544247 -23.16664) (xy 34.585166 -23.152095) (xy 34.623015 -23.130804)
			(xy 34.656692 -23.103386) (xy 34.685217 -23.070641) (xy 34.707757 -23.033522) (xy 34.723656 -22.99311)
			(xy 34.732452 -22.950584) (xy 34.733888 -22.907181) (xy 34.727922 -22.864166) (xy 34.714728 -22.822792)
			(xy 34.705036 -22.803358) (xy 34.685293 -22.764238) (xy 34.652325 -22.683044) (xy 34.627053 -22.599134)
			(xy 34.609698 -22.513237) (xy 34.600409 -22.426098) (xy 34.599266 -22.338473) (xy 34.606281 -22.251121)
			(xy 34.621392 -22.164801) (xy 34.644467 -22.080261) (xy 34.675308 -21.998235) (xy 34.713646 -21.919433)
			(xy 34.759148 -21.84454) (xy 34.811421 -21.774204) (xy 34.870011 -21.709037) (xy 34.934409 -21.649603)
			(xy 35.004057 -21.596418) (xy 35.07835 -21.549943) (xy 35.156646 -21.510582) (xy 35.238263 -21.478674)
			(xy 35.322495 -21.454499) (xy 35.408611 -21.438264) (xy 35.495864 -21.430112) (xy 35.583496 -21.430112)
			(xy 35.670749 -21.438264) (xy 35.756865 -21.454499) (xy 35.841097 -21.478674) (xy 35.922714 -21.510582)
			(xy 36.00101 -21.549943) (xy 36.075303 -21.596418) (xy 36.144951 -21.649603) (xy 36.209349 -21.709037)
			(xy 36.267939 -21.774204) (xy 36.320212 -21.84454) (xy 36.365714 -21.919433) (xy 36.404052 -21.998235)
			(xy 36.434893 -22.080261) (xy 36.457968 -22.164801) (xy 36.473079 -22.251121) (xy 36.480094 -22.338473)
			(xy 36.478951 -22.426098) (xy 36.469662 -22.513237) (xy 36.452307 -22.599134) (xy 36.427035 -22.683044)
			(xy 36.394067 -22.764238) (xy 36.374324 -22.803358) (xy 36.364715 -22.822821) (xy 36.351549 -22.864179)
			(xy 36.345604 -22.907173) (xy 36.347053 -22.950551) (xy 36.355853 -22.993053) (xy 36.371749 -23.03344)
			(xy 36.394278 -23.070538) (xy 36.422784 -23.103267) (xy 36.456438 -23.130675) (xy 36.494261 -23.151965)
			(xy 36.535152 -23.166516) (xy 36.577921 -23.173906) (xy 36.599622 -23.174452) (xy 39.819834 -23.174452)
			(xy 40.150288 -22.843744) (xy 40.170811 -22.823831) (xy 40.215753 -22.788471) (xy 40.264557 -22.758666)
			(xy 40.31654 -22.734835) (xy 40.370974 -22.71731) (xy 40.398954 -22.71141) (xy 40.422333 -22.706236)
			(xy 40.46674 -22.688345) (xy 40.507019 -22.662466) (xy 40.541748 -22.629511) (xy 40.569702 -22.590644)
			(xy 40.589895 -22.547235) (xy 40.601615 -22.500816) (xy 40.604449 -22.453024) (xy 40.6019 -22.429216)
			(xy 40.599184 -22.405916) (xy 40.598783 -22.359008) (xy 40.604127 -22.312404) (xy 40.609266 -22.289516)
			(xy 40.614191 -22.267038) (xy 40.616781 -22.221098) (xy 40.611058 -22.175443) (xy 40.597209 -22.131564)
			(xy 40.575686 -22.090895) (xy 40.547193 -22.054766) (xy 40.512661 -22.024357) (xy 40.473219 -22.000661)
			(xy 40.430155 -21.984454) (xy 40.384877 -21.976265) (xy 40.36187 -21.975826) (xy 40.334067 -21.975394)
			(xy 40.279032 -21.967463) (xy 40.225732 -21.951627) (xy 40.175294 -21.928221) (xy 40.128789 -21.897742)
			(xy 40.0872 -21.860836) (xy 40.051409 -21.818283) (xy 40.022174 -21.770985) (xy 40.000115 -21.719945)
			(xy 39.985697 -21.666243) (xy 39.979228 -21.611017) (xy 39.980844 -21.555438) (xy 39.990511 -21.500681)
			(xy 40.008023 -21.447907) (xy 40.033011 -21.398235) (xy 40.064944 -21.352716) (xy 40.103147 -21.312314)
			(xy 40.146809 -21.277886) (xy 40.195007 -21.25016) (xy 40.246719 -21.229724) (xy 40.30085 -21.217011)
			(xy 40.356252 -21.212291) (xy 40.411753 -21.215662) (xy 40.466177 -21.227054) (xy 40.518371 -21.246226)
			(xy 40.567229 -21.27277) (xy 40.611716 -21.306126) (xy 40.65089 -21.345587) (xy 40.683922 -21.390315)
			(xy 40.710111 -21.439365) (xy 40.728902 -21.491697) (xy 40.739898 -21.546202) (xy 40.742866 -21.601726)
			(xy 40.737742 -21.657093) (xy 40.731694 -21.684234) (xy 40.726774 -21.706711) (xy 40.724193 -21.752646)
			(xy 40.729923 -21.798296) (xy 40.743776 -21.842169) (xy 40.765299 -21.882831) (xy 40.79379 -21.918956)
			(xy 40.828318 -21.949362) (xy 40.867755 -21.973056) (xy 40.910813 -21.989265) (xy 40.956085 -21.997459)
			(xy 40.97909 -21.997924) (xy 41.007138 -21.99836) (xy 41.062644 -22.006457) (xy 41.116366 -22.022595)
			(xy 41.167146 -22.046425) (xy 41.213888 -22.077435) (xy 41.255586 -22.114956) (xy 41.291339 -22.158179)
			(xy 41.320377 -22.206171) (xy 41.342075 -22.257898) (xy 41.355963 -22.312245) (xy 41.361743 -22.36804)
			(xy 41.35929 -22.42408) (xy 41.348657 -22.479157) (xy 41.330073 -22.532082) (xy 41.303939 -22.581716)
			(xy 41.270818 -22.626987) (xy 41.231425 -22.666921) (xy 41.186609 -22.700655) (xy 41.137336 -22.727462)
			(xy 41.11117 -22.737572) (xy 41.088872 -22.746332) (xy 41.04778 -22.770949) (xy 41.012026 -22.802827)
			(xy 40.982875 -22.840836) (xy 40.961358 -22.883634) (xy 40.948238 -22.929703) (xy 40.943979 -22.977415)
			(xy 40.948731 -23.02508) (xy 40.95496 -23.048214) (xy 40.963682 -23.079442) (xy 40.973647 -23.143509)
			(xy 40.974948 -23.208334) (xy 40.967562 -23.272749) (xy 40.951622 -23.335597) (xy 40.927414 -23.395746)
			(xy 40.895374 -23.452114) (xy 40.856078 -23.503687) (xy 40.833548 -23.527004) (xy 40.220138 -24.14016)
			(xy 29.085032 -24.14016) (xy 28.154884 -25.070562) (xy 28.154884 -29.381954) (xy 64.852532 -29.381954)
			(xy 64.852532 -29.322018) (xy 64.860355 -29.262596) (xy 64.875868 -29.204703) (xy 64.898804 -29.14933)
			(xy 64.928771 -29.097424) (xy 64.965258 -29.049874) (xy 65.007638 -29.007494) (xy 65.055188 -28.971007)
			(xy 65.107094 -28.94104) (xy 65.162467 -28.918104) (xy 65.22036 -28.902591) (xy 65.279782 -28.894768)
			(xy 65.30975 -28.894278) (xy 65.339718 -28.894768) (xy 65.39914 -28.902591) (xy 65.457033 -28.918104)
			(xy 65.512406 -28.94104) (xy 65.564312 -28.971007) (xy 65.611862 -29.007494) (xy 65.654242 -29.049874)
			(xy 65.690729 -29.097424) (xy 65.720696 -29.14933) (xy 65.743632 -29.204703) (xy 65.759145 -29.262596)
			(xy 65.766968 -29.322018) (xy 65.766968 -29.381954) (xy 65.759145 -29.441376) (xy 65.743632 -29.499269)
			(xy 65.720696 -29.554642) (xy 65.690729 -29.606548) (xy 65.654242 -29.654098) (xy 65.611862 -29.696478)
			(xy 65.564312 -29.732965) (xy 65.512406 -29.762932) (xy 65.457033 -29.785868) (xy 65.39914 -29.801381)
			(xy 65.339718 -29.809204) (xy 65.279782 -29.809204) (xy 65.22036 -29.801381) (xy 65.162467 -29.785868)
			(xy 65.107094 -29.762932) (xy 65.055188 -29.732965) (xy 65.007638 -29.696478) (xy 64.965258 -29.654098)
			(xy 64.928771 -29.606548) (xy 64.898804 -29.554642) (xy 64.875868 -29.499269) (xy 64.860355 -29.441376)
			(xy 64.852532 -29.381954) (xy 28.154884 -29.381954) (xy 28.154884 -32.612072) (xy 64.80732 -32.612072)
			(xy 64.80732 -32.552136) (xy 64.815143 -32.492714) (xy 64.830656 -32.434821) (xy 64.853592 -32.379448)
			(xy 64.883559 -32.327542) (xy 64.920046 -32.279992) (xy 64.962426 -32.237612) (xy 65.009976 -32.201125)
			(xy 65.061882 -32.171158) (xy 65.117255 -32.148222) (xy 65.175148 -32.132709) (xy 65.23457 -32.124886)
			(xy 65.264538 -32.124396) (xy 65.294506 -32.124886) (xy 65.353928 -32.132709) (xy 65.411821 -32.148222)
			(xy 65.467194 -32.171158) (xy 65.5191 -32.201125) (xy 65.56665 -32.237612) (xy 65.60903 -32.279992)
			(xy 65.645517 -32.327542) (xy 65.658452 -32.349947) (xy 72.999096 -32.349947) (xy 73.001098 -32.149819)
			(xy 73.011106 -31.949931) (xy 73.029103 -31.750604) (xy 73.055061 -31.552156) (xy 73.088938 -31.354906)
			(xy 73.13068 -31.159169) (xy 73.180219 -30.965259) (xy 73.237477 -30.773486) (xy 73.302362 -30.584157)
			(xy 73.37477 -30.397577) (xy 73.454586 -30.214042) (xy 73.54168 -30.033848) (xy 73.635914 -29.857283)
			(xy 73.737137 -29.68463) (xy 73.845187 -29.516165) (xy 73.95989 -29.352157) (xy 74.081064 -29.19287)
			(xy 74.208513 -29.038559) (xy 74.342034 -28.889471) (xy 74.481414 -28.745844) (xy 74.626428 -28.607908)
			(xy 74.776845 -28.475885) (xy 74.932423 -28.349986) (xy 75.092915 -28.230412) (xy 75.258061 -28.117356)
			(xy 75.427599 -28.010997) (xy 75.601257 -27.911506) (xy 75.778756 -27.819043) (xy 75.959812 -27.733756)
			(xy 76.144136 -27.655781) (xy 76.331432 -27.585244) (xy 76.5214 -27.522256) (xy 76.713736 -27.466919)
			(xy 76.908132 -27.419322) (xy 77.104277 -27.379541) (xy 77.301856 -27.347639) (xy 77.500553 -27.323668)
			(xy 77.700051 -27.307666) (xy 77.900029 -27.299659) (xy 78.000098 -27.299158) (xy 78.100167 -27.299659)
			(xy 78.300145 -27.307666) (xy 78.499643 -27.323668) (xy 78.69834 -27.347639) (xy 78.895919 -27.379541)
			(xy 79.092064 -27.419322) (xy 79.28646 -27.466919) (xy 79.478796 -27.522256) (xy 79.668764 -27.585244)
			(xy 79.85606 -27.655781) (xy 80.040384 -27.733756) (xy 80.22144 -27.819043) (xy 80.398939 -27.911506)
			(xy 80.572597 -28.010997) (xy 80.742135 -28.117356) (xy 80.907281 -28.230412) (xy 81.067773 -28.349986)
			(xy 81.223351 -28.475885) (xy 81.373768 -28.607908) (xy 81.518782 -28.745844) (xy 81.658162 -28.889471)
			(xy 81.791683 -29.038559) (xy 81.919132 -29.19287) (xy 82.040306 -29.352157) (xy 82.155009 -29.516165)
			(xy 82.263059 -29.68463) (xy 82.364282 -29.857283) (xy 82.458516 -30.033848) (xy 82.54561 -30.214042)
			(xy 82.625426 -30.397577) (xy 82.697834 -30.584157) (xy 82.762719 -30.773486) (xy 82.819977 -30.965259)
			(xy 82.869516 -31.159169) (xy 82.911258 -31.354906) (xy 82.945135 -31.552156) (xy 82.971093 -31.750604)
			(xy 82.98909 -31.949931) (xy 82.999098 -32.149819) (xy 83.0011 -32.349947) (xy 82.995094 -32.549995)
			(xy 82.981089 -32.749643) (xy 82.959107 -32.94857) (xy 82.929183 -33.146459) (xy 82.891366 -33.342992)
			(xy 82.845717 -33.537854) (xy 82.792307 -33.730734) (xy 82.731223 -33.921323) (xy 82.662563 -34.109315)
			(xy 82.586436 -34.29441) (xy 82.502965 -34.47631) (xy 82.412282 -34.654726) (xy 82.314534 -34.82937)
			(xy 82.209877 -34.999963) (xy 82.098478 -35.166233) (xy 81.980516 -35.327912) (xy 81.85618 -35.484743)
			(xy 81.725668 -35.636473) (xy 81.589191 -35.78286) (xy 81.446965 -35.923669) (xy 81.29922 -36.058676)
			(xy 81.146192 -36.187663) (xy 80.988125 -36.310424) (xy 80.825274 -36.426762) (xy 80.657898 -36.536492)
			(xy 80.486266 -36.639437) (xy 80.310652 -36.735433) (xy 80.131339 -36.824326) (xy 79.948612 -36.905973)
			(xy 79.762765 -36.980245) (xy 79.574095 -37.047021) (xy 79.382905 -37.106195) (xy 79.1895 -37.157672)
			(xy 78.994191 -37.20137) (xy 78.797289 -37.237218) (xy 78.599111 -37.26516) (xy 78.399974 -37.285151)
			(xy 78.200196 -37.297158) (xy 78.000098 -37.301163) (xy 77.8 -37.297158) (xy 77.600222 -37.285151)
			(xy 77.401085 -37.26516) (xy 77.202907 -37.237218) (xy 77.006005 -37.20137) (xy 76.810696 -37.157672)
			(xy 76.617291 -37.106195) (xy 76.426101 -37.047021) (xy 76.237431 -36.980245) (xy 76.051584 -36.905973)
			(xy 75.868857 -36.824326) (xy 75.689544 -36.735433) (xy 75.51393 -36.639437) (xy 75.342298 -36.536492)
			(xy 75.174922 -36.426762) (xy 75.012071 -36.310424) (xy 74.854004 -36.187663) (xy 74.700976 -36.058676)
			(xy 74.553231 -35.923669) (xy 74.411005 -35.78286) (xy 74.274528 -35.636473) (xy 74.144016 -35.484743)
			(xy 74.01968 -35.327912) (xy 73.901718 -35.166233) (xy 73.790319 -34.999963) (xy 73.685662 -34.82937)
			(xy 73.587914 -34.654726) (xy 73.497231 -34.47631) (xy 73.41376 -34.29441) (xy 73.337633 -34.109315)
			(xy 73.268973 -33.921323) (xy 73.207889 -33.730734) (xy 73.154479 -33.537854) (xy 73.10883 -33.342992)
			(xy 73.071013 -33.146459) (xy 73.041089 -32.94857) (xy 73.019107 -32.749643) (xy 73.005102 -32.549995)
			(xy 72.999096 -32.349947) (xy 65.658452 -32.349947) (xy 65.675484 -32.379448) (xy 65.69842 -32.434821)
			(xy 65.713933 -32.492714) (xy 65.721756 -32.552136) (xy 65.721756 -32.612072) (xy 65.713933 -32.671494)
			(xy 65.69842 -32.729387) (xy 65.675484 -32.78476) (xy 65.645517 -32.836666) (xy 65.60903 -32.884216)
			(xy 65.56665 -32.926596) (xy 65.5191 -32.963083) (xy 65.467194 -32.99305) (xy 65.411821 -33.015986)
			(xy 65.353928 -33.031499) (xy 65.294506 -33.039322) (xy 65.23457 -33.039322) (xy 65.175148 -33.031499)
			(xy 65.117255 -33.015986) (xy 65.061882 -32.99305) (xy 65.009976 -32.963083) (xy 64.962426 -32.926596)
			(xy 64.920046 -32.884216) (xy 64.883559 -32.836666) (xy 64.853592 -32.78476) (xy 64.830656 -32.729387)
			(xy 64.815143 -32.671494) (xy 64.80732 -32.612072) (xy 28.154884 -32.612072) (xy 28.154884 -37.794692)
			(xy 51.007772 -37.794692) (xy 52.65928 -37.794692) (xy 52.65928 -39.142517) (xy 55.93892 -39.142517)
			(xy 55.93892 -39.071195) (xy 55.946906 -39.000321) (xy 55.962776 -38.930786) (xy 55.986333 -38.863466)
			(xy 56.017278 -38.799207) (xy 56.055224 -38.738816) (xy 56.099693 -38.683054) (xy 56.150126 -38.632621)
			(xy 56.205888 -38.588152) (xy 56.266279 -38.550206) (xy 56.330538 -38.519261) (xy 56.397858 -38.495704)
			(xy 56.467393 -38.479834) (xy 56.538267 -38.471848) (xy 56.573928 -38.471348) (xy 56.609589 -38.471848)
			(xy 56.680463 -38.479834) (xy 56.749998 -38.495704) (xy 56.817318 -38.519261) (xy 56.881577 -38.550206)
			(xy 56.941968 -38.588152) (xy 56.99773 -38.632621) (xy 57.048163 -38.683054) (xy 57.092632 -38.738816)
			(xy 57.130578 -38.799207) (xy 57.161523 -38.863466) (xy 57.18508 -38.930786) (xy 57.20095 -39.000321)
			(xy 57.208936 -39.071195) (xy 57.208936 -39.142517) (xy 58.470792 -39.142517) (xy 58.470792 -39.071195)
			(xy 58.478778 -39.000321) (xy 58.494648 -38.930786) (xy 58.518205 -38.863466) (xy 58.54915 -38.799207)
			(xy 58.587096 -38.738816) (xy 58.631565 -38.683054) (xy 58.681998 -38.632621) (xy 58.73776 -38.588152)
			(xy 58.798151 -38.550206) (xy 58.86241 -38.519261) (xy 58.92973 -38.495704) (xy 58.999265 -38.479834)
			(xy 59.070139 -38.471848) (xy 59.1058 -38.471348) (xy 59.141461 -38.471848) (xy 59.212335 -38.479834)
			(xy 59.28187 -38.495704) (xy 59.34919 -38.519261) (xy 59.413449 -38.550206) (xy 59.47384 -38.588152)
			(xy 59.529602 -38.632621) (xy 59.580035 -38.683054) (xy 59.624504 -38.738816) (xy 59.66245 -38.799207)
			(xy 59.693395 -38.863466) (xy 59.716952 -38.930786) (xy 59.732822 -39.000321) (xy 59.740808 -39.071195)
			(xy 59.740808 -39.142517) (xy 61.275206 -39.142517) (xy 61.275206 -39.071195) (xy 61.283192 -39.000321)
			(xy 61.299062 -38.930786) (xy 61.322619 -38.863466) (xy 61.353564 -38.799207) (xy 61.39151 -38.738816)
			(xy 61.435979 -38.683054) (xy 61.486412 -38.632621) (xy 61.542174 -38.588152) (xy 61.602565 -38.550206)
			(xy 61.666824 -38.519261) (xy 61.734144 -38.495704) (xy 61.803679 -38.479834) (xy 61.874553 -38.471848)
			(xy 61.910214 -38.471348) (xy 61.945875 -38.471848) (xy 62.016749 -38.479834) (xy 62.086284 -38.495704)
			(xy 62.153604 -38.519261) (xy 62.217863 -38.550206) (xy 62.278254 -38.588152) (xy 62.334016 -38.632621)
			(xy 62.384449 -38.683054) (xy 62.428918 -38.738816) (xy 62.466864 -38.799207) (xy 62.497809 -38.863466)
			(xy 62.521366 -38.930786) (xy 62.537236 -39.000321) (xy 62.545222 -39.071195) (xy 62.545222 -39.142517)
			(xy 63.648074 -39.142517) (xy 63.648074 -39.071195) (xy 63.65606 -39.000321) (xy 63.67193 -38.930786)
			(xy 63.695487 -38.863466) (xy 63.726432 -38.799207) (xy 63.764378 -38.738816) (xy 63.808847 -38.683054)
			(xy 63.85928 -38.632621) (xy 63.915042 -38.588152) (xy 63.975433 -38.550206) (xy 64.039692 -38.519261)
			(xy 64.107012 -38.495704) (xy 64.176547 -38.479834) (xy 64.247421 -38.471848) (xy 64.283082 -38.471348)
			(xy 64.318743 -38.471848) (xy 64.389617 -38.479834) (xy 64.459152 -38.495704) (xy 64.526472 -38.519261)
			(xy 64.590731 -38.550206) (xy 64.651122 -38.588152) (xy 64.706884 -38.632621) (xy 64.757317 -38.683054)
			(xy 64.801786 -38.738816) (xy 64.839732 -38.799207) (xy 64.870677 -38.863466) (xy 64.894234 -38.930786)
			(xy 64.910104 -39.000321) (xy 64.91809 -39.071195) (xy 64.91809 -39.142517) (xy 66.639686 -39.142517)
			(xy 66.639686 -39.071195) (xy 66.647672 -39.000321) (xy 66.663542 -38.930786) (xy 66.687099 -38.863466)
			(xy 66.718044 -38.799207) (xy 66.75599 -38.738816) (xy 66.800459 -38.683054) (xy 66.850892 -38.632621)
			(xy 66.906654 -38.588152) (xy 66.967045 -38.550206) (xy 67.031304 -38.519261) (xy 67.098624 -38.495704)
			(xy 67.168159 -38.479834) (xy 67.239033 -38.471848) (xy 67.274694 -38.471348) (xy 67.310355 -38.471848)
			(xy 67.381229 -38.479834) (xy 67.450764 -38.495704) (xy 67.518084 -38.519261) (xy 67.582343 -38.550206)
			(xy 67.642734 -38.588152) (xy 67.698496 -38.632621) (xy 67.748929 -38.683054) (xy 67.793398 -38.738816)
			(xy 67.831344 -38.799207) (xy 67.862289 -38.863466) (xy 67.885846 -38.930786) (xy 67.901716 -39.000321)
			(xy 67.909702 -39.071195) (xy 67.909702 -39.142517) (xy 67.901716 -39.213391) (xy 67.885846 -39.282926)
			(xy 67.862289 -39.350246) (xy 67.831344 -39.414505) (xy 67.793398 -39.474896) (xy 67.748929 -39.530658)
			(xy 67.698496 -39.581091) (xy 67.642734 -39.62556) (xy 67.582343 -39.663506) (xy 67.518084 -39.694451)
			(xy 67.450764 -39.718008) (xy 67.381229 -39.733878) (xy 67.310355 -39.741864) (xy 67.239033 -39.741864)
			(xy 67.168159 -39.733878) (xy 67.098624 -39.718008) (xy 67.031304 -39.694451) (xy 66.967045 -39.663506)
			(xy 66.906654 -39.62556) (xy 66.850892 -39.581091) (xy 66.800459 -39.530658) (xy 66.75599 -39.474896)
			(xy 66.718044 -39.414505) (xy 66.687099 -39.350246) (xy 66.663542 -39.282926) (xy 66.647672 -39.213391)
			(xy 66.639686 -39.142517) (xy 64.91809 -39.142517) (xy 64.910104 -39.213391) (xy 64.894234 -39.282926)
			(xy 64.870677 -39.350246) (xy 64.839732 -39.414505) (xy 64.801786 -39.474896) (xy 64.757317 -39.530658)
			(xy 64.706884 -39.581091) (xy 64.651122 -39.62556) (xy 64.590731 -39.663506) (xy 64.526472 -39.694451)
			(xy 64.459152 -39.718008) (xy 64.389617 -39.733878) (xy 64.318743 -39.741864) (xy 64.247421 -39.741864)
			(xy 64.176547 -39.733878) (xy 64.107012 -39.718008) (xy 64.039692 -39.694451) (xy 63.975433 -39.663506)
			(xy 63.915042 -39.62556) (xy 63.85928 -39.581091) (xy 63.808847 -39.530658) (xy 63.764378 -39.474896)
			(xy 63.726432 -39.414505) (xy 63.695487 -39.350246) (xy 63.67193 -39.282926) (xy 63.65606 -39.213391)
			(xy 63.648074 -39.142517) (xy 62.545222 -39.142517) (xy 62.537236 -39.213391) (xy 62.521366 -39.282926)
			(xy 62.497809 -39.350246) (xy 62.466864 -39.414505) (xy 62.428918 -39.474896) (xy 62.384449 -39.530658)
			(xy 62.334016 -39.581091) (xy 62.278254 -39.62556) (xy 62.217863 -39.663506) (xy 62.153604 -39.694451)
			(xy 62.086284 -39.718008) (xy 62.016749 -39.733878) (xy 61.945875 -39.741864) (xy 61.874553 -39.741864)
			(xy 61.803679 -39.733878) (xy 61.734144 -39.718008) (xy 61.666824 -39.694451) (xy 61.602565 -39.663506)
			(xy 61.542174 -39.62556) (xy 61.486412 -39.581091) (xy 61.435979 -39.530658) (xy 61.39151 -39.474896)
			(xy 61.353564 -39.414505) (xy 61.322619 -39.350246) (xy 61.299062 -39.282926) (xy 61.283192 -39.213391)
			(xy 61.275206 -39.142517) (xy 59.740808 -39.142517) (xy 59.732822 -39.213391) (xy 59.716952 -39.282926)
			(xy 59.693395 -39.350246) (xy 59.66245 -39.414505) (xy 59.624504 -39.474896) (xy 59.580035 -39.530658)
			(xy 59.529602 -39.581091) (xy 59.47384 -39.62556) (xy 59.413449 -39.663506) (xy 59.34919 -39.694451)
			(xy 59.28187 -39.718008) (xy 59.212335 -39.733878) (xy 59.141461 -39.741864) (xy 59.070139 -39.741864)
			(xy 58.999265 -39.733878) (xy 58.92973 -39.718008) (xy 58.86241 -39.694451) (xy 58.798151 -39.663506)
			(xy 58.73776 -39.62556) (xy 58.681998 -39.581091) (xy 58.631565 -39.530658) (xy 58.587096 -39.474896)
			(xy 58.54915 -39.414505) (xy 58.518205 -39.350246) (xy 58.494648 -39.282926) (xy 58.478778 -39.213391)
			(xy 58.470792 -39.142517) (xy 57.208936 -39.142517) (xy 57.20095 -39.213391) (xy 57.18508 -39.282926)
			(xy 57.161523 -39.350246) (xy 57.130578 -39.414505) (xy 57.092632 -39.474896) (xy 57.048163 -39.530658)
			(xy 56.99773 -39.581091) (xy 56.941968 -39.62556) (xy 56.881577 -39.663506) (xy 56.817318 -39.694451)
			(xy 56.749998 -39.718008) (xy 56.680463 -39.733878) (xy 56.609589 -39.741864) (xy 56.538267 -39.741864)
			(xy 56.467393 -39.733878) (xy 56.397858 -39.718008) (xy 56.330538 -39.694451) (xy 56.266279 -39.663506)
			(xy 56.205888 -39.62556) (xy 56.150126 -39.581091) (xy 56.099693 -39.530658) (xy 56.055224 -39.474896)
			(xy 56.017278 -39.414505) (xy 55.986333 -39.350246) (xy 55.962776 -39.282926) (xy 55.946906 -39.213391)
			(xy 55.93892 -39.142517) (xy 52.65928 -39.142517) (xy 52.65928 -39.446708) (xy 51.007772 -39.446708)
			(xy 51.007772 -37.794692) (xy 28.154884 -37.794692) (xy 28.154884 -41.105429) (xy 55.93892 -41.105429)
			(xy 55.93892 -41.034107) (xy 55.946906 -40.963233) (xy 55.962776 -40.893698) (xy 55.986333 -40.826378)
			(xy 56.017278 -40.762119) (xy 56.055224 -40.701728) (xy 56.099693 -40.645966) (xy 56.150126 -40.595533)
			(xy 56.205888 -40.551064) (xy 56.266279 -40.513118) (xy 56.330538 -40.482173) (xy 56.397858 -40.458616)
			(xy 56.467393 -40.442746) (xy 56.538267 -40.43476) (xy 56.573928 -40.43426) (xy 56.609589 -40.43476)
			(xy 56.680463 -40.442746) (xy 56.749998 -40.458616) (xy 56.817318 -40.482173) (xy 56.881577 -40.513118)
			(xy 56.941968 -40.551064) (xy 56.99773 -40.595533) (xy 57.048163 -40.645966) (xy 57.092632 -40.701728)
			(xy 57.130578 -40.762119) (xy 57.161523 -40.826378) (xy 57.18508 -40.893698) (xy 57.20095 -40.963233)
			(xy 57.208936 -41.034107) (xy 57.208936 -41.105429) (xy 58.470792 -41.105429) (xy 58.470792 -41.034107)
			(xy 58.478778 -40.963233) (xy 58.494648 -40.893698) (xy 58.518205 -40.826378) (xy 58.54915 -40.762119)
			(xy 58.587096 -40.701728) (xy 58.631565 -40.645966) (xy 58.681998 -40.595533) (xy 58.73776 -40.551064)
			(xy 58.798151 -40.513118) (xy 58.86241 -40.482173) (xy 58.92973 -40.458616) (xy 58.999265 -40.442746)
			(xy 59.070139 -40.43476) (xy 59.1058 -40.43426) (xy 59.141461 -40.43476) (xy 59.212335 -40.442746)
			(xy 59.28187 -40.458616) (xy 59.34919 -40.482173) (xy 59.413449 -40.513118) (xy 59.47384 -40.551064)
			(xy 59.529602 -40.595533) (xy 59.580035 -40.645966) (xy 59.624504 -40.701728) (xy 59.66245 -40.762119)
			(xy 59.693395 -40.826378) (xy 59.716952 -40.893698) (xy 59.732822 -40.963233) (xy 59.740808 -41.034107)
			(xy 59.740808 -41.105429) (xy 61.275206 -41.105429) (xy 61.275206 -41.034107) (xy 61.283192 -40.963233)
			(xy 61.299062 -40.893698) (xy 61.322619 -40.826378) (xy 61.353564 -40.762119) (xy 61.39151 -40.701728)
			(xy 61.435979 -40.645966) (xy 61.486412 -40.595533) (xy 61.542174 -40.551064) (xy 61.602565 -40.513118)
			(xy 61.666824 -40.482173) (xy 61.734144 -40.458616) (xy 61.803679 -40.442746) (xy 61.874553 -40.43476)
			(xy 61.910214 -40.43426) (xy 61.945875 -40.43476) (xy 62.016749 -40.442746) (xy 62.086284 -40.458616)
			(xy 62.153604 -40.482173) (xy 62.217863 -40.513118) (xy 62.278254 -40.551064) (xy 62.334016 -40.595533)
			(xy 62.384449 -40.645966) (xy 62.428918 -40.701728) (xy 62.466864 -40.762119) (xy 62.497809 -40.826378)
			(xy 62.521366 -40.893698) (xy 62.537236 -40.963233) (xy 62.545222 -41.034107) (xy 62.545222 -41.105429)
			(xy 63.648074 -41.105429) (xy 63.648074 -41.034107) (xy 63.65606 -40.963233) (xy 63.67193 -40.893698)
			(xy 63.695487 -40.826378) (xy 63.726432 -40.762119) (xy 63.764378 -40.701728) (xy 63.808847 -40.645966)
			(xy 63.85928 -40.595533) (xy 63.915042 -40.551064) (xy 63.975433 -40.513118) (xy 64.039692 -40.482173)
			(xy 64.107012 -40.458616) (xy 64.176547 -40.442746) (xy 64.247421 -40.43476) (xy 64.283082 -40.43426)
			(xy 64.318743 -40.43476) (xy 64.389617 -40.442746) (xy 64.459152 -40.458616) (xy 64.526472 -40.482173)
			(xy 64.590731 -40.513118) (xy 64.651122 -40.551064) (xy 64.706884 -40.595533) (xy 64.757317 -40.645966)
			(xy 64.801786 -40.701728) (xy 64.839732 -40.762119) (xy 64.870677 -40.826378) (xy 64.894234 -40.893698)
			(xy 64.910104 -40.963233) (xy 64.91809 -41.034107) (xy 64.91809 -41.105429) (xy 66.639686 -41.105429)
			(xy 66.639686 -41.034107) (xy 66.647672 -40.963233) (xy 66.663542 -40.893698) (xy 66.687099 -40.826378)
			(xy 66.718044 -40.762119) (xy 66.75599 -40.701728) (xy 66.800459 -40.645966) (xy 66.850892 -40.595533)
			(xy 66.906654 -40.551064) (xy 66.967045 -40.513118) (xy 67.031304 -40.482173) (xy 67.098624 -40.458616)
			(xy 67.168159 -40.442746) (xy 67.239033 -40.43476) (xy 67.274694 -40.43426) (xy 67.310355 -40.43476)
			(xy 67.381229 -40.442746) (xy 67.450764 -40.458616) (xy 67.518084 -40.482173) (xy 67.582343 -40.513118)
			(xy 67.642734 -40.551064) (xy 67.698496 -40.595533) (xy 67.748929 -40.645966) (xy 67.793398 -40.701728)
			(xy 67.831344 -40.762119) (xy 67.862289 -40.826378) (xy 67.885846 -40.893698) (xy 67.901716 -40.963233)
			(xy 67.909702 -41.034107) (xy 67.909702 -41.105429) (xy 67.901716 -41.176303) (xy 67.885846 -41.245838)
			(xy 67.862289 -41.313158) (xy 67.831344 -41.377417) (xy 67.793398 -41.437808) (xy 67.748929 -41.49357)
			(xy 67.698496 -41.544003) (xy 67.642734 -41.588472) (xy 67.582343 -41.626418) (xy 67.518084 -41.657363)
			(xy 67.450764 -41.68092) (xy 67.381229 -41.69679) (xy 67.310355 -41.704776) (xy 67.239033 -41.704776)
			(xy 67.168159 -41.69679) (xy 67.098624 -41.68092) (xy 67.031304 -41.657363) (xy 66.967045 -41.626418)
			(xy 66.906654 -41.588472) (xy 66.850892 -41.544003) (xy 66.800459 -41.49357) (xy 66.75599 -41.437808)
			(xy 66.718044 -41.377417) (xy 66.687099 -41.313158) (xy 66.663542 -41.245838) (xy 66.647672 -41.176303)
			(xy 66.639686 -41.105429) (xy 64.91809 -41.105429) (xy 64.910104 -41.176303) (xy 64.894234 -41.245838)
			(xy 64.870677 -41.313158) (xy 64.839732 -41.377417) (xy 64.801786 -41.437808) (xy 64.757317 -41.49357)
			(xy 64.706884 -41.544003) (xy 64.651122 -41.588472) (xy 64.590731 -41.626418) (xy 64.526472 -41.657363)
			(xy 64.459152 -41.68092) (xy 64.389617 -41.69679) (xy 64.318743 -41.704776) (xy 64.247421 -41.704776)
			(xy 64.176547 -41.69679) (xy 64.107012 -41.68092) (xy 64.039692 -41.657363) (xy 63.975433 -41.626418)
			(xy 63.915042 -41.588472) (xy 63.85928 -41.544003) (xy 63.808847 -41.49357) (xy 63.764378 -41.437808)
			(xy 63.726432 -41.377417) (xy 63.695487 -41.313158) (xy 63.67193 -41.245838) (xy 63.65606 -41.176303)
			(xy 63.648074 -41.105429) (xy 62.545222 -41.105429) (xy 62.537236 -41.176303) (xy 62.521366 -41.245838)
			(xy 62.497809 -41.313158) (xy 62.466864 -41.377417) (xy 62.428918 -41.437808) (xy 62.384449 -41.49357)
			(xy 62.334016 -41.544003) (xy 62.278254 -41.588472) (xy 62.217863 -41.626418) (xy 62.153604 -41.657363)
			(xy 62.086284 -41.68092) (xy 62.016749 -41.69679) (xy 61.945875 -41.704776) (xy 61.874553 -41.704776)
			(xy 61.803679 -41.69679) (xy 61.734144 -41.68092) (xy 61.666824 -41.657363) (xy 61.602565 -41.626418)
			(xy 61.542174 -41.588472) (xy 61.486412 -41.544003) (xy 61.435979 -41.49357) (xy 61.39151 -41.437808)
			(xy 61.353564 -41.377417) (xy 61.322619 -41.313158) (xy 61.299062 -41.245838) (xy 61.283192 -41.176303)
			(xy 61.275206 -41.105429) (xy 59.740808 -41.105429) (xy 59.732822 -41.176303) (xy 59.716952 -41.245838)
			(xy 59.693395 -41.313158) (xy 59.66245 -41.377417) (xy 59.624504 -41.437808) (xy 59.580035 -41.49357)
			(xy 59.529602 -41.544003) (xy 59.47384 -41.588472) (xy 59.413449 -41.626418) (xy 59.34919 -41.657363)
			(xy 59.28187 -41.68092) (xy 59.212335 -41.69679) (xy 59.141461 -41.704776) (xy 59.070139 -41.704776)
			(xy 58.999265 -41.69679) (xy 58.92973 -41.68092) (xy 58.86241 -41.657363) (xy 58.798151 -41.626418)
			(xy 58.73776 -41.588472) (xy 58.681998 -41.544003) (xy 58.631565 -41.49357) (xy 58.587096 -41.437808)
			(xy 58.54915 -41.377417) (xy 58.518205 -41.313158) (xy 58.494648 -41.245838) (xy 58.478778 -41.176303)
			(xy 58.470792 -41.105429) (xy 57.208936 -41.105429) (xy 57.20095 -41.176303) (xy 57.18508 -41.245838)
			(xy 57.161523 -41.313158) (xy 57.130578 -41.377417) (xy 57.092632 -41.437808) (xy 57.048163 -41.49357)
			(xy 56.99773 -41.544003) (xy 56.941968 -41.588472) (xy 56.881577 -41.626418) (xy 56.817318 -41.657363)
			(xy 56.749998 -41.68092) (xy 56.680463 -41.69679) (xy 56.609589 -41.704776) (xy 56.538267 -41.704776)
			(xy 56.467393 -41.69679) (xy 56.397858 -41.68092) (xy 56.330538 -41.657363) (xy 56.266279 -41.626418)
			(xy 56.205888 -41.588472) (xy 56.150126 -41.544003) (xy 56.099693 -41.49357) (xy 56.055224 -41.437808)
			(xy 56.017278 -41.377417) (xy 55.986333 -41.313158) (xy 55.962776 -41.245838) (xy 55.946906 -41.176303)
			(xy 55.93892 -41.105429) (xy 28.154884 -41.105429) (xy 28.154884 -43.248935) (xy 55.93892 -43.248935)
			(xy 55.93892 -43.177613) (xy 55.946906 -43.106739) (xy 55.962776 -43.037204) (xy 55.986333 -42.969884)
			(xy 56.017278 -42.905625) (xy 56.055224 -42.845234) (xy 56.099693 -42.789472) (xy 56.150126 -42.739039)
			(xy 56.205888 -42.69457) (xy 56.266279 -42.656624) (xy 56.330538 -42.625679) (xy 56.397858 -42.602122)
			(xy 56.467393 -42.586252) (xy 56.538267 -42.578266) (xy 56.573928 -42.577766) (xy 56.609589 -42.578266)
			(xy 56.680463 -42.586252) (xy 56.749998 -42.602122) (xy 56.817318 -42.625679) (xy 56.881577 -42.656624)
			(xy 56.941968 -42.69457) (xy 56.99773 -42.739039) (xy 57.048163 -42.789472) (xy 57.092632 -42.845234)
			(xy 57.130578 -42.905625) (xy 57.161523 -42.969884) (xy 57.18508 -43.037204) (xy 57.20095 -43.106739)
			(xy 57.208936 -43.177613) (xy 57.208936 -43.248935) (xy 58.470792 -43.248935) (xy 58.470792 -43.177613)
			(xy 58.478778 -43.106739) (xy 58.494648 -43.037204) (xy 58.518205 -42.969884) (xy 58.54915 -42.905625)
			(xy 58.587096 -42.845234) (xy 58.631565 -42.789472) (xy 58.681998 -42.739039) (xy 58.73776 -42.69457)
			(xy 58.798151 -42.656624) (xy 58.86241 -42.625679) (xy 58.92973 -42.602122) (xy 58.999265 -42.586252)
			(xy 59.070139 -42.578266) (xy 59.1058 -42.577766) (xy 59.141461 -42.578266) (xy 59.212335 -42.586252)
			(xy 59.28187 -42.602122) (xy 59.34919 -42.625679) (xy 59.413449 -42.656624) (xy 59.47384 -42.69457)
			(xy 59.529602 -42.739039) (xy 59.580035 -42.789472) (xy 59.624504 -42.845234) (xy 59.66245 -42.905625)
			(xy 59.693395 -42.969884) (xy 59.716952 -43.037204) (xy 59.732822 -43.106739) (xy 59.740808 -43.177613)
			(xy 59.740808 -43.248935) (xy 61.275206 -43.248935) (xy 61.275206 -43.177613) (xy 61.283192 -43.106739)
			(xy 61.299062 -43.037204) (xy 61.322619 -42.969884) (xy 61.353564 -42.905625) (xy 61.39151 -42.845234)
			(xy 61.435979 -42.789472) (xy 61.486412 -42.739039) (xy 61.542174 -42.69457) (xy 61.602565 -42.656624)
			(xy 61.666824 -42.625679) (xy 61.734144 -42.602122) (xy 61.803679 -42.586252) (xy 61.874553 -42.578266)
			(xy 61.910214 -42.577766) (xy 61.945875 -42.578266) (xy 62.016749 -42.586252) (xy 62.086284 -42.602122)
			(xy 62.153604 -42.625679) (xy 62.217863 -42.656624) (xy 62.278254 -42.69457) (xy 62.334016 -42.739039)
			(xy 62.384449 -42.789472) (xy 62.428918 -42.845234) (xy 62.466864 -42.905625) (xy 62.497809 -42.969884)
			(xy 62.521366 -43.037204) (xy 62.537236 -43.106739) (xy 62.545222 -43.177613) (xy 62.545222 -43.248935)
			(xy 63.648074 -43.248935) (xy 63.648074 -43.177613) (xy 63.65606 -43.106739) (xy 63.67193 -43.037204)
			(xy 63.695487 -42.969884) (xy 63.726432 -42.905625) (xy 63.764378 -42.845234) (xy 63.808847 -42.789472)
			(xy 63.85928 -42.739039) (xy 63.915042 -42.69457) (xy 63.975433 -42.656624) (xy 64.039692 -42.625679)
			(xy 64.107012 -42.602122) (xy 64.176547 -42.586252) (xy 64.247421 -42.578266) (xy 64.283082 -42.577766)
			(xy 64.318743 -42.578266) (xy 64.389617 -42.586252) (xy 64.459152 -42.602122) (xy 64.526472 -42.625679)
			(xy 64.590731 -42.656624) (xy 64.651122 -42.69457) (xy 64.706884 -42.739039) (xy 64.757317 -42.789472)
			(xy 64.801786 -42.845234) (xy 64.839732 -42.905625) (xy 64.870677 -42.969884) (xy 64.894234 -43.037204)
			(xy 64.910104 -43.106739) (xy 64.91809 -43.177613) (xy 64.91809 -43.248935) (xy 66.639686 -43.248935)
			(xy 66.639686 -43.177613) (xy 66.647672 -43.106739) (xy 66.663542 -43.037204) (xy 66.687099 -42.969884)
			(xy 66.718044 -42.905625) (xy 66.75599 -42.845234) (xy 66.800459 -42.789472) (xy 66.850892 -42.739039)
			(xy 66.906654 -42.69457) (xy 66.967045 -42.656624) (xy 67.031304 -42.625679) (xy 67.098624 -42.602122)
			(xy 67.168159 -42.586252) (xy 67.239033 -42.578266) (xy 67.274694 -42.577766) (xy 67.310355 -42.578266)
			(xy 67.381229 -42.586252) (xy 67.450764 -42.602122) (xy 67.518084 -42.625679) (xy 67.582343 -42.656624)
			(xy 67.642734 -42.69457) (xy 67.698496 -42.739039) (xy 67.748929 -42.789472) (xy 67.793398 -42.845234)
			(xy 67.831344 -42.905625) (xy 67.862289 -42.969884) (xy 67.885846 -43.037204) (xy 67.901716 -43.106739)
			(xy 67.909702 -43.177613) (xy 67.909702 -43.248935) (xy 67.901716 -43.319809) (xy 67.885846 -43.389344)
			(xy 67.862289 -43.456664) (xy 67.831344 -43.520923) (xy 67.793398 -43.581314) (xy 67.748929 -43.637076)
			(xy 67.698496 -43.687509) (xy 67.642734 -43.731978) (xy 67.582343 -43.769924) (xy 67.518084 -43.800869)
			(xy 67.450764 -43.824426) (xy 67.381229 -43.840296) (xy 67.310355 -43.848282) (xy 67.239033 -43.848282)
			(xy 67.168159 -43.840296) (xy 67.098624 -43.824426) (xy 67.031304 -43.800869) (xy 66.967045 -43.769924)
			(xy 66.906654 -43.731978) (xy 66.850892 -43.687509) (xy 66.800459 -43.637076) (xy 66.75599 -43.581314)
			(xy 66.718044 -43.520923) (xy 66.687099 -43.456664) (xy 66.663542 -43.389344) (xy 66.647672 -43.319809)
			(xy 66.639686 -43.248935) (xy 64.91809 -43.248935) (xy 64.910104 -43.319809) (xy 64.894234 -43.389344)
			(xy 64.870677 -43.456664) (xy 64.839732 -43.520923) (xy 64.801786 -43.581314) (xy 64.757317 -43.637076)
			(xy 64.706884 -43.687509) (xy 64.651122 -43.731978) (xy 64.590731 -43.769924) (xy 64.526472 -43.800869)
			(xy 64.459152 -43.824426) (xy 64.389617 -43.840296) (xy 64.318743 -43.848282) (xy 64.247421 -43.848282)
			(xy 64.176547 -43.840296) (xy 64.107012 -43.824426) (xy 64.039692 -43.800869) (xy 63.975433 -43.769924)
			(xy 63.915042 -43.731978) (xy 63.85928 -43.687509) (xy 63.808847 -43.637076) (xy 63.764378 -43.581314)
			(xy 63.726432 -43.520923) (xy 63.695487 -43.456664) (xy 63.67193 -43.389344) (xy 63.65606 -43.319809)
			(xy 63.648074 -43.248935) (xy 62.545222 -43.248935) (xy 62.537236 -43.319809) (xy 62.521366 -43.389344)
			(xy 62.497809 -43.456664) (xy 62.466864 -43.520923) (xy 62.428918 -43.581314) (xy 62.384449 -43.637076)
			(xy 62.334016 -43.687509) (xy 62.278254 -43.731978) (xy 62.217863 -43.769924) (xy 62.153604 -43.800869)
			(xy 62.086284 -43.824426) (xy 62.016749 -43.840296) (xy 61.945875 -43.848282) (xy 61.874553 -43.848282)
			(xy 61.803679 -43.840296) (xy 61.734144 -43.824426) (xy 61.666824 -43.800869) (xy 61.602565 -43.769924)
			(xy 61.542174 -43.731978) (xy 61.486412 -43.687509) (xy 61.435979 -43.637076) (xy 61.39151 -43.581314)
			(xy 61.353564 -43.520923) (xy 61.322619 -43.456664) (xy 61.299062 -43.389344) (xy 61.283192 -43.319809)
			(xy 61.275206 -43.248935) (xy 59.740808 -43.248935) (xy 59.732822 -43.319809) (xy 59.716952 -43.389344)
			(xy 59.693395 -43.456664) (xy 59.66245 -43.520923) (xy 59.624504 -43.581314) (xy 59.580035 -43.637076)
			(xy 59.529602 -43.687509) (xy 59.47384 -43.731978) (xy 59.413449 -43.769924) (xy 59.34919 -43.800869)
			(xy 59.28187 -43.824426) (xy 59.212335 -43.840296) (xy 59.141461 -43.848282) (xy 59.070139 -43.848282)
			(xy 58.999265 -43.840296) (xy 58.92973 -43.824426) (xy 58.86241 -43.800869) (xy 58.798151 -43.769924)
			(xy 58.73776 -43.731978) (xy 58.681998 -43.687509) (xy 58.631565 -43.637076) (xy 58.587096 -43.581314)
			(xy 58.54915 -43.520923) (xy 58.518205 -43.456664) (xy 58.494648 -43.389344) (xy 58.478778 -43.319809)
			(xy 58.470792 -43.248935) (xy 57.208936 -43.248935) (xy 57.20095 -43.319809) (xy 57.18508 -43.389344)
			(xy 57.161523 -43.456664) (xy 57.130578 -43.520923) (xy 57.092632 -43.581314) (xy 57.048163 -43.637076)
			(xy 56.99773 -43.687509) (xy 56.941968 -43.731978) (xy 56.881577 -43.769924) (xy 56.817318 -43.800869)
			(xy 56.749998 -43.824426) (xy 56.680463 -43.840296) (xy 56.609589 -43.848282) (xy 56.538267 -43.848282)
			(xy 56.467393 -43.840296) (xy 56.397858 -43.824426) (xy 56.330538 -43.800869) (xy 56.266279 -43.769924)
			(xy 56.205888 -43.731978) (xy 56.150126 -43.687509) (xy 56.099693 -43.637076) (xy 56.055224 -43.581314)
			(xy 56.017278 -43.520923) (xy 55.986333 -43.456664) (xy 55.962776 -43.389344) (xy 55.946906 -43.319809)
			(xy 55.93892 -43.248935) (xy 28.154884 -43.248935) (xy 28.154884 -51.331047) (xy 39.818567 -51.331047)
			(xy 39.824576 -51.215126) (xy 39.838567 -51.099897) (xy 39.860475 -50.985907) (xy 39.890195 -50.8737)
			(xy 39.927585 -50.763811) (xy 39.972468 -50.656764) (xy 40.024629 -50.553068) (xy 40.08382 -50.453218)
			(xy 40.149759 -50.357689) (xy 40.222131 -50.266938) (xy 40.300592 -50.181395) (xy 40.384767 -50.101469)
			(xy 40.474256 -50.027542) (xy 40.568632 -49.959964) (xy 40.667446 -49.899058) (xy 40.770226 -49.845115)
			(xy 40.876483 -49.798391) (xy 40.98571 -49.75911) (xy 41.097387 -49.727458) (xy 41.210982 -49.703585)
			(xy 41.325953 -49.687607) (xy 41.441752 -49.679599) (xy 41.49979 -49.679098) (xy 41.557828 -49.679599)
			(xy 41.673627 -49.687607) (xy 41.788598 -49.703585) (xy 41.902193 -49.727458) (xy 42.01387 -49.75911)
			(xy 42.123097 -49.798391) (xy 42.229354 -49.845115) (xy 42.332134 -49.899058) (xy 42.430948 -49.959964)
			(xy 42.474432 -49.991101) (xy 63.647829 -49.991101) (xy 63.653878 -49.915531) (xy 63.667925 -49.841033)
			(xy 63.689811 -49.76845) (xy 63.719288 -49.698604) (xy 63.756023 -49.632287) (xy 63.799598 -49.570251)
			(xy 63.84952 -49.513198) (xy 63.905224 -49.461774) (xy 63.966079 -49.416563) (xy 64.031394 -49.378076)
			(xy 64.10043 -49.34675) (xy 64.172405 -49.32294) (xy 64.246503 -49.306915) (xy 64.321884 -49.298856)
			(xy 64.35979 -49.298352) (xy 64.397696 -49.298856) (xy 64.473077 -49.306915) (xy 64.547175 -49.32294)
			(xy 64.61915 -49.34675) (xy 64.688186 -49.378076) (xy 64.753501 -49.416563) (xy 64.814356 -49.461774)
			(xy 64.87006 -49.513198) (xy 64.919982 -49.570251) (xy 64.963557 -49.632287) (xy 65.000292 -49.698604)
			(xy 65.029769 -49.76845) (xy 65.051655 -49.841033) (xy 65.065702 -49.915531) (xy 65.071751 -49.991101)
			(xy 66.187829 -49.991101) (xy 66.193878 -49.915531) (xy 66.207925 -49.841033) (xy 66.229811 -49.76845)
			(xy 66.259288 -49.698604) (xy 66.296023 -49.632287) (xy 66.339598 -49.570251) (xy 66.38952 -49.513198)
			(xy 66.445224 -49.461774) (xy 66.506079 -49.416563) (xy 66.571394 -49.378076) (xy 66.64043 -49.34675)
			(xy 66.712405 -49.32294) (xy 66.786503 -49.306915) (xy 66.861884 -49.298856) (xy 66.89979 -49.298352)
			(xy 66.937696 -49.298856) (xy 67.013077 -49.306915) (xy 67.087175 -49.32294) (xy 67.15915 -49.34675)
			(xy 67.228186 -49.378076) (xy 67.293501 -49.416563) (xy 67.354356 -49.461774) (xy 67.41006 -49.513198)
			(xy 67.459982 -49.570251) (xy 67.503557 -49.632287) (xy 67.540292 -49.698604) (xy 67.569769 -49.76845)
			(xy 67.591655 -49.841033) (xy 67.605702 -49.915531) (xy 67.611751 -49.991101) (xy 68.727829 -49.991101)
			(xy 68.733878 -49.915531) (xy 68.747925 -49.841033) (xy 68.769811 -49.76845) (xy 68.799288 -49.698604)
			(xy 68.836023 -49.632287) (xy 68.879598 -49.570251) (xy 68.92952 -49.513198) (xy 68.985224 -49.461774)
			(xy 69.046079 -49.416563) (xy 69.111394 -49.378076) (xy 69.18043 -49.34675) (xy 69.252405 -49.32294)
			(xy 69.326503 -49.306915) (xy 69.401884 -49.298856) (xy 69.43979 -49.298352) (xy 69.477696 -49.298856)
			(xy 69.553077 -49.306915) (xy 69.627175 -49.32294) (xy 69.69915 -49.34675) (xy 69.768186 -49.378076)
			(xy 69.833501 -49.416563) (xy 69.894356 -49.461774) (xy 69.95006 -49.513198) (xy 69.999982 -49.570251)
			(xy 70.043557 -49.632287) (xy 70.080292 -49.698604) (xy 70.109769 -49.76845) (xy 70.131655 -49.841033)
			(xy 70.145702 -49.915531) (xy 70.151751 -49.991101) (xy 71.267829 -49.991101) (xy 71.273878 -49.915531)
			(xy 71.287925 -49.841033) (xy 71.309811 -49.76845) (xy 71.339288 -49.698604) (xy 71.376023 -49.632287)
			(xy 71.419598 -49.570251) (xy 71.46952 -49.513198) (xy 71.525224 -49.461774) (xy 71.586079 -49.416563)
			(xy 71.651394 -49.378076) (xy 71.72043 -49.34675) (xy 71.792405 -49.32294) (xy 71.866503 -49.306915)
			(xy 71.941884 -49.298856) (xy 71.97979 -49.298352) (xy 72.017696 -49.298856) (xy 72.093077 -49.306915)
			(xy 72.167175 -49.32294) (xy 72.23915 -49.34675) (xy 72.308186 -49.378076) (xy 72.373501 -49.416563)
			(xy 72.434356 -49.461774) (xy 72.49006 -49.513198) (xy 72.539982 -49.570251) (xy 72.583557 -49.632287)
			(xy 72.620292 -49.698604) (xy 72.649769 -49.76845) (xy 72.671655 -49.841033) (xy 72.685702 -49.915531)
			(xy 72.691751 -49.991101) (xy 73.807829 -49.991101) (xy 73.813878 -49.915531) (xy 73.827925 -49.841033)
			(xy 73.849811 -49.76845) (xy 73.879288 -49.698604) (xy 73.916023 -49.632287) (xy 73.959598 -49.570251)
			(xy 74.00952 -49.513198) (xy 74.065224 -49.461774) (xy 74.126079 -49.416563) (xy 74.191394 -49.378076)
			(xy 74.26043 -49.34675) (xy 74.332405 -49.32294) (xy 74.406503 -49.306915) (xy 74.481884 -49.298856)
			(xy 74.51979 -49.298352) (xy 74.557696 -49.298856) (xy 74.633077 -49.306915) (xy 74.707175 -49.32294)
			(xy 74.77915 -49.34675) (xy 74.848186 -49.378076) (xy 74.913501 -49.416563) (xy 74.974356 -49.461774)
			(xy 75.03006 -49.513198) (xy 75.079982 -49.570251) (xy 75.123557 -49.632287) (xy 75.160292 -49.698604)
			(xy 75.189769 -49.76845) (xy 75.211655 -49.841033) (xy 75.225702 -49.915531) (xy 75.231751 -49.991101)
			(xy 76.347829 -49.991101) (xy 76.353878 -49.915531) (xy 76.367925 -49.841033) (xy 76.389811 -49.76845)
			(xy 76.419288 -49.698604) (xy 76.456023 -49.632287) (xy 76.499598 -49.570251) (xy 76.54952 -49.513198)
			(xy 76.605224 -49.461774) (xy 76.666079 -49.416563) (xy 76.731394 -49.378076) (xy 76.80043 -49.34675)
			(xy 76.872405 -49.32294) (xy 76.946503 -49.306915) (xy 77.021884 -49.298856) (xy 77.05979 -49.298352)
			(xy 77.097696 -49.298856) (xy 77.173077 -49.306915) (xy 77.247175 -49.32294) (xy 77.31915 -49.34675)
			(xy 77.388186 -49.378076) (xy 77.453501 -49.416563) (xy 77.514356 -49.461774) (xy 77.57006 -49.513198)
			(xy 77.619982 -49.570251) (xy 77.663557 -49.632287) (xy 77.700292 -49.698604) (xy 77.729769 -49.76845)
			(xy 77.751655 -49.841033) (xy 77.765702 -49.915531) (xy 77.771751 -49.991101) (xy 78.887829 -49.991101)
			(xy 78.893878 -49.915531) (xy 78.907925 -49.841033) (xy 78.929811 -49.76845) (xy 78.959288 -49.698604)
			(xy 78.996023 -49.632287) (xy 79.039598 -49.570251) (xy 79.08952 -49.513198) (xy 79.145224 -49.461774)
			(xy 79.206079 -49.416563) (xy 79.271394 -49.378076) (xy 79.34043 -49.34675) (xy 79.412405 -49.32294)
			(xy 79.486503 -49.306915) (xy 79.561884 -49.298856) (xy 79.59979 -49.298352) (xy 79.637696 -49.298856)
			(xy 79.713077 -49.306915) (xy 79.787175 -49.32294) (xy 79.85915 -49.34675) (xy 79.928186 -49.378076)
			(xy 79.993501 -49.416563) (xy 80.054356 -49.461774) (xy 80.11006 -49.513198) (xy 80.159982 -49.570251)
			(xy 80.203557 -49.632287) (xy 80.240292 -49.698604) (xy 80.269769 -49.76845) (xy 80.291655 -49.841033)
			(xy 80.305702 -49.915531) (xy 80.311751 -49.991101) (xy 81.427829 -49.991101) (xy 81.433878 -49.915531)
			(xy 81.447925 -49.841033) (xy 81.469811 -49.76845) (xy 81.499288 -49.698604) (xy 81.536023 -49.632287)
			(xy 81.579598 -49.570251) (xy 81.62952 -49.513198) (xy 81.685224 -49.461774) (xy 81.746079 -49.416563)
			(xy 81.811394 -49.378076) (xy 81.88043 -49.34675) (xy 81.952405 -49.32294) (xy 82.026503 -49.306915)
			(xy 82.101884 -49.298856) (xy 82.13979 -49.298352) (xy 82.177696 -49.298856) (xy 82.253077 -49.306915)
			(xy 82.327175 -49.32294) (xy 82.39915 -49.34675) (xy 82.468186 -49.378076) (xy 82.533501 -49.416563)
			(xy 82.559813 -49.436111) (xy 86.197949 -49.436111) (xy 86.203998 -49.360541) (xy 86.218045 -49.286043)
			(xy 86.239931 -49.21346) (xy 86.269408 -49.143614) (xy 86.306143 -49.077297) (xy 86.349718 -49.015261)
			(xy 86.39964 -48.958208) (xy 86.455344 -48.906784) (xy 86.516199 -48.861573) (xy 86.581514 -48.823086)
			(xy 86.65055 -48.79176) (xy 86.722525 -48.76795) (xy 86.796623 -48.751925) (xy 86.872004 -48.743866)
			(xy 86.90991 -48.743362) (xy 86.947816 -48.743866) (xy 87.023197 -48.751925) (xy 87.097295 -48.76795)
			(xy 87.16927 -48.79176) (xy 87.238306 -48.823086) (xy 87.303621 -48.861573) (xy 87.364476 -48.906784)
			(xy 87.42018 -48.958208) (xy 87.470102 -49.015261) (xy 87.513677 -49.077297) (xy 87.550412 -49.143614)
			(xy 87.579889 -49.21346) (xy 87.601775 -49.286043) (xy 87.615822 -49.360541) (xy 87.621871 -49.436111)
			(xy 88.737949 -49.436111) (xy 88.743998 -49.360541) (xy 88.758045 -49.286043) (xy 88.779931 -49.21346)
			(xy 88.809408 -49.143614) (xy 88.846143 -49.077297) (xy 88.889718 -49.015261) (xy 88.93964 -48.958208)
			(xy 88.995344 -48.906784) (xy 89.056199 -48.861573) (xy 89.121514 -48.823086) (xy 89.19055 -48.79176)
			(xy 89.262525 -48.76795) (xy 89.336623 -48.751925) (xy 89.412004 -48.743866) (xy 89.44991 -48.743362)
			(xy 89.487816 -48.743866) (xy 89.563197 -48.751925) (xy 89.637295 -48.76795) (xy 89.70927 -48.79176)
			(xy 89.778306 -48.823086) (xy 89.843621 -48.861573) (xy 89.904476 -48.906784) (xy 89.96018 -48.958208)
			(xy 90.010102 -49.015261) (xy 90.053677 -49.077297) (xy 90.090412 -49.143614) (xy 90.119889 -49.21346)
			(xy 90.141775 -49.286043) (xy 90.155822 -49.360541) (xy 90.161871 -49.436111) (xy 91.277949 -49.436111)
			(xy 91.283998 -49.360541) (xy 91.298045 -49.286043) (xy 91.319931 -49.21346) (xy 91.349408 -49.143614)
			(xy 91.386143 -49.077297) (xy 91.429718 -49.015261) (xy 91.47964 -48.958208) (xy 91.535344 -48.906784)
			(xy 91.596199 -48.861573) (xy 91.661514 -48.823086) (xy 91.73055 -48.79176) (xy 91.802525 -48.76795)
			(xy 91.876623 -48.751925) (xy 91.952004 -48.743866) (xy 91.98991 -48.743362) (xy 92.027816 -48.743866)
			(xy 92.103197 -48.751925) (xy 92.177295 -48.76795) (xy 92.24927 -48.79176) (xy 92.318306 -48.823086)
			(xy 92.383621 -48.861573) (xy 92.444476 -48.906784) (xy 92.50018 -48.958208) (xy 92.550102 -49.015261)
			(xy 92.593677 -49.077297) (xy 92.630412 -49.143614) (xy 92.659889 -49.21346) (xy 92.681775 -49.286043)
			(xy 92.695822 -49.360541) (xy 92.701871 -49.436111) (xy 92.699852 -49.511895) (xy 92.68979 -49.587035)
			(xy 92.671798 -49.66068) (xy 92.64608 -49.731996) (xy 92.612928 -49.800173) (xy 92.572716 -49.864441)
			(xy 92.525901 -49.92407) (xy 92.473013 -49.978386) (xy 92.414651 -50.026772) (xy 92.351476 -50.06868)
			(xy 92.284205 -50.103636) (xy 92.2136 -50.131243) (xy 92.140459 -50.151189) (xy 92.065614 -50.163248)
			(xy 91.98991 -50.167283) (xy 91.914206 -50.163248) (xy 91.839361 -50.151189) (xy 91.76622 -50.131243)
			(xy 91.695615 -50.103636) (xy 91.628344 -50.06868) (xy 91.565169 -50.026772) (xy 91.506807 -49.978386)
			(xy 91.453919 -49.92407) (xy 91.407104 -49.864441) (xy 91.366892 -49.800173) (xy 91.33374 -49.731996)
			(xy 91.308022 -49.66068) (xy 91.29003 -49.587035) (xy 91.279968 -49.511895) (xy 91.277949 -49.436111)
			(xy 90.161871 -49.436111) (xy 90.159852 -49.511895) (xy 90.14979 -49.587035) (xy 90.131798 -49.66068)
			(xy 90.10608 -49.731996) (xy 90.072928 -49.800173) (xy 90.032716 -49.864441) (xy 89.985901 -49.92407)
			(xy 89.933013 -49.978386) (xy 89.874651 -50.026772) (xy 89.811476 -50.06868) (xy 89.744205 -50.103636)
			(xy 89.6736 -50.131243) (xy 89.600459 -50.151189) (xy 89.525614 -50.163248) (xy 89.44991 -50.167283)
			(xy 89.374206 -50.163248) (xy 89.299361 -50.151189) (xy 89.22622 -50.131243) (xy 89.155615 -50.103636)
			(xy 89.088344 -50.06868) (xy 89.025169 -50.026772) (xy 88.966807 -49.978386) (xy 88.913919 -49.92407)
			(xy 88.867104 -49.864441) (xy 88.826892 -49.800173) (xy 88.79374 -49.731996) (xy 88.768022 -49.66068)
			(xy 88.75003 -49.587035) (xy 88.739968 -49.511895) (xy 88.737949 -49.436111) (xy 87.621871 -49.436111)
			(xy 87.619852 -49.511895) (xy 87.60979 -49.587035) (xy 87.591798 -49.66068) (xy 87.56608 -49.731996)
			(xy 87.532928 -49.800173) (xy 87.492716 -49.864441) (xy 87.445901 -49.92407) (xy 87.393013 -49.978386)
			(xy 87.334651 -50.026772) (xy 87.271476 -50.06868) (xy 87.204205 -50.103636) (xy 87.1336 -50.131243)
			(xy 87.060459 -50.151189) (xy 86.985614 -50.163248) (xy 86.90991 -50.167283) (xy 86.834206 -50.163248)
			(xy 86.759361 -50.151189) (xy 86.68622 -50.131243) (xy 86.615615 -50.103636) (xy 86.548344 -50.06868)
			(xy 86.485169 -50.026772) (xy 86.426807 -49.978386) (xy 86.373919 -49.92407) (xy 86.327104 -49.864441)
			(xy 86.286892 -49.800173) (xy 86.25374 -49.731996) (xy 86.228022 -49.66068) (xy 86.21003 -49.587035)
			(xy 86.199968 -49.511895) (xy 86.197949 -49.436111) (xy 82.559813 -49.436111) (xy 82.594356 -49.461774)
			(xy 82.65006 -49.513198) (xy 82.699982 -49.570251) (xy 82.743557 -49.632287) (xy 82.780292 -49.698604)
			(xy 82.809769 -49.76845) (xy 82.831655 -49.841033) (xy 82.845702 -49.915531) (xy 82.851751 -49.991101)
			(xy 82.849732 -50.066885) (xy 82.83967 -50.142025) (xy 82.821678 -50.21567) (xy 82.79596 -50.286986)
			(xy 82.762808 -50.355163) (xy 82.722596 -50.419431) (xy 82.675781 -50.47906) (xy 82.622893 -50.533376)
			(xy 82.564531 -50.581762) (xy 82.501356 -50.62367) (xy 82.434085 -50.658626) (xy 82.36348 -50.686233)
			(xy 82.290588 -50.706111) (xy 84.927949 -50.706111) (xy 84.933998 -50.630541) (xy 84.948045 -50.556043)
			(xy 84.969931 -50.48346) (xy 84.999408 -50.413614) (xy 85.036143 -50.347297) (xy 85.079718 -50.285261)
			(xy 85.12964 -50.228208) (xy 85.185344 -50.176784) (xy 85.246199 -50.131573) (xy 85.311514 -50.093086)
			(xy 85.38055 -50.06176) (xy 85.452525 -50.03795) (xy 85.526623 -50.021925) (xy 85.602004 -50.013866)
			(xy 85.63991 -50.013362) (xy 85.677816 -50.013866) (xy 85.753197 -50.021925) (xy 85.827295 -50.03795)
			(xy 85.89927 -50.06176) (xy 85.968306 -50.093086) (xy 86.033621 -50.131573) (xy 86.094476 -50.176784)
			(xy 86.15018 -50.228208) (xy 86.200102 -50.285261) (xy 86.243677 -50.347297) (xy 86.280412 -50.413614)
			(xy 86.309889 -50.48346) (xy 86.331775 -50.556043) (xy 86.345822 -50.630541) (xy 86.351871 -50.706111)
			(xy 87.467949 -50.706111) (xy 87.473998 -50.630541) (xy 87.488045 -50.556043) (xy 87.509931 -50.48346)
			(xy 87.539408 -50.413614) (xy 87.576143 -50.347297) (xy 87.619718 -50.285261) (xy 87.66964 -50.228208)
			(xy 87.725344 -50.176784) (xy 87.786199 -50.131573) (xy 87.851514 -50.093086) (xy 87.92055 -50.06176)
			(xy 87.992525 -50.03795) (xy 88.066623 -50.021925) (xy 88.142004 -50.013866) (xy 88.17991 -50.013362)
			(xy 88.217816 -50.013866) (xy 88.293197 -50.021925) (xy 88.367295 -50.03795) (xy 88.43927 -50.06176)
			(xy 88.508306 -50.093086) (xy 88.573621 -50.131573) (xy 88.634476 -50.176784) (xy 88.69018 -50.228208)
			(xy 88.740102 -50.285261) (xy 88.783677 -50.347297) (xy 88.820412 -50.413614) (xy 88.849889 -50.48346)
			(xy 88.871775 -50.556043) (xy 88.885822 -50.630541) (xy 88.891871 -50.706111) (xy 90.007949 -50.706111)
			(xy 90.013998 -50.630541) (xy 90.028045 -50.556043) (xy 90.049931 -50.48346) (xy 90.079408 -50.413614)
			(xy 90.116143 -50.347297) (xy 90.159718 -50.285261) (xy 90.20964 -50.228208) (xy 90.265344 -50.176784)
			(xy 90.326199 -50.131573) (xy 90.391514 -50.093086) (xy 90.46055 -50.06176) (xy 90.532525 -50.03795)
			(xy 90.606623 -50.021925) (xy 90.682004 -50.013866) (xy 90.71991 -50.013362) (xy 90.757816 -50.013866)
			(xy 90.833197 -50.021925) (xy 90.907295 -50.03795) (xy 90.97927 -50.06176) (xy 91.048306 -50.093086)
			(xy 91.113621 -50.131573) (xy 91.174476 -50.176784) (xy 91.23018 -50.228208) (xy 91.280102 -50.285261)
			(xy 91.323677 -50.347297) (xy 91.360412 -50.413614) (xy 91.389889 -50.48346) (xy 91.411775 -50.556043)
			(xy 91.425822 -50.630541) (xy 91.431871 -50.706111) (xy 91.429852 -50.781895) (xy 91.41979 -50.857035)
			(xy 91.401798 -50.93068) (xy 91.37608 -51.001996) (xy 91.342928 -51.070173) (xy 91.302716 -51.134441)
			(xy 91.255901 -51.19407) (xy 91.203013 -51.248386) (xy 91.144651 -51.296772) (xy 91.081476 -51.33868)
			(xy 91.014205 -51.373636) (xy 90.9436 -51.401243) (xy 90.870459 -51.421189) (xy 90.795614 -51.433248)
			(xy 90.71991 -51.437283) (xy 90.644206 -51.433248) (xy 90.569361 -51.421189) (xy 90.49622 -51.401243)
			(xy 90.425615 -51.373636) (xy 90.358344 -51.33868) (xy 90.295169 -51.296772) (xy 90.236807 -51.248386)
			(xy 90.183919 -51.19407) (xy 90.137104 -51.134441) (xy 90.096892 -51.070173) (xy 90.06374 -51.001996)
			(xy 90.038022 -50.93068) (xy 90.02003 -50.857035) (xy 90.009968 -50.781895) (xy 90.007949 -50.706111)
			(xy 88.891871 -50.706111) (xy 88.889852 -50.781895) (xy 88.87979 -50.857035) (xy 88.861798 -50.93068)
			(xy 88.83608 -51.001996) (xy 88.802928 -51.070173) (xy 88.762716 -51.134441) (xy 88.715901 -51.19407)
			(xy 88.663013 -51.248386) (xy 88.604651 -51.296772) (xy 88.541476 -51.33868) (xy 88.474205 -51.373636)
			(xy 88.4036 -51.401243) (xy 88.330459 -51.421189) (xy 88.255614 -51.433248) (xy 88.17991 -51.437283)
			(xy 88.104206 -51.433248) (xy 88.029361 -51.421189) (xy 87.95622 -51.401243) (xy 87.885615 -51.373636)
			(xy 87.818344 -51.33868) (xy 87.755169 -51.296772) (xy 87.696807 -51.248386) (xy 87.643919 -51.19407)
			(xy 87.597104 -51.134441) (xy 87.556892 -51.070173) (xy 87.52374 -51.001996) (xy 87.498022 -50.93068)
			(xy 87.48003 -50.857035) (xy 87.469968 -50.781895) (xy 87.467949 -50.706111) (xy 86.351871 -50.706111)
			(xy 86.349852 -50.781895) (xy 86.33979 -50.857035) (xy 86.321798 -50.93068) (xy 86.29608 -51.001996)
			(xy 86.262928 -51.070173) (xy 86.222716 -51.134441) (xy 86.175901 -51.19407) (xy 86.123013 -51.248386)
			(xy 86.064651 -51.296772) (xy 86.001476 -51.33868) (xy 85.934205 -51.373636) (xy 85.8636 -51.401243)
			(xy 85.790459 -51.421189) (xy 85.715614 -51.433248) (xy 85.63991 -51.437283) (xy 85.564206 -51.433248)
			(xy 85.489361 -51.421189) (xy 85.41622 -51.401243) (xy 85.345615 -51.373636) (xy 85.278344 -51.33868)
			(xy 85.215169 -51.296772) (xy 85.156807 -51.248386) (xy 85.103919 -51.19407) (xy 85.057104 -51.134441)
			(xy 85.016892 -51.070173) (xy 84.98374 -51.001996) (xy 84.958022 -50.93068) (xy 84.94003 -50.857035)
			(xy 84.929968 -50.781895) (xy 84.927949 -50.706111) (xy 82.290588 -50.706111) (xy 82.290339 -50.706179)
			(xy 82.215494 -50.718238) (xy 82.13979 -50.722273) (xy 82.064086 -50.718238) (xy 81.989241 -50.706179)
			(xy 81.9161 -50.686233) (xy 81.845495 -50.658626) (xy 81.778224 -50.62367) (xy 81.715049 -50.581762)
			(xy 81.656687 -50.533376) (xy 81.603799 -50.47906) (xy 81.556984 -50.419431) (xy 81.516772 -50.355163)
			(xy 81.48362 -50.286986) (xy 81.457902 -50.21567) (xy 81.43991 -50.142025) (xy 81.429848 -50.066885)
			(xy 81.427829 -49.991101) (xy 80.311751 -49.991101) (xy 80.309732 -50.066885) (xy 80.29967 -50.142025)
			(xy 80.281678 -50.21567) (xy 80.25596 -50.286986) (xy 80.222808 -50.355163) (xy 80.182596 -50.419431)
			(xy 80.135781 -50.47906) (xy 80.082893 -50.533376) (xy 80.024531 -50.581762) (xy 79.961356 -50.62367)
			(xy 79.894085 -50.658626) (xy 79.82348 -50.686233) (xy 79.750339 -50.706179) (xy 79.675494 -50.718238)
			(xy 79.59979 -50.722273) (xy 79.524086 -50.718238) (xy 79.449241 -50.706179) (xy 79.3761 -50.686233)
			(xy 79.305495 -50.658626) (xy 79.238224 -50.62367) (xy 79.175049 -50.581762) (xy 79.116687 -50.533376)
			(xy 79.063799 -50.47906) (xy 79.016984 -50.419431) (xy 78.976772 -50.355163) (xy 78.94362 -50.286986)
			(xy 78.917902 -50.21567) (xy 78.89991 -50.142025) (xy 78.889848 -50.066885) (xy 78.887829 -49.991101)
			(xy 77.771751 -49.991101) (xy 77.769732 -50.066885) (xy 77.75967 -50.142025) (xy 77.741678 -50.21567)
			(xy 77.71596 -50.286986) (xy 77.682808 -50.355163) (xy 77.642596 -50.419431) (xy 77.595781 -50.47906)
			(xy 77.542893 -50.533376) (xy 77.484531 -50.581762) (xy 77.421356 -50.62367) (xy 77.354085 -50.658626)
			(xy 77.28348 -50.686233) (xy 77.210339 -50.706179) (xy 77.135494 -50.718238) (xy 77.05979 -50.722273)
			(xy 76.984086 -50.718238) (xy 76.909241 -50.706179) (xy 76.8361 -50.686233) (xy 76.765495 -50.658626)
			(xy 76.698224 -50.62367) (xy 76.635049 -50.581762) (xy 76.576687 -50.533376) (xy 76.523799 -50.47906)
			(xy 76.476984 -50.419431) (xy 76.436772 -50.355163) (xy 76.40362 -50.286986) (xy 76.377902 -50.21567)
			(xy 76.35991 -50.142025) (xy 76.349848 -50.066885) (xy 76.347829 -49.991101) (xy 75.231751 -49.991101)
			(xy 75.229732 -50.066885) (xy 75.21967 -50.142025) (xy 75.201678 -50.21567) (xy 75.17596 -50.286986)
			(xy 75.142808 -50.355163) (xy 75.102596 -50.419431) (xy 75.055781 -50.47906) (xy 75.002893 -50.533376)
			(xy 74.944531 -50.581762) (xy 74.881356 -50.62367) (xy 74.814085 -50.658626) (xy 74.74348 -50.686233)
			(xy 74.670339 -50.706179) (xy 74.595494 -50.718238) (xy 74.51979 -50.722273) (xy 74.444086 -50.718238)
			(xy 74.369241 -50.706179) (xy 74.2961 -50.686233) (xy 74.225495 -50.658626) (xy 74.158224 -50.62367)
			(xy 74.095049 -50.581762) (xy 74.036687 -50.533376) (xy 73.983799 -50.47906) (xy 73.936984 -50.419431)
			(xy 73.896772 -50.355163) (xy 73.86362 -50.286986) (xy 73.837902 -50.21567) (xy 73.81991 -50.142025)
			(xy 73.809848 -50.066885) (xy 73.807829 -49.991101) (xy 72.691751 -49.991101) (xy 72.689732 -50.066885)
			(xy 72.67967 -50.142025) (xy 72.661678 -50.21567) (xy 72.63596 -50.286986) (xy 72.602808 -50.355163)
			(xy 72.562596 -50.419431) (xy 72.515781 -50.47906) (xy 72.462893 -50.533376) (xy 72.404531 -50.581762)
			(xy 72.341356 -50.62367) (xy 72.274085 -50.658626) (xy 72.20348 -50.686233) (xy 72.130339 -50.706179)
			(xy 72.055494 -50.718238) (xy 71.97979 -50.722273) (xy 71.904086 -50.718238) (xy 71.829241 -50.706179)
			(xy 71.7561 -50.686233) (xy 71.685495 -50.658626) (xy 71.618224 -50.62367) (xy 71.555049 -50.581762)
			(xy 71.496687 -50.533376) (xy 71.443799 -50.47906) (xy 71.396984 -50.419431) (xy 71.356772 -50.355163)
			(xy 71.32362 -50.286986) (xy 71.297902 -50.21567) (xy 71.27991 -50.142025) (xy 71.269848 -50.066885)
			(xy 71.267829 -49.991101) (xy 70.151751 -49.991101) (xy 70.149732 -50.066885) (xy 70.13967 -50.142025)
			(xy 70.121678 -50.21567) (xy 70.09596 -50.286986) (xy 70.062808 -50.355163) (xy 70.022596 -50.419431)
			(xy 69.975781 -50.47906) (xy 69.922893 -50.533376) (xy 69.864531 -50.581762) (xy 69.801356 -50.62367)
			(xy 69.734085 -50.658626) (xy 69.66348 -50.686233) (xy 69.590339 -50.706179) (xy 69.515494 -50.718238)
			(xy 69.43979 -50.722273) (xy 69.364086 -50.718238) (xy 69.289241 -50.706179) (xy 69.2161 -50.686233)
			(xy 69.145495 -50.658626) (xy 69.078224 -50.62367) (xy 69.015049 -50.581762) (xy 68.956687 -50.533376)
			(xy 68.903799 -50.47906) (xy 68.856984 -50.419431) (xy 68.816772 -50.355163) (xy 68.78362 -50.286986)
			(xy 68.757902 -50.21567) (xy 68.73991 -50.142025) (xy 68.729848 -50.066885) (xy 68.727829 -49.991101)
			(xy 67.611751 -49.991101) (xy 67.609732 -50.066885) (xy 67.59967 -50.142025) (xy 67.581678 -50.21567)
			(xy 67.55596 -50.286986) (xy 67.522808 -50.355163) (xy 67.482596 -50.419431) (xy 67.435781 -50.47906)
			(xy 67.382893 -50.533376) (xy 67.324531 -50.581762) (xy 67.261356 -50.62367) (xy 67.194085 -50.658626)
			(xy 67.12348 -50.686233) (xy 67.050339 -50.706179) (xy 66.975494 -50.718238) (xy 66.89979 -50.722273)
			(xy 66.824086 -50.718238) (xy 66.749241 -50.706179) (xy 66.6761 -50.686233) (xy 66.605495 -50.658626)
			(xy 66.538224 -50.62367) (xy 66.475049 -50.581762) (xy 66.416687 -50.533376) (xy 66.363799 -50.47906)
			(xy 66.316984 -50.419431) (xy 66.276772 -50.355163) (xy 66.24362 -50.286986) (xy 66.217902 -50.21567)
			(xy 66.19991 -50.142025) (xy 66.189848 -50.066885) (xy 66.187829 -49.991101) (xy 65.071751 -49.991101)
			(xy 65.069732 -50.066885) (xy 65.05967 -50.142025) (xy 65.041678 -50.21567) (xy 65.01596 -50.286986)
			(xy 64.982808 -50.355163) (xy 64.942596 -50.419431) (xy 64.895781 -50.47906) (xy 64.842893 -50.533376)
			(xy 64.784531 -50.581762) (xy 64.721356 -50.62367) (xy 64.654085 -50.658626) (xy 64.58348 -50.686233)
			(xy 64.510339 -50.706179) (xy 64.435494 -50.718238) (xy 64.35979 -50.722273) (xy 64.284086 -50.718238)
			(xy 64.209241 -50.706179) (xy 64.1361 -50.686233) (xy 64.065495 -50.658626) (xy 63.998224 -50.62367)
			(xy 63.935049 -50.581762) (xy 63.876687 -50.533376) (xy 63.823799 -50.47906) (xy 63.776984 -50.419431)
			(xy 63.736772 -50.355163) (xy 63.70362 -50.286986) (xy 63.677902 -50.21567) (xy 63.65991 -50.142025)
			(xy 63.649848 -50.066885) (xy 63.647829 -49.991101) (xy 42.474432 -49.991101) (xy 42.525324 -50.027542)
			(xy 42.614813 -50.101469) (xy 42.698988 -50.181395) (xy 42.777449 -50.266938) (xy 42.849821 -50.357689)
			(xy 42.91576 -50.453218) (xy 42.974951 -50.553068) (xy 43.027112 -50.656764) (xy 43.071995 -50.763811)
			(xy 43.109385 -50.8737) (xy 43.139105 -50.985907) (xy 43.161013 -51.099897) (xy 43.175004 -51.215126)
			(xy 43.181013 -51.331047) (xy 43.179009 -51.447105) (xy 43.169003 -51.562749) (xy 43.151043 -51.677427)
			(xy 43.125213 -51.790593) (xy 43.091638 -51.901707) (xy 43.06342 -51.976111) (xy 86.197949 -51.976111)
			(xy 86.203998 -51.900541) (xy 86.218045 -51.826043) (xy 86.239931 -51.75346) (xy 86.269408 -51.683614)
			(xy 86.306143 -51.617297) (xy 86.349718 -51.555261) (xy 86.39964 -51.498208) (xy 86.455344 -51.446784)
			(xy 86.516199 -51.401573) (xy 86.581514 -51.363086) (xy 86.65055 -51.33176) (xy 86.722525 -51.30795)
			(xy 86.796623 -51.291925) (xy 86.872004 -51.283866) (xy 86.90991 -51.283362) (xy 86.947816 -51.283866)
			(xy 87.023197 -51.291925) (xy 87.097295 -51.30795) (xy 87.16927 -51.33176) (xy 87.238306 -51.363086)
			(xy 87.303621 -51.401573) (xy 87.364476 -51.446784) (xy 87.42018 -51.498208) (xy 87.470102 -51.555261)
			(xy 87.513677 -51.617297) (xy 87.550412 -51.683614) (xy 87.579889 -51.75346) (xy 87.601775 -51.826043)
			(xy 87.615822 -51.900541) (xy 87.621871 -51.976111) (xy 88.737949 -51.976111) (xy 88.743998 -51.900541)
			(xy 88.758045 -51.826043) (xy 88.779931 -51.75346) (xy 88.809408 -51.683614) (xy 88.846143 -51.617297)
			(xy 88.889718 -51.555261) (xy 88.93964 -51.498208) (xy 88.995344 -51.446784) (xy 89.056199 -51.401573)
			(xy 89.121514 -51.363086) (xy 89.19055 -51.33176) (xy 89.262525 -51.30795) (xy 89.336623 -51.291925)
			(xy 89.412004 -51.283866) (xy 89.44991 -51.283362) (xy 89.487816 -51.283866) (xy 89.563197 -51.291925)
			(xy 89.637295 -51.30795) (xy 89.70927 -51.33176) (xy 89.778306 -51.363086) (xy 89.843621 -51.401573)
			(xy 89.904476 -51.446784) (xy 89.96018 -51.498208) (xy 90.010102 -51.555261) (xy 90.053677 -51.617297)
			(xy 90.090412 -51.683614) (xy 90.119889 -51.75346) (xy 90.141775 -51.826043) (xy 90.155822 -51.900541)
			(xy 90.161871 -51.976111) (xy 91.277949 -51.976111) (xy 91.283998 -51.900541) (xy 91.298045 -51.826043)
			(xy 91.319931 -51.75346) (xy 91.349408 -51.683614) (xy 91.386143 -51.617297) (xy 91.429718 -51.555261)
			(xy 91.47964 -51.498208) (xy 91.535344 -51.446784) (xy 91.596199 -51.401573) (xy 91.661514 -51.363086)
			(xy 91.73055 -51.33176) (xy 91.802525 -51.30795) (xy 91.876623 -51.291925) (xy 91.952004 -51.283866)
			(xy 91.98991 -51.283362) (xy 92.027816 -51.283866) (xy 92.103197 -51.291925) (xy 92.177295 -51.30795)
			(xy 92.24927 -51.33176) (xy 92.318306 -51.363086) (xy 92.383621 -51.401573) (xy 92.444476 -51.446784)
			(xy 92.50018 -51.498208) (xy 92.550102 -51.555261) (xy 92.593677 -51.617297) (xy 92.630412 -51.683614)
			(xy 92.659889 -51.75346) (xy 92.681775 -51.826043) (xy 92.695822 -51.900541) (xy 92.701871 -51.976111)
			(xy 92.699852 -52.051895) (xy 92.68979 -52.127035) (xy 92.671798 -52.20068) (xy 92.64608 -52.271996)
			(xy 92.612928 -52.340173) (xy 92.572716 -52.404441) (xy 92.525901 -52.46407) (xy 92.473013 -52.518386)
			(xy 92.414651 -52.566772) (xy 92.351476 -52.60868) (xy 92.284205 -52.643636) (xy 92.2136 -52.671243)
			(xy 92.177855 -52.680991) (xy 93.154757 -52.680991) (xy 93.160779 -52.564808) (xy 93.174802 -52.449317)
			(xy 93.19676 -52.335069) (xy 93.226547 -52.222608) (xy 93.264022 -52.11247) (xy 93.309007 -52.00518)
			(xy 93.361286 -51.901249) (xy 93.420611 -51.801173) (xy 93.486699 -51.705427) (xy 93.559235 -51.61447)
			(xy 93.637874 -51.528734) (xy 93.72224 -51.448627) (xy 93.811932 -51.374531) (xy 93.906522 -51.306801)
			(xy 94.00556 -51.245757) (xy 94.108573 -51.191692) (xy 94.21507 -51.144862) (xy 94.324545 -51.105491)
			(xy 94.436475 -51.073767) (xy 94.550327 -51.049841) (xy 94.665559 -51.033827) (xy 94.781621 -51.0258)
			(xy 94.83979 -51.025298) (xy 94.897959 -51.0258) (xy 95.014021 -51.033827) (xy 95.129253 -51.049841)
			(xy 95.243105 -51.073767) (xy 95.355035 -51.105491) (xy 95.46451 -51.144862) (xy 95.571007 -51.191692)
			(xy 95.67402 -51.245757) (xy 95.773058 -51.306801) (xy 95.867648 -51.374531) (xy 95.95734 -51.448627)
			(xy 96.041706 -51.528734) (xy 96.120345 -51.61447) (xy 96.192881 -51.705427) (xy 96.258969 -51.801173)
			(xy 96.318294 -51.901249) (xy 96.370573 -52.00518) (xy 96.415558 -52.11247) (xy 96.453033 -52.222608)
			(xy 96.48282 -52.335069) (xy 96.504778 -52.449317) (xy 96.518801 -52.564808) (xy 96.524823 -52.680991)
			(xy 96.522815 -52.797313) (xy 96.512786 -52.913219) (xy 96.494785 -53.028156) (xy 96.468897 -53.141579)
			(xy 96.435246 -53.252944) (xy 96.393992 -53.361723) (xy 96.345331 -53.467397) (xy 96.289495 -53.569461)
			(xy 96.226752 -53.66743) (xy 96.157398 -53.760837) (xy 96.081766 -53.849237) (xy 96.000215 -53.932208)
			(xy 95.913134 -54.009355) (xy 95.820938 -54.08031) (xy 95.724066 -54.144736) (xy 95.622981 -54.202325)
			(xy 95.518163 -54.252802) (xy 95.410112 -54.295928) (xy 95.299344 -54.331497) (xy 95.186385 -54.359339)
			(xy 95.071775 -54.379321) (xy 94.95606 -54.391348) (xy 94.83979 -54.395364) (xy 94.72352 -54.391348)
			(xy 94.607805 -54.379321) (xy 94.493195 -54.359339) (xy 94.380236 -54.331497) (xy 94.269468 -54.295928)
			(xy 94.161417 -54.252802) (xy 94.056599 -54.202325) (xy 93.955514 -54.144736) (xy 93.858642 -54.08031)
			(xy 93.766446 -54.009355) (xy 93.679365 -53.932208) (xy 93.597814 -53.849237) (xy 93.522182 -53.760837)
			(xy 93.452828 -53.66743) (xy 93.390085 -53.569461) (xy 93.334249 -53.467397) (xy 93.285588 -53.361723)
			(xy 93.244334 -53.252944) (xy 93.210683 -53.141579) (xy 93.184795 -53.028156) (xy 93.166794 -52.913219)
			(xy 93.156765 -52.797313) (xy 93.154757 -52.680991) (xy 92.177855 -52.680991) (xy 92.140459 -52.691189)
			(xy 92.065614 -52.703248) (xy 91.98991 -52.707283) (xy 91.914206 -52.703248) (xy 91.839361 -52.691189)
			(xy 91.76622 -52.671243) (xy 91.695615 -52.643636) (xy 91.628344 -52.60868) (xy 91.565169 -52.566772)
			(xy 91.506807 -52.518386) (xy 91.453919 -52.46407) (xy 91.407104 -52.404441) (xy 91.366892 -52.340173)
			(xy 91.33374 -52.271996) (xy 91.308022 -52.20068) (xy 91.29003 -52.127035) (xy 91.279968 -52.051895)
			(xy 91.277949 -51.976111) (xy 90.161871 -51.976111) (xy 90.159852 -52.051895) (xy 90.14979 -52.127035)
			(xy 90.131798 -52.20068) (xy 90.10608 -52.271996) (xy 90.072928 -52.340173) (xy 90.032716 -52.404441)
			(xy 89.985901 -52.46407) (xy 89.933013 -52.518386) (xy 89.874651 -52.566772) (xy 89.811476 -52.60868)
			(xy 89.744205 -52.643636) (xy 89.6736 -52.671243) (xy 89.600459 -52.691189) (xy 89.525614 -52.703248)
			(xy 89.44991 -52.707283) (xy 89.374206 -52.703248) (xy 89.299361 -52.691189) (xy 89.22622 -52.671243)
			(xy 89.155615 -52.643636) (xy 89.088344 -52.60868) (xy 89.025169 -52.566772) (xy 88.966807 -52.518386)
			(xy 88.913919 -52.46407) (xy 88.867104 -52.404441) (xy 88.826892 -52.340173) (xy 88.79374 -52.271996)
			(xy 88.768022 -52.20068) (xy 88.75003 -52.127035) (xy 88.739968 -52.051895) (xy 88.737949 -51.976111)
			(xy 87.621871 -51.976111) (xy 87.619852 -52.051895) (xy 87.60979 -52.127035) (xy 87.591798 -52.20068)
			(xy 87.56608 -52.271996) (xy 87.532928 -52.340173) (xy 87.492716 -52.404441) (xy 87.445901 -52.46407)
			(xy 87.393013 -52.518386) (xy 87.334651 -52.566772) (xy 87.271476 -52.60868) (xy 87.204205 -52.643636)
			(xy 87.1336 -52.671243) (xy 87.060459 -52.691189) (xy 86.985614 -52.703248) (xy 86.90991 -52.707283)
			(xy 86.834206 -52.703248) (xy 86.759361 -52.691189) (xy 86.68622 -52.671243) (xy 86.615615 -52.643636)
			(xy 86.548344 -52.60868) (xy 86.485169 -52.566772) (xy 86.426807 -52.518386) (xy 86.373919 -52.46407)
			(xy 86.327104 -52.404441) (xy 86.286892 -52.340173) (xy 86.25374 -52.271996) (xy 86.228022 -52.20068)
			(xy 86.21003 -52.127035) (xy 86.199968 -52.051895) (xy 86.197949 -51.976111) (xy 43.06342 -51.976111)
			(xy 43.050477 -52.01024) (xy 43.001926 -52.115674) (xy 42.946217 -52.217508) (xy 42.883615 -52.315256)
			(xy 42.814419 -52.408451) (xy 42.738957 -52.496651) (xy 42.65759 -52.579434) (xy 42.570706 -52.656407)
			(xy 42.525601 -52.691121) (xy 63.647829 -52.691121) (xy 63.653878 -52.615551) (xy 63.667925 -52.541053)
			(xy 63.689811 -52.46847) (xy 63.719288 -52.398624) (xy 63.756023 -52.332307) (xy 63.799598 -52.270271)
			(xy 63.84952 -52.213218) (xy 63.905224 -52.161794) (xy 63.966079 -52.116583) (xy 64.031394 -52.078096)
			(xy 64.10043 -52.04677) (xy 64.172405 -52.02296) (xy 64.246503 -52.006935) (xy 64.321884 -51.998876)
			(xy 64.35979 -51.998372) (xy 64.397696 -51.998876) (xy 64.473077 -52.006935) (xy 64.547175 -52.02296)
			(xy 64.61915 -52.04677) (xy 64.688186 -52.078096) (xy 64.753501 -52.116583) (xy 64.814356 -52.161794)
			(xy 64.87006 -52.213218) (xy 64.919982 -52.270271) (xy 64.963557 -52.332307) (xy 65.000292 -52.398624)
			(xy 65.029769 -52.46847) (xy 65.051655 -52.541053) (xy 65.065702 -52.615551) (xy 65.071751 -52.691121)
			(xy 66.187829 -52.691121) (xy 66.193878 -52.615551) (xy 66.207925 -52.541053) (xy 66.229811 -52.46847)
			(xy 66.259288 -52.398624) (xy 66.296023 -52.332307) (xy 66.339598 -52.270271) (xy 66.38952 -52.213218)
			(xy 66.445224 -52.161794) (xy 66.506079 -52.116583) (xy 66.571394 -52.078096) (xy 66.64043 -52.04677)
			(xy 66.712405 -52.02296) (xy 66.786503 -52.006935) (xy 66.861884 -51.998876) (xy 66.89979 -51.998372)
			(xy 66.937696 -51.998876) (xy 67.013077 -52.006935) (xy 67.087175 -52.02296) (xy 67.15915 -52.04677)
			(xy 67.228186 -52.078096) (xy 67.293501 -52.116583) (xy 67.354356 -52.161794) (xy 67.41006 -52.213218)
			(xy 67.459982 -52.270271) (xy 67.503557 -52.332307) (xy 67.540292 -52.398624) (xy 67.569769 -52.46847)
			(xy 67.591655 -52.541053) (xy 67.605702 -52.615551) (xy 67.611751 -52.691121) (xy 68.727829 -52.691121)
			(xy 68.733878 -52.615551) (xy 68.747925 -52.541053) (xy 68.769811 -52.46847) (xy 68.799288 -52.398624)
			(xy 68.836023 -52.332307) (xy 68.879598 -52.270271) (xy 68.92952 -52.213218) (xy 68.985224 -52.161794)
			(xy 69.046079 -52.116583) (xy 69.111394 -52.078096) (xy 69.18043 -52.04677) (xy 69.252405 -52.02296)
			(xy 69.326503 -52.006935) (xy 69.401884 -51.998876) (xy 69.43979 -51.998372) (xy 69.477696 -51.998876)
			(xy 69.553077 -52.006935) (xy 69.627175 -52.02296) (xy 69.69915 -52.04677) (xy 69.768186 -52.078096)
			(xy 69.833501 -52.116583) (xy 69.894356 -52.161794) (xy 69.95006 -52.213218) (xy 69.999982 -52.270271)
			(xy 70.043557 -52.332307) (xy 70.080292 -52.398624) (xy 70.109769 -52.46847) (xy 70.131655 -52.541053)
			(xy 70.145702 -52.615551) (xy 70.151751 -52.691121) (xy 71.267829 -52.691121) (xy 71.273878 -52.615551)
			(xy 71.287925 -52.541053) (xy 71.309811 -52.46847) (xy 71.339288 -52.398624) (xy 71.376023 -52.332307)
			(xy 71.419598 -52.270271) (xy 71.46952 -52.213218) (xy 71.525224 -52.161794) (xy 71.586079 -52.116583)
			(xy 71.651394 -52.078096) (xy 71.72043 -52.04677) (xy 71.792405 -52.02296) (xy 71.866503 -52.006935)
			(xy 71.941884 -51.998876) (xy 71.97979 -51.998372) (xy 72.017696 -51.998876) (xy 72.093077 -52.006935)
			(xy 72.167175 -52.02296) (xy 72.23915 -52.04677) (xy 72.308186 -52.078096) (xy 72.373501 -52.116583)
			(xy 72.434356 -52.161794) (xy 72.49006 -52.213218) (xy 72.539982 -52.270271) (xy 72.583557 -52.332307)
			(xy 72.620292 -52.398624) (xy 72.649769 -52.46847) (xy 72.671655 -52.541053) (xy 72.685702 -52.615551)
			(xy 72.691751 -52.691121) (xy 73.807829 -52.691121) (xy 73.813878 -52.615551) (xy 73.827925 -52.541053)
			(xy 73.849811 -52.46847) (xy 73.879288 -52.398624) (xy 73.916023 -52.332307) (xy 73.959598 -52.270271)
			(xy 74.00952 -52.213218) (xy 74.065224 -52.161794) (xy 74.126079 -52.116583) (xy 74.191394 -52.078096)
			(xy 74.26043 -52.04677) (xy 74.332405 -52.02296) (xy 74.406503 -52.006935) (xy 74.481884 -51.998876)
			(xy 74.51979 -51.998372) (xy 74.557696 -51.998876) (xy 74.633077 -52.006935) (xy 74.707175 -52.02296)
			(xy 74.77915 -52.04677) (xy 74.848186 -52.078096) (xy 74.913501 -52.116583) (xy 74.974356 -52.161794)
			(xy 75.03006 -52.213218) (xy 75.079982 -52.270271) (xy 75.123557 -52.332307) (xy 75.160292 -52.398624)
			(xy 75.189769 -52.46847) (xy 75.211655 -52.541053) (xy 75.225702 -52.615551) (xy 75.231751 -52.691121)
			(xy 76.347829 -52.691121) (xy 76.353878 -52.615551) (xy 76.367925 -52.541053) (xy 76.389811 -52.46847)
			(xy 76.419288 -52.398624) (xy 76.456023 -52.332307) (xy 76.499598 -52.270271) (xy 76.54952 -52.213218)
			(xy 76.605224 -52.161794) (xy 76.666079 -52.116583) (xy 76.731394 -52.078096) (xy 76.80043 -52.04677)
			(xy 76.872405 -52.02296) (xy 76.946503 -52.006935) (xy 77.021884 -51.998876) (xy 77.05979 -51.998372)
			(xy 77.097696 -51.998876) (xy 77.173077 -52.006935) (xy 77.247175 -52.02296) (xy 77.31915 -52.04677)
			(xy 77.388186 -52.078096) (xy 77.453501 -52.116583) (xy 77.514356 -52.161794) (xy 77.57006 -52.213218)
			(xy 77.619982 -52.270271) (xy 77.663557 -52.332307) (xy 77.700292 -52.398624) (xy 77.729769 -52.46847)
			(xy 77.751655 -52.541053) (xy 77.765702 -52.615551) (xy 77.771751 -52.691121) (xy 78.887829 -52.691121)
			(xy 78.893878 -52.615551) (xy 78.907925 -52.541053) (xy 78.929811 -52.46847) (xy 78.959288 -52.398624)
			(xy 78.996023 -52.332307) (xy 79.039598 -52.270271) (xy 79.08952 -52.213218) (xy 79.145224 -52.161794)
			(xy 79.206079 -52.116583) (xy 79.271394 -52.078096) (xy 79.34043 -52.04677) (xy 79.412405 -52.02296)
			(xy 79.486503 -52.006935) (xy 79.561884 -51.998876) (xy 79.59979 -51.998372) (xy 79.637696 -51.998876)
			(xy 79.713077 -52.006935) (xy 79.787175 -52.02296) (xy 79.85915 -52.04677) (xy 79.928186 -52.078096)
			(xy 79.993501 -52.116583) (xy 80.054356 -52.161794) (xy 80.11006 -52.213218) (xy 80.159982 -52.270271)
			(xy 80.203557 -52.332307) (xy 80.240292 -52.398624) (xy 80.269769 -52.46847) (xy 80.291655 -52.541053)
			(xy 80.305702 -52.615551) (xy 80.311751 -52.691121) (xy 81.427829 -52.691121) (xy 81.433878 -52.615551)
			(xy 81.447925 -52.541053) (xy 81.469811 -52.46847) (xy 81.499288 -52.398624) (xy 81.536023 -52.332307)
			(xy 81.579598 -52.270271) (xy 81.62952 -52.213218) (xy 81.685224 -52.161794) (xy 81.746079 -52.116583)
			(xy 81.811394 -52.078096) (xy 81.88043 -52.04677) (xy 81.952405 -52.02296) (xy 82.026503 -52.006935)
			(xy 82.101884 -51.998876) (xy 82.13979 -51.998372) (xy 82.177696 -51.998876) (xy 82.253077 -52.006935)
			(xy 82.327175 -52.02296) (xy 82.39915 -52.04677) (xy 82.468186 -52.078096) (xy 82.533501 -52.116583)
			(xy 82.594356 -52.161794) (xy 82.65006 -52.213218) (xy 82.699982 -52.270271) (xy 82.743557 -52.332307)
			(xy 82.780292 -52.398624) (xy 82.809769 -52.46847) (xy 82.831655 -52.541053) (xy 82.845702 -52.615551)
			(xy 82.851751 -52.691121) (xy 82.849732 -52.766905) (xy 82.83967 -52.842045) (xy 82.821678 -52.91569)
			(xy 82.79596 -52.987006) (xy 82.762808 -53.055183) (xy 82.722596 -53.119451) (xy 82.675781 -53.17908)
			(xy 82.622893 -53.233396) (xy 82.607556 -53.246111) (xy 84.927949 -53.246111) (xy 84.933998 -53.170541)
			(xy 84.948045 -53.096043) (xy 84.969931 -53.02346) (xy 84.999408 -52.953614) (xy 85.036143 -52.887297)
			(xy 85.079718 -52.825261) (xy 85.12964 -52.768208) (xy 85.185344 -52.716784) (xy 85.246199 -52.671573)
			(xy 85.311514 -52.633086) (xy 85.38055 -52.60176) (xy 85.452525 -52.57795) (xy 85.526623 -52.561925)
			(xy 85.602004 -52.553866) (xy 85.63991 -52.553362) (xy 85.677816 -52.553866) (xy 85.753197 -52.561925)
			(xy 85.827295 -52.57795) (xy 85.89927 -52.60176) (xy 85.968306 -52.633086) (xy 86.033621 -52.671573)
			(xy 86.094476 -52.716784) (xy 86.15018 -52.768208) (xy 86.200102 -52.825261) (xy 86.243677 -52.887297)
			(xy 86.280412 -52.953614) (xy 86.309889 -53.02346) (xy 86.331775 -53.096043) (xy 86.345822 -53.170541)
			(xy 86.351871 -53.246111) (xy 87.467949 -53.246111) (xy 87.473998 -53.170541) (xy 87.488045 -53.096043)
			(xy 87.509931 -53.02346) (xy 87.539408 -52.953614) (xy 87.576143 -52.887297) (xy 87.619718 -52.825261)
			(xy 87.66964 -52.768208) (xy 87.725344 -52.716784) (xy 87.786199 -52.671573) (xy 87.851514 -52.633086)
			(xy 87.92055 -52.60176) (xy 87.992525 -52.57795) (xy 88.066623 -52.561925) (xy 88.142004 -52.553866)
			(xy 88.17991 -52.553362) (xy 88.217816 -52.553866) (xy 88.293197 -52.561925) (xy 88.367295 -52.57795)
			(xy 88.43927 -52.60176) (xy 88.508306 -52.633086) (xy 88.573621 -52.671573) (xy 88.634476 -52.716784)
			(xy 88.69018 -52.768208) (xy 88.740102 -52.825261) (xy 88.783677 -52.887297) (xy 88.820412 -52.953614)
			(xy 88.849889 -53.02346) (xy 88.871775 -53.096043) (xy 88.885822 -53.170541) (xy 88.891871 -53.246111)
			(xy 90.007949 -53.246111) (xy 90.013998 -53.170541) (xy 90.028045 -53.096043) (xy 90.049931 -53.02346)
			(xy 90.079408 -52.953614) (xy 90.116143 -52.887297) (xy 90.159718 -52.825261) (xy 90.20964 -52.768208)
			(xy 90.265344 -52.716784) (xy 90.326199 -52.671573) (xy 90.391514 -52.633086) (xy 90.46055 -52.60176)
			(xy 90.532525 -52.57795) (xy 90.606623 -52.561925) (xy 90.682004 -52.553866) (xy 90.71991 -52.553362)
			(xy 90.757816 -52.553866) (xy 90.833197 -52.561925) (xy 90.907295 -52.57795) (xy 90.97927 -52.60176)
			(xy 91.048306 -52.633086) (xy 91.113621 -52.671573) (xy 91.174476 -52.716784) (xy 91.23018 -52.768208)
			(xy 91.280102 -52.825261) (xy 91.323677 -52.887297) (xy 91.360412 -52.953614) (xy 91.389889 -53.02346)
			(xy 91.411775 -53.096043) (xy 91.425822 -53.170541) (xy 91.431871 -53.246111) (xy 91.429852 -53.321895)
			(xy 91.41979 -53.397035) (xy 91.401798 -53.47068) (xy 91.37608 -53.541996) (xy 91.342928 -53.610173)
			(xy 91.302716 -53.674441) (xy 91.255901 -53.73407) (xy 91.203013 -53.788386) (xy 91.144651 -53.836772)
			(xy 91.081476 -53.87868) (xy 91.014205 -53.913636) (xy 90.9436 -53.941243) (xy 90.870459 -53.961189)
			(xy 90.795614 -53.973248) (xy 90.71991 -53.977283) (xy 90.644206 -53.973248) (xy 90.569361 -53.961189)
			(xy 90.49622 -53.941243) (xy 90.425615 -53.913636) (xy 90.358344 -53.87868) (xy 90.295169 -53.836772)
			(xy 90.236807 -53.788386) (xy 90.183919 -53.73407) (xy 90.137104 -53.674441) (xy 90.096892 -53.610173)
			(xy 90.06374 -53.541996) (xy 90.038022 -53.47068) (xy 90.02003 -53.397035) (xy 90.009968 -53.321895)
			(xy 90.007949 -53.246111) (xy 88.891871 -53.246111) (xy 88.889852 -53.321895) (xy 88.87979 -53.397035)
			(xy 88.861798 -53.47068) (xy 88.83608 -53.541996) (xy 88.802928 -53.610173) (xy 88.762716 -53.674441)
			(xy 88.715901 -53.73407) (xy 88.663013 -53.788386) (xy 88.604651 -53.836772) (xy 88.541476 -53.87868)
			(xy 88.474205 -53.913636) (xy 88.4036 -53.941243) (xy 88.330459 -53.961189) (xy 88.255614 -53.973248)
			(xy 88.17991 -53.977283) (xy 88.104206 -53.973248) (xy 88.029361 -53.961189) (xy 87.95622 -53.941243)
			(xy 87.885615 -53.913636) (xy 87.818344 -53.87868) (xy 87.755169 -53.836772) (xy 87.696807 -53.788386)
			(xy 87.643919 -53.73407) (xy 87.597104 -53.674441) (xy 87.556892 -53.610173) (xy 87.52374 -53.541996)
			(xy 87.498022 -53.47068) (xy 87.48003 -53.397035) (xy 87.469968 -53.321895) (xy 87.467949 -53.246111)
			(xy 86.351871 -53.246111) (xy 86.349852 -53.321895) (xy 86.33979 -53.397035) (xy 86.321798 -53.47068)
			(xy 86.29608 -53.541996) (xy 86.262928 -53.610173) (xy 86.222716 -53.674441) (xy 86.175901 -53.73407)
			(xy 86.123013 -53.788386) (xy 86.064651 -53.836772) (xy 86.001476 -53.87868) (xy 85.934205 -53.913636)
			(xy 85.8636 -53.941243) (xy 85.790459 -53.961189) (xy 85.715614 -53.973248) (xy 85.63991 -53.977283)
			(xy 85.564206 -53.973248) (xy 85.489361 -53.961189) (xy 85.41622 -53.941243) (xy 85.345615 -53.913636)
			(xy 85.278344 -53.87868) (xy 85.215169 -53.836772) (xy 85.156807 -53.788386) (xy 85.103919 -53.73407)
			(xy 85.057104 -53.674441) (xy 85.016892 -53.610173) (xy 84.98374 -53.541996) (xy 84.958022 -53.47068)
			(xy 84.94003 -53.397035) (xy 84.929968 -53.321895) (xy 84.927949 -53.246111) (xy 82.607556 -53.246111)
			(xy 82.564531 -53.281782) (xy 82.501356 -53.32369) (xy 82.434085 -53.358646) (xy 82.36348 -53.386253)
			(xy 82.290339 -53.406199) (xy 82.215494 -53.418258) (xy 82.13979 -53.422293) (xy 82.064086 -53.418258)
			(xy 81.989241 -53.406199) (xy 81.9161 -53.386253) (xy 81.845495 -53.358646) (xy 81.778224 -53.32369)
			(xy 81.715049 -53.281782) (xy 81.656687 -53.233396) (xy 81.603799 -53.17908) (xy 81.556984 -53.119451)
			(xy 81.516772 -53.055183) (xy 81.48362 -52.987006) (xy 81.457902 -52.91569) (xy 81.43991 -52.842045)
			(xy 81.429848 -52.766905) (xy 81.427829 -52.691121) (xy 80.311751 -52.691121) (xy 80.309732 -52.766905)
			(xy 80.29967 -52.842045) (xy 80.281678 -52.91569) (xy 80.25596 -52.987006) (xy 80.222808 -53.055183)
			(xy 80.182596 -53.119451) (xy 80.135781 -53.17908) (xy 80.082893 -53.233396) (xy 80.024531 -53.281782)
			(xy 79.961356 -53.32369) (xy 79.894085 -53.358646) (xy 79.82348 -53.386253) (xy 79.750339 -53.406199)
			(xy 79.675494 -53.418258) (xy 79.59979 -53.422293) (xy 79.524086 -53.418258) (xy 79.449241 -53.406199)
			(xy 79.3761 -53.386253) (xy 79.305495 -53.358646) (xy 79.238224 -53.32369) (xy 79.175049 -53.281782)
			(xy 79.116687 -53.233396) (xy 79.063799 -53.17908) (xy 79.016984 -53.119451) (xy 78.976772 -53.055183)
			(xy 78.94362 -52.987006) (xy 78.917902 -52.91569) (xy 78.89991 -52.842045) (xy 78.889848 -52.766905)
			(xy 78.887829 -52.691121) (xy 77.771751 -52.691121) (xy 77.769732 -52.766905) (xy 77.75967 -52.842045)
			(xy 77.741678 -52.91569) (xy 77.71596 -52.987006) (xy 77.682808 -53.055183) (xy 77.642596 -53.119451)
			(xy 77.595781 -53.17908) (xy 77.542893 -53.233396) (xy 77.484531 -53.281782) (xy 77.421356 -53.32369)
			(xy 77.354085 -53.358646) (xy 77.28348 -53.386253) (xy 77.210339 -53.406199) (xy 77.135494 -53.418258)
			(xy 77.05979 -53.422293) (xy 76.984086 -53.418258) (xy 76.909241 -53.406199) (xy 76.8361 -53.386253)
			(xy 76.765495 -53.358646) (xy 76.698224 -53.32369) (xy 76.635049 -53.281782) (xy 76.576687 -53.233396)
			(xy 76.523799 -53.17908) (xy 76.476984 -53.119451) (xy 76.436772 -53.055183) (xy 76.40362 -52.987006)
			(xy 76.377902 -52.91569) (xy 76.35991 -52.842045) (xy 76.349848 -52.766905) (xy 76.347829 -52.691121)
			(xy 75.231751 -52.691121) (xy 75.229732 -52.766905) (xy 75.21967 -52.842045) (xy 75.201678 -52.91569)
			(xy 75.17596 -52.987006) (xy 75.142808 -53.055183) (xy 75.102596 -53.119451) (xy 75.055781 -53.17908)
			(xy 75.002893 -53.233396) (xy 74.944531 -53.281782) (xy 74.881356 -53.32369) (xy 74.814085 -53.358646)
			(xy 74.74348 -53.386253) (xy 74.670339 -53.406199) (xy 74.595494 -53.418258) (xy 74.51979 -53.422293)
			(xy 74.444086 -53.418258) (xy 74.369241 -53.406199) (xy 74.2961 -53.386253) (xy 74.225495 -53.358646)
			(xy 74.158224 -53.32369) (xy 74.095049 -53.281782) (xy 74.036687 -53.233396) (xy 73.983799 -53.17908)
			(xy 73.936984 -53.119451) (xy 73.896772 -53.055183) (xy 73.86362 -52.987006) (xy 73.837902 -52.91569)
			(xy 73.81991 -52.842045) (xy 73.809848 -52.766905) (xy 73.807829 -52.691121) (xy 72.691751 -52.691121)
			(xy 72.689732 -52.766905) (xy 72.67967 -52.842045) (xy 72.661678 -52.91569) (xy 72.63596 -52.987006)
			(xy 72.602808 -53.055183) (xy 72.562596 -53.119451) (xy 72.515781 -53.17908) (xy 72.462893 -53.233396)
			(xy 72.404531 -53.281782) (xy 72.341356 -53.32369) (xy 72.274085 -53.358646) (xy 72.20348 -53.386253)
			(xy 72.130339 -53.406199) (xy 72.055494 -53.418258) (xy 71.97979 -53.422293) (xy 71.904086 -53.418258)
			(xy 71.829241 -53.406199) (xy 71.7561 -53.386253) (xy 71.685495 -53.358646) (xy 71.618224 -53.32369)
			(xy 71.555049 -53.281782) (xy 71.496687 -53.233396) (xy 71.443799 -53.17908) (xy 71.396984 -53.119451)
			(xy 71.356772 -53.055183) (xy 71.32362 -52.987006) (xy 71.297902 -52.91569) (xy 71.27991 -52.842045)
			(xy 71.269848 -52.766905) (xy 71.267829 -52.691121) (xy 70.151751 -52.691121) (xy 70.149732 -52.766905)
			(xy 70.13967 -52.842045) (xy 70.121678 -52.91569) (xy 70.09596 -52.987006) (xy 70.062808 -53.055183)
			(xy 70.022596 -53.119451) (xy 69.975781 -53.17908) (xy 69.922893 -53.233396) (xy 69.864531 -53.281782)
			(xy 69.801356 -53.32369) (xy 69.734085 -53.358646) (xy 69.66348 -53.386253) (xy 69.590339 -53.406199)
			(xy 69.515494 -53.418258) (xy 69.43979 -53.422293) (xy 69.364086 -53.418258) (xy 69.289241 -53.406199)
			(xy 69.2161 -53.386253) (xy 69.145495 -53.358646) (xy 69.078224 -53.32369) (xy 69.015049 -53.281782)
			(xy 68.956687 -53.233396) (xy 68.903799 -53.17908) (xy 68.856984 -53.119451) (xy 68.816772 -53.055183)
			(xy 68.78362 -52.987006) (xy 68.757902 -52.91569) (xy 68.73991 -52.842045) (xy 68.729848 -52.766905)
			(xy 68.727829 -52.691121) (xy 67.611751 -52.691121) (xy 67.609732 -52.766905) (xy 67.59967 -52.842045)
			(xy 67.581678 -52.91569) (xy 67.55596 -52.987006) (xy 67.522808 -53.055183) (xy 67.482596 -53.119451)
			(xy 67.435781 -53.17908) (xy 67.382893 -53.233396) (xy 67.324531 -53.281782) (xy 67.261356 -53.32369)
			(xy 67.194085 -53.358646) (xy 67.12348 -53.386253) (xy 67.050339 -53.406199) (xy 66.975494 -53.418258)
			(xy 66.89979 -53.422293) (xy 66.824086 -53.418258) (xy 66.749241 -53.406199) (xy 66.6761 -53.386253)
			(xy 66.605495 -53.358646) (xy 66.538224 -53.32369) (xy 66.475049 -53.281782) (xy 66.416687 -53.233396)
			(xy 66.363799 -53.17908) (xy 66.316984 -53.119451) (xy 66.276772 -53.055183) (xy 66.24362 -52.987006)
			(xy 66.217902 -52.91569) (xy 66.19991 -52.842045) (xy 66.189848 -52.766905) (xy 66.187829 -52.691121)
			(xy 65.071751 -52.691121) (xy 65.069732 -52.766905) (xy 65.05967 -52.842045) (xy 65.041678 -52.91569)
			(xy 65.01596 -52.987006) (xy 64.982808 -53.055183) (xy 64.942596 -53.119451) (xy 64.895781 -53.17908)
			(xy 64.842893 -53.233396) (xy 64.784531 -53.281782) (xy 64.721356 -53.32369) (xy 64.654085 -53.358646)
			(xy 64.58348 -53.386253) (xy 64.510339 -53.406199) (xy 64.435494 -53.418258) (xy 64.35979 -53.422293)
			(xy 64.284086 -53.418258) (xy 64.209241 -53.406199) (xy 64.1361 -53.386253) (xy 64.065495 -53.358646)
			(xy 63.998224 -53.32369) (xy 63.935049 -53.281782) (xy 63.876687 -53.233396) (xy 63.823799 -53.17908)
			(xy 63.776984 -53.119451) (xy 63.736772 -53.055183) (xy 63.70362 -52.987006) (xy 63.677902 -52.91569)
			(xy 63.65991 -52.842045) (xy 63.649848 -52.766905) (xy 63.647829 -52.691121) (xy 42.525601 -52.691121)
			(xy 42.478719 -52.727202) (xy 42.382066 -52.791482) (xy 42.281209 -52.84894) (xy 42.176629 -52.899304)
			(xy 42.068822 -52.942332) (xy 41.958305 -52.97782) (xy 41.845602 -53.005599) (xy 41.731251 -53.025536)
			(xy 41.615797 -53.037537) (xy 41.49979 -53.041543) (xy 41.383783 -53.037537) (xy 41.268329 -53.025536)
			(xy 41.153978 -53.005599) (xy 41.041275 -52.97782) (xy 40.930758 -52.942332) (xy 40.822951 -52.899304)
			(xy 40.718371 -52.84894) (xy 40.617514 -52.791482) (xy 40.520861 -52.727202) (xy 40.428874 -52.656407)
			(xy 40.34199 -52.579434) (xy 40.260623 -52.496651) (xy 40.185161 -52.408451) (xy 40.115965 -52.315256)
			(xy 40.053363 -52.217508) (xy 39.997654 -52.115674) (xy 39.949103 -52.01024) (xy 39.907942 -51.901707)
			(xy 39.874367 -51.790593) (xy 39.848537 -51.677427) (xy 39.830577 -51.562749) (xy 39.820571 -51.447105)
			(xy 39.818567 -51.331047) (xy 28.154884 -51.331047) (xy 28.154884 -55.433484) (xy 29.519874 -55.433484)
			(xy 29.519874 -55.346584) (xy 29.527892 -55.260055) (xy 29.54386 -55.174635) (xy 29.567641 -55.091053)
			(xy 29.599033 -55.010021) (xy 29.637767 -54.932232) (xy 29.683514 -54.858348) (xy 29.735883 -54.789001)
			(xy 29.794427 -54.724781) (xy 29.858647 -54.666237) (xy 29.927994 -54.613868) (xy 30.001878 -54.568121)
			(xy 30.079667 -54.529387) (xy 30.160699 -54.497995) (xy 30.244281 -54.474214) (xy 30.329701 -54.458246)
			(xy 30.41623 -54.450228) (xy 30.45968 -54.449726) (xy 30.50313 -54.450228) (xy 30.589659 -54.458246)
			(xy 30.675079 -54.474214) (xy 30.758661 -54.497995) (xy 30.839693 -54.529387) (xy 30.917482 -54.568121)
			(xy 30.991366 -54.613868) (xy 31.060713 -54.666237) (xy 31.124933 -54.724781) (xy 31.183477 -54.789001)
			(xy 31.235846 -54.858348) (xy 31.281593 -54.932232) (xy 31.320327 -55.010021) (xy 31.351719 -55.091053)
			(xy 31.3755 -55.174635) (xy 31.391468 -55.260055) (xy 31.399486 -55.346584) (xy 31.399486 -55.433484)
			(xy 34.599874 -55.433484) (xy 34.599874 -55.346584) (xy 34.607892 -55.260055) (xy 34.62386 -55.174635)
			(xy 34.647641 -55.091053) (xy 34.679033 -55.010021) (xy 34.717767 -54.932232) (xy 34.763514 -54.858348)
			(xy 34.815883 -54.789001) (xy 34.874427 -54.724781) (xy 34.938647 -54.666237) (xy 35.007994 -54.613868)
			(xy 35.081878 -54.568121) (xy 35.159667 -54.529387) (xy 35.240699 -54.497995) (xy 35.324281 -54.474214)
			(xy 35.409701 -54.458246) (xy 35.49623 -54.450228) (xy 35.53968 -54.449726) (xy 35.58313 -54.450228)
			(xy 35.669659 -54.458246) (xy 35.755079 -54.474214) (xy 35.838661 -54.497995) (xy 35.919693 -54.529387)
			(xy 35.997482 -54.568121) (xy 36.071366 -54.613868) (xy 36.140713 -54.666237) (xy 36.204933 -54.724781)
			(xy 36.263477 -54.789001) (xy 36.315846 -54.858348) (xy 36.361593 -54.932232) (xy 36.400327 -55.010021)
			(xy 36.431719 -55.091053) (xy 36.4555 -55.174635) (xy 36.471468 -55.260055) (xy 36.479486 -55.346584)
			(xy 36.479486 -55.433484) (xy 36.471468 -55.520013) (xy 36.4555 -55.605433) (xy 36.431719 -55.689015)
			(xy 36.400327 -55.770047) (xy 36.361593 -55.847836) (xy 36.315846 -55.92172) (xy 36.263477 -55.991067)
			(xy 36.204933 -56.055287) (xy 36.140713 -56.113831) (xy 36.071366 -56.1662) (xy 35.997482 -56.211947)
			(xy 35.919693 -56.250681) (xy 35.838661 -56.282073) (xy 35.755079 -56.305854) (xy 35.669659 -56.321822)
			(xy 35.58313 -56.32984) (xy 35.49623 -56.32984) (xy 35.409701 -56.321822) (xy 35.324281 -56.305854)
			(xy 35.240699 -56.282073) (xy 35.159667 -56.250681) (xy 35.081878 -56.211947) (xy 35.007994 -56.1662)
			(xy 34.938647 -56.113831) (xy 34.874427 -56.055287) (xy 34.815883 -55.991067) (xy 34.763514 -55.92172)
			(xy 34.717767 -55.847836) (xy 34.679033 -55.770047) (xy 34.647641 -55.689015) (xy 34.62386 -55.605433)
			(xy 34.607892 -55.520013) (xy 34.599874 -55.433484) (xy 31.399486 -55.433484) (xy 31.391468 -55.520013)
			(xy 31.3755 -55.605433) (xy 31.351719 -55.689015) (xy 31.320327 -55.770047) (xy 31.281593 -55.847836)
			(xy 31.235846 -55.92172) (xy 31.183477 -55.991067) (xy 31.124933 -56.055287) (xy 31.060713 -56.113831)
			(xy 30.991366 -56.1662) (xy 30.917482 -56.211947) (xy 30.839693 -56.250681) (xy 30.758661 -56.282073)
			(xy 30.675079 -56.305854) (xy 30.589659 -56.321822) (xy 30.50313 -56.32984) (xy 30.41623 -56.32984)
			(xy 30.329701 -56.321822) (xy 30.244281 -56.305854) (xy 30.160699 -56.282073) (xy 30.079667 -56.250681)
			(xy 30.001878 -56.211947) (xy 29.927994 -56.1662) (xy 29.858647 -56.113831) (xy 29.794427 -56.055287)
			(xy 29.735883 -55.991067) (xy 29.683514 -55.92172) (xy 29.637767 -55.847836) (xy 29.599033 -55.770047)
			(xy 29.567641 -55.689015) (xy 29.54386 -55.605433) (xy 29.527892 -55.520013) (xy 29.519874 -55.433484)
			(xy 28.154884 -55.433484) (xy 28.154884 -56.338317) (xy 63.580764 -56.338317) (xy 63.580764 -56.266995)
			(xy 63.58875 -56.196121) (xy 63.60462 -56.126586) (xy 63.628177 -56.059266) (xy 63.659122 -55.995007)
			(xy 63.697068 -55.934616) (xy 63.741537 -55.878854) (xy 63.79197 -55.828421) (xy 63.847732 -55.783952)
			(xy 63.908123 -55.746006) (xy 63.972382 -55.715061) (xy 64.039702 -55.691504) (xy 64.109237 -55.675634)
			(xy 64.180111 -55.667648) (xy 64.215772 -55.667148) (xy 64.251433 -55.667648) (xy 64.322307 -55.675634)
			(xy 64.391842 -55.691504) (xy 64.459162 -55.715061) (xy 64.523421 -55.746006) (xy 64.583812 -55.783952)
			(xy 64.639574 -55.828421) (xy 64.690007 -55.878854) (xy 64.734476 -55.934616) (xy 64.772422 -55.995007)
			(xy 64.803367 -56.059266) (xy 64.826924 -56.126586) (xy 64.842794 -56.196121) (xy 64.85078 -56.266995)
			(xy 64.85078 -56.338317) (xy 66.572376 -56.338317) (xy 66.572376 -56.266995) (xy 66.580362 -56.196121)
			(xy 66.596232 -56.126586) (xy 66.619789 -56.059266) (xy 66.650734 -55.995007) (xy 66.68868 -55.934616)
			(xy 66.733149 -55.878854) (xy 66.783582 -55.828421) (xy 66.839344 -55.783952) (xy 66.899735 -55.746006)
			(xy 66.963994 -55.715061) (xy 67.031314 -55.691504) (xy 67.100849 -55.675634) (xy 67.171723 -55.667648)
			(xy 67.207384 -55.667148) (xy 67.243045 -55.667648) (xy 67.313919 -55.675634) (xy 67.383454 -55.691504)
			(xy 67.450774 -55.715061) (xy 67.515033 -55.746006) (xy 67.575424 -55.783952) (xy 67.631186 -55.828421)
			(xy 67.681619 -55.878854) (xy 67.726088 -55.934616) (xy 67.764034 -55.995007) (xy 67.794979 -56.059266)
			(xy 67.818536 -56.126586) (xy 67.834406 -56.196121) (xy 67.842392 -56.266995) (xy 67.842392 -56.338317)
			(xy 67.834406 -56.409191) (xy 67.818536 -56.478726) (xy 67.794979 -56.546046) (xy 67.764034 -56.610305)
			(xy 67.726088 -56.670696) (xy 67.681619 -56.726458) (xy 67.631186 -56.776891) (xy 67.575424 -56.82136)
			(xy 67.515033 -56.859306) (xy 67.450774 -56.890251) (xy 67.383454 -56.913808) (xy 67.313919 -56.929678)
			(xy 67.243045 -56.937664) (xy 67.171723 -56.937664) (xy 67.100849 -56.929678) (xy 67.031314 -56.913808)
			(xy 66.963994 -56.890251) (xy 66.899735 -56.859306) (xy 66.839344 -56.82136) (xy 66.783582 -56.776891)
			(xy 66.733149 -56.726458) (xy 66.68868 -56.670696) (xy 66.650734 -56.610305) (xy 66.619789 -56.546046)
			(xy 66.596232 -56.478726) (xy 66.580362 -56.409191) (xy 66.572376 -56.338317) (xy 64.85078 -56.338317)
			(xy 64.842794 -56.409191) (xy 64.826924 -56.478726) (xy 64.803367 -56.546046) (xy 64.772422 -56.610305)
			(xy 64.734476 -56.670696) (xy 64.690007 -56.726458) (xy 64.639574 -56.776891) (xy 64.583812 -56.82136)
			(xy 64.523421 -56.859306) (xy 64.459162 -56.890251) (xy 64.391842 -56.913808) (xy 64.322307 -56.929678)
			(xy 64.251433 -56.937664) (xy 64.180111 -56.937664) (xy 64.109237 -56.929678) (xy 64.039702 -56.913808)
			(xy 63.972382 -56.890251) (xy 63.908123 -56.859306) (xy 63.847732 -56.82136) (xy 63.79197 -56.776891)
			(xy 63.741537 -56.726458) (xy 63.697068 -56.670696) (xy 63.659122 -56.610305) (xy 63.628177 -56.546046)
			(xy 63.60462 -56.478726) (xy 63.58875 -56.409191) (xy 63.580764 -56.338317) (xy 28.154884 -56.338317)
			(xy 28.154884 -57.973484) (xy 29.519874 -57.973484) (xy 29.519874 -57.886584) (xy 29.527892 -57.800055)
			(xy 29.54386 -57.714635) (xy 29.567641 -57.631053) (xy 29.599033 -57.550021) (xy 29.637767 -57.472232)
			(xy 29.683514 -57.398348) (xy 29.735883 -57.329001) (xy 29.794427 -57.264781) (xy 29.858647 -57.206237)
			(xy 29.927994 -57.153868) (xy 30.001878 -57.108121) (xy 30.079667 -57.069387) (xy 30.160699 -57.037995)
			(xy 30.244281 -57.014214) (xy 30.329701 -56.998246) (xy 30.41623 -56.990228) (xy 30.45968 -56.989726)
			(xy 30.50313 -56.990228) (xy 30.589659 -56.998246) (xy 30.675079 -57.014214) (xy 30.758661 -57.037995)
			(xy 30.839693 -57.069387) (xy 30.917482 -57.108121) (xy 30.991366 -57.153868) (xy 31.060713 -57.206237)
			(xy 31.124933 -57.264781) (xy 31.183477 -57.329001) (xy 31.235846 -57.398348) (xy 31.281593 -57.472232)
			(xy 31.320327 -57.550021) (xy 31.351719 -57.631053) (xy 31.3755 -57.714635) (xy 31.391468 -57.800055)
			(xy 31.399486 -57.886584) (xy 31.399486 -57.973484) (xy 34.599874 -57.973484) (xy 34.599874 -57.886584)
			(xy 34.607892 -57.800055) (xy 34.62386 -57.714635) (xy 34.647641 -57.631053) (xy 34.679033 -57.550021)
			(xy 34.717767 -57.472232) (xy 34.763514 -57.398348) (xy 34.815883 -57.329001) (xy 34.874427 -57.264781)
			(xy 34.938647 -57.206237) (xy 35.007994 -57.153868) (xy 35.081878 -57.108121) (xy 35.159667 -57.069387)
			(xy 35.240699 -57.037995) (xy 35.324281 -57.014214) (xy 35.409701 -56.998246) (xy 35.49623 -56.990228)
			(xy 35.53968 -56.989726) (xy 35.58313 -56.990228) (xy 35.669659 -56.998246) (xy 35.755079 -57.014214)
			(xy 35.838661 -57.037995) (xy 35.919693 -57.069387) (xy 35.997482 -57.108121) (xy 36.071366 -57.153868)
			(xy 36.140713 -57.206237) (xy 36.204933 -57.264781) (xy 36.263477 -57.329001) (xy 36.315846 -57.398348)
			(xy 36.334598 -57.428634) (xy 80.91727 -57.428634) (xy 80.91727 -57.368698) (xy 80.925093 -57.309276)
			(xy 80.940606 -57.251383) (xy 80.963542 -57.19601) (xy 80.993509 -57.144104) (xy 81.029996 -57.096554)
			(xy 81.072376 -57.054174) (xy 81.119926 -57.017687) (xy 81.171832 -56.98772) (xy 81.227205 -56.964784)
			(xy 81.285098 -56.949271) (xy 81.34452 -56.941448) (xy 81.374488 -56.940958) (xy 81.404456 -56.941448)
			(xy 81.463878 -56.949271) (xy 81.521771 -56.964784) (xy 81.577144 -56.98772) (xy 81.62905 -57.017687)
			(xy 81.6766 -57.054174) (xy 81.71898 -57.096554) (xy 81.755467 -57.144104) (xy 81.785434 -57.19601)
			(xy 81.80837 -57.251383) (xy 81.823883 -57.309276) (xy 81.831706 -57.368698) (xy 81.831706 -57.428634)
			(xy 81.823883 -57.488056) (xy 81.80837 -57.545949) (xy 81.785434 -57.601322) (xy 81.755467 -57.653228)
			(xy 81.71898 -57.700778) (xy 81.6766 -57.743158) (xy 81.62905 -57.779645) (xy 81.577144 -57.809612)
			(xy 81.521771 -57.832548) (xy 81.463878 -57.848061) (xy 81.404456 -57.855884) (xy 81.34452 -57.855884)
			(xy 81.285098 -57.848061) (xy 81.227205 -57.832548) (xy 81.171832 -57.809612) (xy 81.119926 -57.779645)
			(xy 81.072376 -57.743158) (xy 81.029996 -57.700778) (xy 80.993509 -57.653228) (xy 80.963542 -57.601322)
			(xy 80.940606 -57.545949) (xy 80.925093 -57.488056) (xy 80.91727 -57.428634) (xy 36.334598 -57.428634)
			(xy 36.361593 -57.472232) (xy 36.400327 -57.550021) (xy 36.431719 -57.631053) (xy 36.4555 -57.714635)
			(xy 36.471468 -57.800055) (xy 36.479486 -57.886584) (xy 36.479486 -57.973484) (xy 36.471468 -58.060013)
			(xy 36.4555 -58.145433) (xy 36.431719 -58.229015) (xy 36.400327 -58.310047) (xy 36.361593 -58.387836)
			(xy 36.315846 -58.46172) (xy 36.263477 -58.531067) (xy 36.204933 -58.595287) (xy 36.140713 -58.653831)
			(xy 36.071366 -58.7062) (xy 35.997482 -58.751947) (xy 35.919693 -58.790681) (xy 35.838661 -58.822073)
			(xy 35.755079 -58.845854) (xy 35.669659 -58.861822) (xy 35.58313 -58.86984) (xy 35.49623 -58.86984)
			(xy 35.409701 -58.861822) (xy 35.324281 -58.845854) (xy 35.240699 -58.822073) (xy 35.159667 -58.790681)
			(xy 35.081878 -58.751947) (xy 35.007994 -58.7062) (xy 34.938647 -58.653831) (xy 34.874427 -58.595287)
			(xy 34.815883 -58.531067) (xy 34.763514 -58.46172) (xy 34.717767 -58.387836) (xy 34.679033 -58.310047)
			(xy 34.647641 -58.229015) (xy 34.62386 -58.145433) (xy 34.607892 -58.060013) (xy 34.599874 -57.973484)
			(xy 31.399486 -57.973484) (xy 31.391468 -58.060013) (xy 31.3755 -58.145433) (xy 31.351719 -58.229015)
			(xy 31.320327 -58.310047) (xy 31.281593 -58.387836) (xy 31.235846 -58.46172) (xy 31.183477 -58.531067)
			(xy 31.124933 -58.595287) (xy 31.060713 -58.653831) (xy 30.991366 -58.7062) (xy 30.917482 -58.751947)
			(xy 30.839693 -58.790681) (xy 30.758661 -58.822073) (xy 30.675079 -58.845854) (xy 30.589659 -58.861822)
			(xy 30.50313 -58.86984) (xy 30.41623 -58.86984) (xy 30.329701 -58.861822) (xy 30.244281 -58.845854)
			(xy 30.160699 -58.822073) (xy 30.079667 -58.790681) (xy 30.001878 -58.751947) (xy 29.927994 -58.7062)
			(xy 29.858647 -58.653831) (xy 29.794427 -58.595287) (xy 29.735883 -58.531067) (xy 29.683514 -58.46172)
			(xy 29.637767 -58.387836) (xy 29.599033 -58.310047) (xy 29.567641 -58.229015) (xy 29.54386 -58.145433)
			(xy 29.527892 -58.060013) (xy 29.519874 -57.973484) (xy 28.154884 -57.973484) (xy 28.154884 -59.009127)
			(xy 63.580764 -59.009127) (xy 63.580764 -58.937805) (xy 63.58875 -58.866931) (xy 63.60462 -58.797396)
			(xy 63.628177 -58.730076) (xy 63.659122 -58.665817) (xy 63.697068 -58.605426) (xy 63.741537 -58.549664)
			(xy 63.79197 -58.499231) (xy 63.847732 -58.454762) (xy 63.908123 -58.416816) (xy 63.972382 -58.385871)
			(xy 64.039702 -58.362314) (xy 64.109237 -58.346444) (xy 64.180111 -58.338458) (xy 64.215772 -58.337958)
			(xy 64.251433 -58.338458) (xy 64.322307 -58.346444) (xy 64.391842 -58.362314) (xy 64.459162 -58.385871)
			(xy 64.523421 -58.416816) (xy 64.583812 -58.454762) (xy 64.639574 -58.499231) (xy 64.690007 -58.549664)
			(xy 64.734476 -58.605426) (xy 64.772422 -58.665817) (xy 64.803367 -58.730076) (xy 64.826924 -58.797396)
			(xy 64.842794 -58.866931) (xy 64.85078 -58.937805) (xy 64.85078 -59.009127) (xy 66.572376 -59.009127)
			(xy 66.572376 -58.937805) (xy 66.580362 -58.866931) (xy 66.596232 -58.797396) (xy 66.619789 -58.730076)
			(xy 66.650734 -58.665817) (xy 66.68868 -58.605426) (xy 66.733149 -58.549664) (xy 66.783582 -58.499231)
			(xy 66.839344 -58.454762) (xy 66.899735 -58.416816) (xy 66.963994 -58.385871) (xy 67.031314 -58.362314)
			(xy 67.100849 -58.346444) (xy 67.171723 -58.338458) (xy 67.207384 -58.337958) (xy 67.243045 -58.338458)
			(xy 67.313919 -58.346444) (xy 67.383454 -58.362314) (xy 67.450774 -58.385871) (xy 67.515033 -58.416816)
			(xy 67.575424 -58.454762) (xy 67.631186 -58.499231) (xy 67.681619 -58.549664) (xy 67.726088 -58.605426)
			(xy 67.764034 -58.665817) (xy 67.794979 -58.730076) (xy 67.818536 -58.797396) (xy 67.834406 -58.866931)
			(xy 67.839512 -58.912248) (xy 80.337134 -58.912248) (xy 80.337134 -58.852312) (xy 80.344957 -58.79289)
			(xy 80.36047 -58.734997) (xy 80.383406 -58.679624) (xy 80.413373 -58.627718) (xy 80.44986 -58.580168)
			(xy 80.49224 -58.537788) (xy 80.53979 -58.501301) (xy 80.591696 -58.471334) (xy 80.647069 -58.448398)
			(xy 80.704962 -58.432885) (xy 80.764384 -58.425062) (xy 80.794352 -58.424572) (xy 80.82432 -58.425062)
			(xy 80.883742 -58.432885) (xy 80.941635 -58.448398) (xy 80.997008 -58.471334) (xy 81.048914 -58.501301)
			(xy 81.096464 -58.537788) (xy 81.138844 -58.580168) (xy 81.175331 -58.627718) (xy 81.205298 -58.679624)
			(xy 81.228234 -58.734997) (xy 81.243747 -58.79289) (xy 81.251435 -58.851288) (xy 82.018868 -58.851288)
			(xy 82.018868 -58.791352) (xy 82.026691 -58.73193) (xy 82.042204 -58.674037) (xy 82.06514 -58.618664)
			(xy 82.095107 -58.566758) (xy 82.131594 -58.519208) (xy 82.173974 -58.476828) (xy 82.221524 -58.440341)
			(xy 82.27343 -58.410374) (xy 82.328803 -58.387438) (xy 82.386696 -58.371925) (xy 82.446118 -58.364102)
			(xy 82.476086 -58.363612) (xy 82.506054 -58.364102) (xy 82.565476 -58.371925) (xy 82.623369 -58.387438)
			(xy 82.678742 -58.410374) (xy 82.730648 -58.440341) (xy 82.778198 -58.476828) (xy 82.820578 -58.519208)
			(xy 82.857065 -58.566758) (xy 82.887032 -58.618664) (xy 82.909968 -58.674037) (xy 82.925481 -58.73193)
			(xy 82.933304 -58.791352) (xy 82.933304 -58.851288) (xy 82.925481 -58.91071) (xy 82.911388 -58.963302)
			(xy 83.628466 -58.963302) (xy 83.628466 -58.903366) (xy 83.636289 -58.843944) (xy 83.651802 -58.786051)
			(xy 83.674738 -58.730678) (xy 83.704705 -58.678772) (xy 83.741192 -58.631222) (xy 83.783572 -58.588842)
			(xy 83.831122 -58.552355) (xy 83.883028 -58.522388) (xy 83.938401 -58.499452) (xy 83.996294 -58.483939)
			(xy 84.055716 -58.476116) (xy 84.085684 -58.475626) (xy 84.115652 -58.476116) (xy 84.175074 -58.483939)
			(xy 84.232967 -58.499452) (xy 84.28834 -58.522388) (xy 84.340246 -58.552355) (xy 84.387796 -58.588842)
			(xy 84.430176 -58.631222) (xy 84.466663 -58.678772) (xy 84.49663 -58.730678) (xy 84.519566 -58.786051)
			(xy 84.535079 -58.843944) (xy 84.542902 -58.903366) (xy 84.542902 -58.963302) (xy 84.535079 -59.022724)
			(xy 84.519566 -59.080617) (xy 84.49663 -59.13599) (xy 84.466663 -59.187896) (xy 84.430176 -59.235446)
			(xy 84.387796 -59.277826) (xy 84.340246 -59.314313) (xy 84.28834 -59.34428) (xy 84.232967 -59.367216)
			(xy 84.175074 -59.382729) (xy 84.115652 -59.390552) (xy 84.055716 -59.390552) (xy 83.996294 -59.382729)
			(xy 83.938401 -59.367216) (xy 83.883028 -59.34428) (xy 83.831122 -59.314313) (xy 83.783572 -59.277826)
			(xy 83.741192 -59.235446) (xy 83.704705 -59.187896) (xy 83.674738 -59.13599) (xy 83.651802 -59.080617)
			(xy 83.636289 -59.022724) (xy 83.628466 -58.963302) (xy 82.911388 -58.963302) (xy 82.909968 -58.968603)
			(xy 82.887032 -59.023976) (xy 82.857065 -59.075882) (xy 82.820578 -59.123432) (xy 82.778198 -59.165812)
			(xy 82.730648 -59.202299) (xy 82.678742 -59.232266) (xy 82.623369 -59.255202) (xy 82.565476 -59.270715)
			(xy 82.506054 -59.278538) (xy 82.446118 -59.278538) (xy 82.386696 -59.270715) (xy 82.328803 -59.255202)
			(xy 82.27343 -59.232266) (xy 82.221524 -59.202299) (xy 82.173974 -59.165812) (xy 82.131594 -59.123432)
			(xy 82.095107 -59.075882) (xy 82.06514 -59.023976) (xy 82.042204 -58.968603) (xy 82.026691 -58.91071)
			(xy 82.018868 -58.851288) (xy 81.251435 -58.851288) (xy 81.25157 -58.852312) (xy 81.25157 -58.912248)
			(xy 81.243747 -58.97167) (xy 81.228234 -59.029563) (xy 81.205298 -59.084936) (xy 81.175331 -59.136842)
			(xy 81.138844 -59.184392) (xy 81.096464 -59.226772) (xy 81.048914 -59.263259) (xy 80.997008 -59.293226)
			(xy 80.941635 -59.316162) (xy 80.883742 -59.331675) (xy 80.82432 -59.339498) (xy 80.764384 -59.339498)
			(xy 80.704962 -59.331675) (xy 80.647069 -59.316162) (xy 80.591696 -59.293226) (xy 80.53979 -59.263259)
			(xy 80.49224 -59.226772) (xy 80.44986 -59.184392) (xy 80.413373 -59.136842) (xy 80.383406 -59.084936)
			(xy 80.36047 -59.029563) (xy 80.344957 -58.97167) (xy 80.337134 -58.912248) (xy 67.839512 -58.912248)
			(xy 67.842392 -58.937805) (xy 67.842392 -59.009127) (xy 67.834406 -59.080001) (xy 67.818536 -59.149536)
			(xy 67.794979 -59.216856) (xy 67.764034 -59.281115) (xy 67.726088 -59.341506) (xy 67.681619 -59.397268)
			(xy 67.631186 -59.447701) (xy 67.575424 -59.49217) (xy 67.515033 -59.530116) (xy 67.450774 -59.561061)
			(xy 67.383454 -59.584618) (xy 67.313919 -59.600488) (xy 67.243045 -59.608474) (xy 67.171723 -59.608474)
			(xy 67.100849 -59.600488) (xy 67.031314 -59.584618) (xy 66.963994 -59.561061) (xy 66.899735 -59.530116)
			(xy 66.839344 -59.49217) (xy 66.783582 -59.447701) (xy 66.733149 -59.397268) (xy 66.68868 -59.341506)
			(xy 66.650734 -59.281115) (xy 66.619789 -59.216856) (xy 66.596232 -59.149536) (xy 66.580362 -59.080001)
			(xy 66.572376 -59.009127) (xy 64.85078 -59.009127) (xy 64.842794 -59.080001) (xy 64.826924 -59.149536)
			(xy 64.803367 -59.216856) (xy 64.772422 -59.281115) (xy 64.734476 -59.341506) (xy 64.690007 -59.397268)
			(xy 64.639574 -59.447701) (xy 64.583812 -59.49217) (xy 64.523421 -59.530116) (xy 64.459162 -59.561061)
			(xy 64.391842 -59.584618) (xy 64.322307 -59.600488) (xy 64.251433 -59.608474) (xy 64.180111 -59.608474)
			(xy 64.109237 -59.600488) (xy 64.039702 -59.584618) (xy 63.972382 -59.561061) (xy 63.908123 -59.530116)
			(xy 63.847732 -59.49217) (xy 63.79197 -59.447701) (xy 63.741537 -59.397268) (xy 63.697068 -59.341506)
			(xy 63.659122 -59.281115) (xy 63.628177 -59.216856) (xy 63.60462 -59.149536) (xy 63.58875 -59.080001)
			(xy 63.580764 -59.009127) (xy 28.154884 -59.009127) (xy 28.154884 -60.513484) (xy 29.519874 -60.513484)
			(xy 29.519874 -60.426584) (xy 29.527892 -60.340055) (xy 29.54386 -60.254635) (xy 29.567641 -60.171053)
			(xy 29.599033 -60.090021) (xy 29.637767 -60.012232) (xy 29.683514 -59.938348) (xy 29.735883 -59.869001)
			(xy 29.794427 -59.804781) (xy 29.858647 -59.746237) (xy 29.927994 -59.693868) (xy 30.001878 -59.648121)
			(xy 30.079667 -59.609387) (xy 30.160699 -59.577995) (xy 30.244281 -59.554214) (xy 30.329701 -59.538246)
			(xy 30.41623 -59.530228) (xy 30.45968 -59.529726) (xy 30.50313 -59.530228) (xy 30.589659 -59.538246)
			(xy 30.675079 -59.554214) (xy 30.758661 -59.577995) (xy 30.839693 -59.609387) (xy 30.917482 -59.648121)
			(xy 30.991366 -59.693868) (xy 31.060713 -59.746237) (xy 31.124933 -59.804781) (xy 31.183477 -59.869001)
			(xy 31.235846 -59.938348) (xy 31.281593 -60.012232) (xy 31.320327 -60.090021) (xy 31.351719 -60.171053)
			(xy 31.3755 -60.254635) (xy 31.391468 -60.340055) (xy 31.399486 -60.426584) (xy 31.399486 -60.513484)
			(xy 34.599874 -60.513484) (xy 34.599874 -60.426584) (xy 34.607892 -60.340055) (xy 34.62386 -60.254635)
			(xy 34.647641 -60.171053) (xy 34.679033 -60.090021) (xy 34.717767 -60.012232) (xy 34.763514 -59.938348)
			(xy 34.815883 -59.869001) (xy 34.874427 -59.804781) (xy 34.938647 -59.746237) (xy 35.007994 -59.693868)
			(xy 35.081878 -59.648121) (xy 35.159667 -59.609387) (xy 35.240699 -59.577995) (xy 35.324281 -59.554214)
			(xy 35.409701 -59.538246) (xy 35.49623 -59.530228) (xy 35.53968 -59.529726) (xy 35.58313 -59.530228)
			(xy 35.669659 -59.538246) (xy 35.755079 -59.554214) (xy 35.838661 -59.577995) (xy 35.919693 -59.609387)
			(xy 35.997482 -59.648121) (xy 36.071366 -59.693868) (xy 36.140713 -59.746237) (xy 36.204933 -59.804781)
			(xy 36.263477 -59.869001) (xy 36.315846 -59.938348) (xy 36.361593 -60.012232) (xy 36.400327 -60.090021)
			(xy 36.431719 -60.171053) (xy 36.4555 -60.254635) (xy 36.471468 -60.340055) (xy 36.479486 -60.426584)
			(xy 36.479486 -60.513484) (xy 36.478593 -60.523116) (xy 79.530938 -60.523116) (xy 79.530938 -60.46318)
			(xy 79.538761 -60.403758) (xy 79.554274 -60.345865) (xy 79.57721 -60.290492) (xy 79.607177 -60.238586)
			(xy 79.643664 -60.191036) (xy 79.686044 -60.148656) (xy 79.733594 -60.112169) (xy 79.7855 -60.082202)
			(xy 79.840873 -60.059266) (xy 79.898766 -60.043753) (xy 79.958188 -60.03593) (xy 79.988156 -60.03544)
			(xy 80.018124 -60.03593) (xy 80.077546 -60.043753) (xy 80.135439 -60.059266) (xy 80.190812 -60.082202)
			(xy 80.242718 -60.112169) (xy 80.290268 -60.148656) (xy 80.332648 -60.191036) (xy 80.369135 -60.238586)
			(xy 80.399102 -60.290492) (xy 80.422038 -60.345865) (xy 80.437551 -60.403758) (xy 80.445374 -60.46318)
			(xy 80.445374 -60.516766) (xy 81.305128 -60.516766) (xy 81.305128 -60.45683) (xy 81.312951 -60.397408)
			(xy 81.328464 -60.339515) (xy 81.3514 -60.284142) (xy 81.381367 -60.232236) (xy 81.417854 -60.184686)
			(xy 81.460234 -60.142306) (xy 81.507784 -60.105819) (xy 81.55969 -60.075852) (xy 81.615063 -60.052916)
			(xy 81.672956 -60.037403) (xy 81.732378 -60.02958) (xy 81.762346 -60.02909) (xy 81.792314 -60.02958)
			(xy 81.851736 -60.037403) (xy 81.909629 -60.052916) (xy 81.965002 -60.075852) (xy 82.016908 -60.105819)
			(xy 82.064458 -60.142306) (xy 82.106838 -60.184686) (xy 82.143325 -60.232236) (xy 82.173292 -60.284142)
			(xy 82.196228 -60.339515) (xy 82.211741 -60.397408) (xy 82.219564 -60.45683) (xy 82.219564 -60.516766)
			(xy 82.211741 -60.576188) (xy 82.196228 -60.634081) (xy 82.173292 -60.689454) (xy 82.143325 -60.74136)
			(xy 82.106838 -60.78891) (xy 82.064458 -60.83129) (xy 82.016908 -60.867777) (xy 81.965002 -60.897744)
			(xy 81.909629 -60.92068) (xy 81.851736 -60.936193) (xy 81.792314 -60.944016) (xy 81.732378 -60.944016)
			(xy 81.672956 -60.936193) (xy 81.615063 -60.92068) (xy 81.55969 -60.897744) (xy 81.507784 -60.867777)
			(xy 81.460234 -60.83129) (xy 81.417854 -60.78891) (xy 81.381367 -60.74136) (xy 81.3514 -60.689454)
			(xy 81.328464 -60.634081) (xy 81.312951 -60.576188) (xy 81.305128 -60.516766) (xy 80.445374 -60.516766)
			(xy 80.445374 -60.523116) (xy 80.437551 -60.582538) (xy 80.422038 -60.640431) (xy 80.399102 -60.695804)
			(xy 80.369135 -60.74771) (xy 80.332648 -60.79526) (xy 80.290268 -60.83764) (xy 80.242718 -60.874127)
			(xy 80.190812 -60.904094) (xy 80.135439 -60.92703) (xy 80.077546 -60.942543) (xy 80.018124 -60.950366)
			(xy 79.958188 -60.950366) (xy 79.898766 -60.942543) (xy 79.840873 -60.92703) (xy 79.7855 -60.904094)
			(xy 79.733594 -60.874127) (xy 79.686044 -60.83764) (xy 79.643664 -60.79526) (xy 79.607177 -60.74771)
			(xy 79.57721 -60.695804) (xy 79.554274 -60.640431) (xy 79.538761 -60.582538) (xy 79.530938 -60.523116)
			(xy 36.478593 -60.523116) (xy 36.471468 -60.600013) (xy 36.4555 -60.685433) (xy 36.431719 -60.769015)
			(xy 36.400327 -60.850047) (xy 36.361593 -60.927836) (xy 36.315846 -61.00172) (xy 36.263477 -61.071067)
			(xy 36.204933 -61.135287) (xy 36.140713 -61.193831) (xy 36.071366 -61.2462) (xy 35.997482 -61.291947)
			(xy 35.919693 -61.330681) (xy 35.838661 -61.362073) (xy 35.755079 -61.385854) (xy 35.669659 -61.401822)
			(xy 35.58313 -61.40984) (xy 35.49623 -61.40984) (xy 35.409701 -61.401822) (xy 35.324281 -61.385854)
			(xy 35.240699 -61.362073) (xy 35.159667 -61.330681) (xy 35.081878 -61.291947) (xy 35.007994 -61.2462)
			(xy 34.938647 -61.193831) (xy 34.874427 -61.135287) (xy 34.815883 -61.071067) (xy 34.763514 -61.00172)
			(xy 34.717767 -60.927836) (xy 34.679033 -60.850047) (xy 34.647641 -60.769015) (xy 34.62386 -60.685433)
			(xy 34.607892 -60.600013) (xy 34.599874 -60.513484) (xy 31.399486 -60.513484) (xy 31.391468 -60.600013)
			(xy 31.3755 -60.685433) (xy 31.351719 -60.769015) (xy 31.320327 -60.850047) (xy 31.281593 -60.927836)
			(xy 31.235846 -61.00172) (xy 31.183477 -61.071067) (xy 31.124933 -61.135287) (xy 31.060713 -61.193831)
			(xy 30.991366 -61.2462) (xy 30.917482 -61.291947) (xy 30.839693 -61.330681) (xy 30.758661 -61.362073)
			(xy 30.675079 -61.385854) (xy 30.589659 -61.401822) (xy 30.50313 -61.40984) (xy 30.41623 -61.40984)
			(xy 30.329701 -61.401822) (xy 30.244281 -61.385854) (xy 30.160699 -61.362073) (xy 30.079667 -61.330681)
			(xy 30.001878 -61.291947) (xy 29.927994 -61.2462) (xy 29.858647 -61.193831) (xy 29.794427 -61.135287)
			(xy 29.735883 -61.071067) (xy 29.683514 -61.00172) (xy 29.637767 -60.927836) (xy 29.599033 -60.850047)
			(xy 29.567641 -60.769015) (xy 29.54386 -60.685433) (xy 29.527892 -60.600013) (xy 29.519874 -60.513484)
			(xy 28.154884 -60.513484) (xy 28.154884 -61.677397) (xy 63.580764 -61.677397) (xy 63.580764 -61.606075)
			(xy 63.58875 -61.535201) (xy 63.60462 -61.465666) (xy 63.628177 -61.398346) (xy 63.659122 -61.334087)
			(xy 63.697068 -61.273696) (xy 63.741537 -61.217934) (xy 63.79197 -61.167501) (xy 63.847732 -61.123032)
			(xy 63.908123 -61.085086) (xy 63.972382 -61.054141) (xy 64.039702 -61.030584) (xy 64.109237 -61.014714)
			(xy 64.180111 -61.006728) (xy 64.215772 -61.006228) (xy 64.251433 -61.006728) (xy 64.322307 -61.014714)
			(xy 64.391842 -61.030584) (xy 64.459162 -61.054141) (xy 64.523421 -61.085086) (xy 64.583812 -61.123032)
			(xy 64.639574 -61.167501) (xy 64.690007 -61.217934) (xy 64.734476 -61.273696) (xy 64.772422 -61.334087)
			(xy 64.803367 -61.398346) (xy 64.826924 -61.465666) (xy 64.842794 -61.535201) (xy 64.85078 -61.606075)
			(xy 64.85078 -61.677397) (xy 66.572376 -61.677397) (xy 66.572376 -61.606075) (xy 66.580362 -61.535201)
			(xy 66.596232 -61.465666) (xy 66.619789 -61.398346) (xy 66.650734 -61.334087) (xy 66.68868 -61.273696)
			(xy 66.733149 -61.217934) (xy 66.783582 -61.167501) (xy 66.839344 -61.123032) (xy 66.899735 -61.085086)
			(xy 66.963994 -61.054141) (xy 67.031314 -61.030584) (xy 67.100849 -61.014714) (xy 67.171723 -61.006728)
			(xy 67.207384 -61.006228) (xy 67.243045 -61.006728) (xy 67.313919 -61.014714) (xy 67.383454 -61.030584)
			(xy 67.450774 -61.054141) (xy 67.515033 -61.085086) (xy 67.575424 -61.123032) (xy 67.631186 -61.167501)
			(xy 67.681619 -61.217934) (xy 67.704406 -61.246508) (xy 77.3346 -61.246508) (xy 77.3346 -61.186572)
			(xy 77.342423 -61.12715) (xy 77.357936 -61.069257) (xy 77.380872 -61.013884) (xy 77.410839 -60.961978)
			(xy 77.447326 -60.914428) (xy 77.489706 -60.872048) (xy 77.537256 -60.835561) (xy 77.589162 -60.805594)
			(xy 77.644535 -60.782658) (xy 77.702428 -60.767145) (xy 77.76185 -60.759322) (xy 77.791818 -60.758832)
			(xy 77.821786 -60.759322) (xy 77.881208 -60.767145) (xy 77.939101 -60.782658) (xy 77.994474 -60.805594)
			(xy 78.04638 -60.835561) (xy 78.09393 -60.872048) (xy 78.13631 -60.914428) (xy 78.172797 -60.961978)
			(xy 78.202764 -61.013884) (xy 78.2257 -61.069257) (xy 78.241213 -61.12715) (xy 78.249036 -61.186572)
			(xy 78.249036 -61.246508) (xy 78.241213 -61.30593) (xy 78.2257 -61.363823) (xy 78.202764 -61.419196)
			(xy 78.172797 -61.471102) (xy 78.13631 -61.518652) (xy 78.09393 -61.561032) (xy 78.04638 -61.597519)
			(xy 77.994474 -61.627486) (xy 77.939101 -61.650422) (xy 77.881208 -61.665935) (xy 77.821786 -61.673758)
			(xy 77.76185 -61.673758) (xy 77.702428 -61.665935) (xy 77.644535 -61.650422) (xy 77.589162 -61.627486)
			(xy 77.537256 -61.597519) (xy 77.489706 -61.561032) (xy 77.447326 -61.518652) (xy 77.410839 -61.471102)
			(xy 77.380872 -61.419196) (xy 77.357936 -61.363823) (xy 77.342423 -61.30593) (xy 77.3346 -61.246508)
			(xy 67.704406 -61.246508) (xy 67.726088 -61.273696) (xy 67.764034 -61.334087) (xy 67.794979 -61.398346)
			(xy 67.818536 -61.465666) (xy 67.834406 -61.535201) (xy 67.842392 -61.606075) (xy 67.842392 -61.677397)
			(xy 67.834406 -61.748271) (xy 67.818536 -61.817806) (xy 67.794979 -61.885126) (xy 67.764034 -61.949385)
			(xy 67.726088 -62.009776) (xy 67.681619 -62.065538) (xy 67.631186 -62.115971) (xy 67.575424 -62.16044)
			(xy 67.515033 -62.198386) (xy 67.450774 -62.229331) (xy 67.383454 -62.252888) (xy 67.313919 -62.268758)
			(xy 67.243045 -62.276744) (xy 67.171723 -62.276744) (xy 67.100849 -62.268758) (xy 67.031314 -62.252888)
			(xy 66.963994 -62.229331) (xy 66.899735 -62.198386) (xy 66.839344 -62.16044) (xy 66.783582 -62.115971)
			(xy 66.733149 -62.065538) (xy 66.68868 -62.009776) (xy 66.650734 -61.949385) (xy 66.619789 -61.885126)
			(xy 66.596232 -61.817806) (xy 66.580362 -61.748271) (xy 66.572376 -61.677397) (xy 64.85078 -61.677397)
			(xy 64.842794 -61.748271) (xy 64.826924 -61.817806) (xy 64.803367 -61.885126) (xy 64.772422 -61.949385)
			(xy 64.734476 -62.009776) (xy 64.690007 -62.065538) (xy 64.639574 -62.115971) (xy 64.583812 -62.16044)
			(xy 64.523421 -62.198386) (xy 64.459162 -62.229331) (xy 64.391842 -62.252888) (xy 64.322307 -62.268758)
			(xy 64.251433 -62.276744) (xy 64.180111 -62.276744) (xy 64.109237 -62.268758) (xy 64.039702 -62.252888)
			(xy 63.972382 -62.229331) (xy 63.908123 -62.198386) (xy 63.847732 -62.16044) (xy 63.79197 -62.115971)
			(xy 63.741537 -62.065538) (xy 63.697068 -62.009776) (xy 63.659122 -61.949385) (xy 63.628177 -61.885126)
			(xy 63.60462 -61.817806) (xy 63.58875 -61.748271) (xy 63.580764 -61.677397) (xy 28.154884 -61.677397)
			(xy 28.154884 -62.056264) (xy 51.025044 -62.056264) (xy 52.676552 -62.056264) (xy 52.676552 -62.433704)
			(xy 83.345002 -62.433704) (xy 83.345002 -62.373768) (xy 83.352825 -62.314346) (xy 83.368338 -62.256453)
			(xy 83.391274 -62.20108) (xy 83.421241 -62.149174) (xy 83.457728 -62.101624) (xy 83.500108 -62.059244)
			(xy 83.547658 -62.022757) (xy 83.599564 -61.99279) (xy 83.654937 -61.969854) (xy 83.71283 -61.954341)
			(xy 83.772252 -61.946518) (xy 83.80222 -61.946028) (xy 83.832188 -61.946518) (xy 83.89161 -61.954341)
			(xy 83.949503 -61.969854) (xy 84.004876 -61.99279) (xy 84.056782 -62.022757) (xy 84.104332 -62.059244)
			(xy 84.146712 -62.101624) (xy 84.183199 -62.149174) (xy 84.213166 -62.20108) (xy 84.236102 -62.256453)
			(xy 84.251615 -62.314346) (xy 84.259438 -62.373768) (xy 84.259438 -62.433704) (xy 84.251615 -62.493126)
			(xy 84.236102 -62.551019) (xy 84.213166 -62.606392) (xy 84.183199 -62.658298) (xy 84.146712 -62.705848)
			(xy 84.104332 -62.748228) (xy 84.056782 -62.784715) (xy 84.004876 -62.814682) (xy 83.949503 -62.837618)
			(xy 83.89161 -62.853131) (xy 83.832188 -62.860954) (xy 83.772252 -62.860954) (xy 83.71283 -62.853131)
			(xy 83.654937 -62.837618) (xy 83.599564 -62.814682) (xy 83.547658 -62.784715) (xy 83.500108 -62.748228)
			(xy 83.457728 -62.705848) (xy 83.421241 -62.658298) (xy 83.391274 -62.606392) (xy 83.368338 -62.551019)
			(xy 83.352825 -62.493126) (xy 83.345002 -62.433704) (xy 52.676552 -62.433704) (xy 52.676552 -63.24117)
			(xy 77.78926 -63.24117) (xy 77.78926 -63.181234) (xy 77.797083 -63.121812) (xy 77.812596 -63.063919)
			(xy 77.835532 -63.008546) (xy 77.865499 -62.95664) (xy 77.901986 -62.90909) (xy 77.944366 -62.86671)
			(xy 77.991916 -62.830223) (xy 78.043822 -62.800256) (xy 78.099195 -62.77732) (xy 78.157088 -62.761807)
			(xy 78.21651 -62.753984) (xy 78.246478 -62.753494) (xy 78.276446 -62.753984) (xy 78.335868 -62.761807)
			(xy 78.393761 -62.77732) (xy 78.449134 -62.800256) (xy 78.50104 -62.830223) (xy 78.54859 -62.86671)
			(xy 78.59097 -62.90909) (xy 78.627457 -62.95664) (xy 78.657424 -63.008546) (xy 78.68036 -63.063919)
			(xy 78.695873 -63.121812) (xy 78.703696 -63.181234) (xy 78.703696 -63.24117) (xy 78.695873 -63.300592)
			(xy 78.68036 -63.358485) (xy 78.657424 -63.413858) (xy 78.627457 -63.465764) (xy 78.59097 -63.513314)
			(xy 78.54859 -63.555694) (xy 78.54736 -63.556638) (xy 81.066876 -63.556638) (xy 81.066876 -63.496702)
			(xy 81.074699 -63.43728) (xy 81.090212 -63.379387) (xy 81.113148 -63.324014) (xy 81.143115 -63.272108)
			(xy 81.179602 -63.224558) (xy 81.221982 -63.182178) (xy 81.269532 -63.145691) (xy 81.321438 -63.115724)
			(xy 81.376811 -63.092788) (xy 81.434704 -63.077275) (xy 81.494126 -63.069452) (xy 81.524094 -63.068962)
			(xy 81.554062 -63.069452) (xy 81.613484 -63.077275) (xy 81.671377 -63.092788) (xy 81.72675 -63.115724)
			(xy 81.778656 -63.145691) (xy 81.826206 -63.182178) (xy 81.868586 -63.224558) (xy 81.905073 -63.272108)
			(xy 81.93504 -63.324014) (xy 81.957976 -63.379387) (xy 81.973489 -63.43728) (xy 81.981312 -63.496702)
			(xy 81.981312 -63.556638) (xy 81.973489 -63.61606) (xy 81.957976 -63.673953) (xy 81.93504 -63.729326)
			(xy 81.905073 -63.781232) (xy 81.868586 -63.828782) (xy 81.826206 -63.871162) (xy 81.778656 -63.907649)
			(xy 81.72675 -63.937616) (xy 81.671377 -63.960552) (xy 81.613484 -63.976065) (xy 81.554062 -63.983888)
			(xy 81.494126 -63.983888) (xy 81.434704 -63.976065) (xy 81.376811 -63.960552) (xy 81.321438 -63.937616)
			(xy 81.269532 -63.907649) (xy 81.221982 -63.871162) (xy 81.179602 -63.828782) (xy 81.143115 -63.781232)
			(xy 81.113148 -63.729326) (xy 81.090212 -63.673953) (xy 81.074699 -63.61606) (xy 81.066876 -63.556638)
			(xy 78.54736 -63.556638) (xy 78.50104 -63.592181) (xy 78.449134 -63.622148) (xy 78.393761 -63.645084)
			(xy 78.335868 -63.660597) (xy 78.276446 -63.66842) (xy 78.21651 -63.66842) (xy 78.157088 -63.660597)
			(xy 78.099195 -63.645084) (xy 78.043822 -63.622148) (xy 77.991916 -63.592181) (xy 77.944366 -63.555694)
			(xy 77.901986 -63.513314) (xy 77.865499 -63.465764) (xy 77.835532 -63.413858) (xy 77.812596 -63.358485)
			(xy 77.797083 -63.300592) (xy 77.78926 -63.24117) (xy 52.676552 -63.24117) (xy 52.676552 -63.70828)
			(xy 51.025044 -63.70828) (xy 51.025044 -62.056264) (xy 28.154884 -62.056264) (xy 28.154884 -63.053484)
			(xy 29.519874 -63.053484) (xy 29.519874 -62.966584) (xy 29.527892 -62.880055) (xy 29.54386 -62.794635)
			(xy 29.567641 -62.711053) (xy 29.599033 -62.630021) (xy 29.637767 -62.552232) (xy 29.683514 -62.478348)
			(xy 29.735883 -62.409001) (xy 29.794427 -62.344781) (xy 29.858647 -62.286237) (xy 29.927994 -62.233868)
			(xy 30.001878 -62.188121) (xy 30.079667 -62.149387) (xy 30.160699 -62.117995) (xy 30.244281 -62.094214)
			(xy 30.329701 -62.078246) (xy 30.41623 -62.070228) (xy 30.45968 -62.069726) (xy 30.50313 -62.070228)
			(xy 30.589659 -62.078246) (xy 30.675079 -62.094214) (xy 30.758661 -62.117995) (xy 30.839693 -62.149387)
			(xy 30.917482 -62.188121) (xy 30.991366 -62.233868) (xy 31.060713 -62.286237) (xy 31.124933 -62.344781)
			(xy 31.183477 -62.409001) (xy 31.235846 -62.478348) (xy 31.281593 -62.552232) (xy 31.320327 -62.630021)
			(xy 31.351719 -62.711053) (xy 31.3755 -62.794635) (xy 31.391468 -62.880055) (xy 31.399486 -62.966584)
			(xy 31.399486 -63.053484) (xy 34.599874 -63.053484) (xy 34.599874 -62.966584) (xy 34.607892 -62.880055)
			(xy 34.62386 -62.794635) (xy 34.647641 -62.711053) (xy 34.679033 -62.630021) (xy 34.717767 -62.552232)
			(xy 34.763514 -62.478348) (xy 34.815883 -62.409001) (xy 34.874427 -62.344781) (xy 34.938647 -62.286237)
			(xy 35.007994 -62.233868) (xy 35.081878 -62.188121) (xy 35.159667 -62.149387) (xy 35.240699 -62.117995)
			(xy 35.324281 -62.094214) (xy 35.409701 -62.078246) (xy 35.49623 -62.070228) (xy 35.53968 -62.069726)
			(xy 35.58313 -62.070228) (xy 35.669659 -62.078246) (xy 35.755079 -62.094214) (xy 35.838661 -62.117995)
			(xy 35.919693 -62.149387) (xy 35.997482 -62.188121) (xy 36.071366 -62.233868) (xy 36.140713 -62.286237)
			(xy 36.204933 -62.344781) (xy 36.263477 -62.409001) (xy 36.315846 -62.478348) (xy 36.361593 -62.552232)
			(xy 36.400327 -62.630021) (xy 36.431719 -62.711053) (xy 36.4555 -62.794635) (xy 36.471468 -62.880055)
			(xy 36.479486 -62.966584) (xy 36.479486 -63.053484) (xy 36.471468 -63.140013) (xy 36.4555 -63.225433)
			(xy 36.431719 -63.309015) (xy 36.400327 -63.390047) (xy 36.361593 -63.467836) (xy 36.315846 -63.54172)
			(xy 36.263477 -63.611067) (xy 36.204933 -63.675287) (xy 36.140713 -63.733831) (xy 36.071366 -63.7862)
			(xy 35.997482 -63.831947) (xy 35.919693 -63.870681) (xy 35.838661 -63.902073) (xy 35.755079 -63.925854)
			(xy 35.669659 -63.941822) (xy 35.58313 -63.94984) (xy 35.49623 -63.94984) (xy 35.409701 -63.941822)
			(xy 35.324281 -63.925854) (xy 35.240699 -63.902073) (xy 35.159667 -63.870681) (xy 35.081878 -63.831947)
			(xy 35.007994 -63.7862) (xy 34.938647 -63.733831) (xy 34.874427 -63.675287) (xy 34.815883 -63.611067)
			(xy 34.763514 -63.54172) (xy 34.717767 -63.467836) (xy 34.679033 -63.390047) (xy 34.647641 -63.309015)
			(xy 34.62386 -63.225433) (xy 34.607892 -63.140013) (xy 34.599874 -63.053484) (xy 31.399486 -63.053484)
			(xy 31.391468 -63.140013) (xy 31.3755 -63.225433) (xy 31.351719 -63.309015) (xy 31.320327 -63.390047)
			(xy 31.281593 -63.467836) (xy 31.235846 -63.54172) (xy 31.183477 -63.611067) (xy 31.124933 -63.675287)
			(xy 31.060713 -63.733831) (xy 30.991366 -63.7862) (xy 30.917482 -63.831947) (xy 30.839693 -63.870681)
			(xy 30.758661 -63.902073) (xy 30.675079 -63.925854) (xy 30.589659 -63.941822) (xy 30.50313 -63.94984)
			(xy 30.41623 -63.94984) (xy 30.329701 -63.941822) (xy 30.244281 -63.925854) (xy 30.160699 -63.902073)
			(xy 30.079667 -63.870681) (xy 30.001878 -63.831947) (xy 29.927994 -63.7862) (xy 29.858647 -63.733831)
			(xy 29.794427 -63.675287) (xy 29.735883 -63.611067) (xy 29.683514 -63.54172) (xy 29.637767 -63.467836)
			(xy 29.599033 -63.390047) (xy 29.567641 -63.309015) (xy 29.54386 -63.225433) (xy 29.527892 -63.140013)
			(xy 29.519874 -63.053484) (xy 28.154884 -63.053484) (xy 28.154884 -64.048995) (xy 63.580764 -64.048995)
			(xy 63.580764 -63.977673) (xy 63.58875 -63.906799) (xy 63.60462 -63.837264) (xy 63.628177 -63.769944)
			(xy 63.659122 -63.705685) (xy 63.697068 -63.645294) (xy 63.741537 -63.589532) (xy 63.79197 -63.539099)
			(xy 63.847732 -63.49463) (xy 63.908123 -63.456684) (xy 63.972382 -63.425739) (xy 64.039702 -63.402182)
			(xy 64.109237 -63.386312) (xy 64.180111 -63.378326) (xy 64.215772 -63.377826) (xy 64.251433 -63.378326)
			(xy 64.322307 -63.386312) (xy 64.391842 -63.402182) (xy 64.459162 -63.425739) (xy 64.523421 -63.456684)
			(xy 64.583812 -63.49463) (xy 64.639574 -63.539099) (xy 64.690007 -63.589532) (xy 64.734476 -63.645294)
			(xy 64.772422 -63.705685) (xy 64.803367 -63.769944) (xy 64.826924 -63.837264) (xy 64.842794 -63.906799)
			(xy 64.85078 -63.977673) (xy 64.85078 -64.048995) (xy 66.572376 -64.048995) (xy 66.572376 -63.977673)
			(xy 66.580362 -63.906799) (xy 66.596232 -63.837264) (xy 66.619789 -63.769944) (xy 66.650734 -63.705685)
			(xy 66.68868 -63.645294) (xy 66.733149 -63.589532) (xy 66.783582 -63.539099) (xy 66.839344 -63.49463)
			(xy 66.899735 -63.456684) (xy 66.963994 -63.425739) (xy 67.031314 -63.402182) (xy 67.100849 -63.386312)
			(xy 67.171723 -63.378326) (xy 67.207384 -63.377826) (xy 67.243045 -63.378326) (xy 67.313919 -63.386312)
			(xy 67.383454 -63.402182) (xy 67.450774 -63.425739) (xy 67.515033 -63.456684) (xy 67.575424 -63.49463)
			(xy 67.631186 -63.539099) (xy 67.681619 -63.589532) (xy 67.726088 -63.645294) (xy 67.764034 -63.705685)
			(xy 67.794979 -63.769944) (xy 67.818536 -63.837264) (xy 67.834406 -63.906799) (xy 67.842392 -63.977673)
			(xy 67.842392 -64.048995) (xy 67.841259 -64.05905) (xy 79.537542 -64.05905) (xy 79.537542 -63.999114)
			(xy 79.545365 -63.939692) (xy 79.560878 -63.881799) (xy 79.583814 -63.826426) (xy 79.613781 -63.77452)
			(xy 79.650268 -63.72697) (xy 79.692648 -63.68459) (xy 79.740198 -63.648103) (xy 79.792104 -63.618136)
			(xy 79.847477 -63.5952) (xy 79.90537 -63.579687) (xy 79.964792 -63.571864) (xy 79.99476 -63.571374)
			(xy 80.024728 -63.571864) (xy 80.08415 -63.579687) (xy 80.142043 -63.5952) (xy 80.197416 -63.618136)
			(xy 80.249322 -63.648103) (xy 80.296872 -63.68459) (xy 80.339252 -63.72697) (xy 80.375739 -63.77452)
			(xy 80.405706 -63.826426) (xy 80.428642 -63.881799) (xy 80.444155 -63.939692) (xy 80.451978 -63.999114)
			(xy 80.451978 -64.05905) (xy 80.444155 -64.118472) (xy 80.428642 -64.176365) (xy 80.405706 -64.231738)
			(xy 80.375739 -64.283644) (xy 80.339252 -64.331194) (xy 80.296872 -64.373574) (xy 80.249322 -64.410061)
			(xy 80.197416 -64.440028) (xy 80.142043 -64.462964) (xy 80.08415 -64.478477) (xy 80.024728 -64.4863)
			(xy 79.964792 -64.4863) (xy 79.90537 -64.478477) (xy 79.847477 -64.462964) (xy 79.792104 -64.440028)
			(xy 79.740198 -64.410061) (xy 79.692648 -64.373574) (xy 79.650268 -64.331194) (xy 79.613781 -64.283644)
			(xy 79.583814 -64.231738) (xy 79.560878 -64.176365) (xy 79.545365 -64.118472) (xy 79.537542 -64.05905)
			(xy 67.841259 -64.05905) (xy 67.834406 -64.119869) (xy 67.818536 -64.189404) (xy 67.794979 -64.256724)
			(xy 67.764034 -64.320983) (xy 67.726088 -64.381374) (xy 67.681619 -64.437136) (xy 67.631186 -64.487569)
			(xy 67.602543 -64.510411) (xy 86.399122 -64.510411) (xy 86.401115 -64.310283) (xy 86.411112 -64.110394)
			(xy 86.429099 -63.911066) (xy 86.455047 -63.712617) (xy 86.488914 -63.515365) (xy 86.530646 -63.319626)
			(xy 86.580175 -63.125713) (xy 86.637424 -62.933938) (xy 86.702299 -62.744606) (xy 86.774698 -62.558022)
			(xy 86.854504 -62.374483) (xy 86.941589 -62.194285) (xy 87.035814 -62.017715) (xy 87.137028 -61.845056)
			(xy 87.245069 -61.676586) (xy 87.359764 -61.512572) (xy 87.48093 -61.353279) (xy 87.608371 -61.198962)
			(xy 87.741885 -61.049866) (xy 87.881257 -60.906232) (xy 88.026264 -60.76829) (xy 88.176675 -60.636259)
			(xy 88.332247 -60.510352) (xy 88.492732 -60.39077) (xy 88.657873 -60.277705) (xy 88.827405 -60.171337)
			(xy 89.001058 -60.071838) (xy 89.178552 -59.979366) (xy 89.359604 -59.89407) (xy 89.543924 -59.816086)
			(xy 89.731216 -59.745538) (xy 89.921181 -59.682541) (xy 90.113514 -59.627195) (xy 90.307908 -59.579588)
			(xy 90.504051 -59.539797) (xy 90.701628 -59.507885) (xy 90.900325 -59.483904) (xy 91.099821 -59.467891)
			(xy 91.299799 -59.459874) (xy 91.399868 -59.459368) (xy 91.499937 -59.459864) (xy 91.699915 -59.467861)
			(xy 91.899414 -59.483853) (xy 92.098112 -59.507814) (xy 92.295693 -59.539706) (xy 92.49184 -59.579477)
			(xy 92.686239 -59.627064) (xy 92.878578 -59.682391) (xy 93.068549 -59.745369) (xy 93.255848 -59.815897)
			(xy 93.440176 -59.893863) (xy 93.621237 -59.979141) (xy 93.79874 -60.071594) (xy 93.972403 -60.171076)
			(xy 94.141946 -60.277426) (xy 94.307099 -60.390475) (xy 94.467596 -60.51004) (xy 94.623181 -60.635932)
			(xy 94.773605 -60.767947) (xy 94.918626 -60.905875) (xy 95.058012 -61.049495) (xy 95.191541 -61.198576)
			(xy 95.318999 -61.352881) (xy 95.44018 -61.512162) (xy 95.554892 -61.676163) (xy 95.66295 -61.844623)
			(xy 95.764182 -62.017272) (xy 95.858425 -62.193832) (xy 95.945528 -62.374022) (xy 96.025353 -62.557552)
			(xy 96.09777 -62.744129) (xy 96.162665 -62.933454) (xy 96.219933 -63.125224) (xy 96.269483 -63.319131)
			(xy 96.311234 -63.514866) (xy 96.345121 -63.712115) (xy 96.371089 -63.910561) (xy 96.389096 -64.109888)
			(xy 96.399114 -64.309775) (xy 96.401127 -64.509903) (xy 96.395131 -64.709951) (xy 96.381135 -64.9096)
			(xy 96.359164 -65.108528) (xy 96.32925 -65.306418) (xy 96.291443 -65.502953) (xy 96.245804 -65.697818)
			(xy 96.192404 -65.890701) (xy 96.13133 -66.081293) (xy 96.062679 -66.269288) (xy 95.986561 -66.454387)
			(xy 95.903099 -66.636292) (xy 95.812426 -66.814711) (xy 95.714687 -66.989361) (xy 95.610038 -67.15996)
			(xy 95.498648 -67.326235) (xy 95.380694 -67.48792) (xy 95.256365 -67.644757) (xy 95.125862 -67.796494)
			(xy 94.989391 -67.942888) (xy 94.847173 -68.083704) (xy 94.699435 -68.218718) (xy 94.546413 -68.347713)
			(xy 94.388353 -68.470482) (xy 94.225507 -68.586829) (xy 94.058137 -68.696567) (xy 93.88651 -68.799521)
			(xy 93.710902 -68.895526) (xy 93.531592 -68.984428) (xy 93.34887 -69.066084) (xy 93.163027 -69.140365)
			(xy 92.97436 -69.207151) (xy 92.783173 -69.266334) (xy 92.589771 -69.317821) (xy 92.394464 -69.361529)
			(xy 92.197564 -69.397388) (xy 91.999387 -69.42534) (xy 91.800251 -69.44534) (xy 91.600474 -69.457358)
			(xy 91.400376 -69.461372) (xy 91.200278 -69.457378) (xy 91.000499 -69.445381) (xy 90.801361 -69.425401)
			(xy 90.603182 -69.397469) (xy 90.406278 -69.36163) (xy 90.210967 -69.317942) (xy 90.017559 -69.266475)
			(xy 89.826366 -69.207311) (xy 89.637693 -69.140544) (xy 89.451842 -69.066282) (xy 89.269111 -68.984644)
			(xy 89.089793 -68.895761) (xy 88.914175 -68.799774) (xy 88.742537 -68.696837) (xy 88.575156 -68.587116)
			(xy 88.412298 -68.470785) (xy 88.254226 -68.348032) (xy 88.101191 -68.219053) (xy 87.953439 -68.084055)
			(xy 87.811206 -67.943252) (xy 87.674721 -67.796872) (xy 87.544202 -67.645149) (xy 87.419858 -67.488325)
			(xy 87.301888 -67.326651) (xy 87.19048 -67.160387) (xy 87.085814 -66.989799) (xy 86.988057 -66.81516)
			(xy 86.897366 -66.636749) (xy 86.813885 -66.454853) (xy 86.737749 -66.269762) (xy 86.669079 -66.081773)
			(xy 86.607986 -65.891188) (xy 86.554566 -65.69831) (xy 86.508906 -65.50345) (xy 86.47108 -65.306919)
			(xy 86.441146 -65.109032) (xy 86.419154 -64.910106) (xy 86.405139 -64.710459) (xy 86.399122 -64.510411)
			(xy 67.602543 -64.510411) (xy 67.575424 -64.532038) (xy 67.515033 -64.569984) (xy 67.450774 -64.600929)
			(xy 67.383454 -64.624486) (xy 67.313919 -64.640356) (xy 67.243045 -64.648342) (xy 67.171723 -64.648342)
			(xy 67.100849 -64.640356) (xy 67.031314 -64.624486) (xy 66.963994 -64.600929) (xy 66.899735 -64.569984)
			(xy 66.839344 -64.532038) (xy 66.783582 -64.487569) (xy 66.733149 -64.437136) (xy 66.68868 -64.381374)
			(xy 66.650734 -64.320983) (xy 66.619789 -64.256724) (xy 66.596232 -64.189404) (xy 66.580362 -64.119869)
			(xy 66.572376 -64.048995) (xy 64.85078 -64.048995) (xy 64.842794 -64.119869) (xy 64.826924 -64.189404)
			(xy 64.803367 -64.256724) (xy 64.772422 -64.320983) (xy 64.734476 -64.381374) (xy 64.690007 -64.437136)
			(xy 64.639574 -64.487569) (xy 64.583812 -64.532038) (xy 64.523421 -64.569984) (xy 64.459162 -64.600929)
			(xy 64.391842 -64.624486) (xy 64.322307 -64.640356) (xy 64.251433 -64.648342) (xy 64.180111 -64.648342)
			(xy 64.109237 -64.640356) (xy 64.039702 -64.624486) (xy 63.972382 -64.600929) (xy 63.908123 -64.569984)
			(xy 63.847732 -64.532038) (xy 63.79197 -64.487569) (xy 63.741537 -64.437136) (xy 63.697068 -64.381374)
			(xy 63.659122 -64.320983) (xy 63.628177 -64.256724) (xy 63.60462 -64.189404) (xy 63.58875 -64.119869)
			(xy 63.580764 -64.048995) (xy 28.154884 -64.048995) (xy 28.154884 -65.593484) (xy 29.519874 -65.593484)
			(xy 29.519874 -65.506584) (xy 29.527892 -65.420055) (xy 29.54386 -65.334635) (xy 29.567641 -65.251053)
			(xy 29.599033 -65.170021) (xy 29.637767 -65.092232) (xy 29.683514 -65.018348) (xy 29.735883 -64.949001)
			(xy 29.794427 -64.884781) (xy 29.858647 -64.826237) (xy 29.927994 -64.773868) (xy 30.001878 -64.728121)
			(xy 30.079667 -64.689387) (xy 30.160699 -64.657995) (xy 30.244281 -64.634214) (xy 30.329701 -64.618246)
			(xy 30.41623 -64.610228) (xy 30.45968 -64.609726) (xy 30.50313 -64.610228) (xy 30.589659 -64.618246)
			(xy 30.675079 -64.634214) (xy 30.758661 -64.657995) (xy 30.839693 -64.689387) (xy 30.917482 -64.728121)
			(xy 30.991366 -64.773868) (xy 31.060713 -64.826237) (xy 31.124933 -64.884781) (xy 31.183477 -64.949001)
			(xy 31.235846 -65.018348) (xy 31.281593 -65.092232) (xy 31.320327 -65.170021) (xy 31.351719 -65.251053)
			(xy 31.3755 -65.334635) (xy 31.391468 -65.420055) (xy 31.399486 -65.506584) (xy 31.399486 -65.593484)
			(xy 34.599874 -65.593484) (xy 34.599874 -65.506584) (xy 34.607892 -65.420055) (xy 34.62386 -65.334635)
			(xy 34.647641 -65.251053) (xy 34.679033 -65.170021) (xy 34.717767 -65.092232) (xy 34.763514 -65.018348)
			(xy 34.815883 -64.949001) (xy 34.874427 -64.884781) (xy 34.938647 -64.826237) (xy 35.007994 -64.773868)
			(xy 35.081878 -64.728121) (xy 35.159667 -64.689387) (xy 35.240699 -64.657995) (xy 35.324281 -64.634214)
			(xy 35.409701 -64.618246) (xy 35.49623 -64.610228) (xy 35.53968 -64.609726) (xy 35.58313 -64.610228)
			(xy 35.669659 -64.618246) (xy 35.755079 -64.634214) (xy 35.838661 -64.657995) (xy 35.919693 -64.689387)
			(xy 35.997482 -64.728121) (xy 36.071366 -64.773868) (xy 36.140713 -64.826237) (xy 36.204933 -64.884781)
			(xy 36.263477 -64.949001) (xy 36.315846 -65.018348) (xy 36.361593 -65.092232) (xy 36.400327 -65.170021)
			(xy 36.431719 -65.251053) (xy 36.4555 -65.334635) (xy 36.471468 -65.420055) (xy 36.479486 -65.506584)
			(xy 36.479486 -65.593484) (xy 36.471468 -65.680013) (xy 36.4555 -65.765433) (xy 36.431719 -65.849015)
			(xy 36.400327 -65.930047) (xy 36.361593 -66.007836) (xy 36.359072 -66.011907) (xy 63.580764 -66.011907)
			(xy 63.580764 -65.940585) (xy 63.58875 -65.869711) (xy 63.60462 -65.800176) (xy 63.628177 -65.732856)
			(xy 63.659122 -65.668597) (xy 63.697068 -65.608206) (xy 63.741537 -65.552444) (xy 63.79197 -65.502011)
			(xy 63.847732 -65.457542) (xy 63.908123 -65.419596) (xy 63.972382 -65.388651) (xy 64.039702 -65.365094)
			(xy 64.109237 -65.349224) (xy 64.180111 -65.341238) (xy 64.215772 -65.340738) (xy 64.251433 -65.341238)
			(xy 64.322307 -65.349224) (xy 64.391842 -65.365094) (xy 64.459162 -65.388651) (xy 64.523421 -65.419596)
			(xy 64.583812 -65.457542) (xy 64.639574 -65.502011) (xy 64.690007 -65.552444) (xy 64.734476 -65.608206)
			(xy 64.772422 -65.668597) (xy 64.803367 -65.732856) (xy 64.826924 -65.800176) (xy 64.842794 -65.869711)
			(xy 64.85078 -65.940585) (xy 64.85078 -66.011907) (xy 66.572376 -66.011907) (xy 66.572376 -65.940585)
			(xy 66.580362 -65.869711) (xy 66.596232 -65.800176) (xy 66.619789 -65.732856) (xy 66.650734 -65.668597)
			(xy 66.68868 -65.608206) (xy 66.733149 -65.552444) (xy 66.783582 -65.502011) (xy 66.839344 -65.457542)
			(xy 66.899735 -65.419596) (xy 66.963994 -65.388651) (xy 67.031314 -65.365094) (xy 67.100849 -65.349224)
			(xy 67.171723 -65.341238) (xy 67.207384 -65.340738) (xy 67.243045 -65.341238) (xy 67.313919 -65.349224)
			(xy 67.383454 -65.365094) (xy 67.450774 -65.388651) (xy 67.515033 -65.419596) (xy 67.575424 -65.457542)
			(xy 67.631186 -65.502011) (xy 67.681619 -65.552444) (xy 67.726088 -65.608206) (xy 67.764034 -65.668597)
			(xy 67.78473 -65.711574) (xy 77.233 -65.711574) (xy 77.233 -65.651638) (xy 77.240823 -65.592216)
			(xy 77.256336 -65.534323) (xy 77.279272 -65.47895) (xy 77.309239 -65.427044) (xy 77.345726 -65.379494)
			(xy 77.388106 -65.337114) (xy 77.435656 -65.300627) (xy 77.487562 -65.27066) (xy 77.542935 -65.247724)
			(xy 77.600828 -65.232211) (xy 77.66025 -65.224388) (xy 77.690218 -65.223898) (xy 77.720186 -65.224388)
			(xy 77.779608 -65.232211) (xy 77.837501 -65.247724) (xy 77.892874 -65.27066) (xy 77.94478 -65.300627)
			(xy 77.99233 -65.337114) (xy 78.03471 -65.379494) (xy 78.071197 -65.427044) (xy 78.101164 -65.47895)
			(xy 78.1241 -65.534323) (xy 78.139613 -65.592216) (xy 78.147436 -65.651638) (xy 78.147436 -65.711574)
			(xy 78.139613 -65.770996) (xy 78.1241 -65.828889) (xy 78.101164 -65.884262) (xy 78.071197 -65.936168)
			(xy 78.03471 -65.983718) (xy 77.99233 -66.026098) (xy 77.94478 -66.062585) (xy 77.892874 -66.092552)
			(xy 77.837501 -66.115488) (xy 77.779608 -66.131001) (xy 77.720186 -66.138824) (xy 77.66025 -66.138824)
			(xy 77.600828 -66.131001) (xy 77.542935 -66.115488) (xy 77.487562 -66.092552) (xy 77.435656 -66.062585)
			(xy 77.388106 -66.026098) (xy 77.345726 -65.983718) (xy 77.309239 -65.936168) (xy 77.279272 -65.884262)
			(xy 77.256336 -65.828889) (xy 77.240823 -65.770996) (xy 77.233 -65.711574) (xy 67.78473 -65.711574)
			(xy 67.794979 -65.732856) (xy 67.818536 -65.800176) (xy 67.834406 -65.869711) (xy 67.842392 -65.940585)
			(xy 67.842392 -66.011907) (xy 67.834406 -66.082781) (xy 67.818536 -66.152316) (xy 67.794979 -66.219636)
			(xy 67.764034 -66.283895) (xy 67.726088 -66.344286) (xy 67.681619 -66.400048) (xy 67.631186 -66.450481)
			(xy 67.575424 -66.49495) (xy 67.515033 -66.532896) (xy 67.450774 -66.563841) (xy 67.383454 -66.587398)
			(xy 67.313919 -66.603268) (xy 67.243045 -66.611254) (xy 67.171723 -66.611254) (xy 67.100849 -66.603268)
			(xy 67.031314 -66.587398) (xy 66.963994 -66.563841) (xy 66.899735 -66.532896) (xy 66.839344 -66.49495)
			(xy 66.783582 -66.450481) (xy 66.733149 -66.400048) (xy 66.68868 -66.344286) (xy 66.650734 -66.283895)
			(xy 66.619789 -66.219636) (xy 66.596232 -66.152316) (xy 66.580362 -66.082781) (xy 66.572376 -66.011907)
			(xy 64.85078 -66.011907) (xy 64.842794 -66.082781) (xy 64.826924 -66.152316) (xy 64.803367 -66.219636)
			(xy 64.772422 -66.283895) (xy 64.734476 -66.344286) (xy 64.690007 -66.400048) (xy 64.639574 -66.450481)
			(xy 64.583812 -66.49495) (xy 64.523421 -66.532896) (xy 64.459162 -66.563841) (xy 64.391842 -66.587398)
			(xy 64.322307 -66.603268) (xy 64.251433 -66.611254) (xy 64.180111 -66.611254) (xy 64.109237 -66.603268)
			(xy 64.039702 -66.587398) (xy 63.972382 -66.563841) (xy 63.908123 -66.532896) (xy 63.847732 -66.49495)
			(xy 63.79197 -66.450481) (xy 63.741537 -66.400048) (xy 63.697068 -66.344286) (xy 63.659122 -66.283895)
			(xy 63.628177 -66.219636) (xy 63.60462 -66.152316) (xy 63.58875 -66.082781) (xy 63.580764 -66.011907)
			(xy 36.359072 -66.011907) (xy 36.315846 -66.08172) (xy 36.263477 -66.151067) (xy 36.204933 -66.215287)
			(xy 36.140713 -66.273831) (xy 36.071366 -66.3262) (xy 35.997482 -66.371947) (xy 35.919693 -66.410681)
			(xy 35.838661 -66.442073) (xy 35.755079 -66.465854) (xy 35.669659 -66.481822) (xy 35.58313 -66.48984)
			(xy 35.49623 -66.48984) (xy 35.409701 -66.481822) (xy 35.324281 -66.465854) (xy 35.240699 -66.442073)
			(xy 35.159667 -66.410681) (xy 35.081878 -66.371947) (xy 35.007994 -66.3262) (xy 34.938647 -66.273831)
			(xy 34.874427 -66.215287) (xy 34.815883 -66.151067) (xy 34.763514 -66.08172) (xy 34.717767 -66.007836)
			(xy 34.679033 -65.930047) (xy 34.647641 -65.849015) (xy 34.62386 -65.765433) (xy 34.607892 -65.680013)
			(xy 34.599874 -65.593484) (xy 31.399486 -65.593484) (xy 31.391468 -65.680013) (xy 31.3755 -65.765433)
			(xy 31.351719 -65.849015) (xy 31.320327 -65.930047) (xy 31.281593 -66.007836) (xy 31.235846 -66.08172)
			(xy 31.183477 -66.151067) (xy 31.124933 -66.215287) (xy 31.060713 -66.273831) (xy 30.991366 -66.3262)
			(xy 30.917482 -66.371947) (xy 30.839693 -66.410681) (xy 30.758661 -66.442073) (xy 30.675079 -66.465854)
			(xy 30.589659 -66.481822) (xy 30.50313 -66.48984) (xy 30.41623 -66.48984) (xy 30.329701 -66.481822)
			(xy 30.244281 -66.465854) (xy 30.160699 -66.442073) (xy 30.079667 -66.410681) (xy 30.001878 -66.371947)
			(xy 29.927994 -66.3262) (xy 29.858647 -66.273831) (xy 29.794427 -66.215287) (xy 29.735883 -66.151067)
			(xy 29.683514 -66.08172) (xy 29.637767 -66.007836) (xy 29.599033 -65.930047) (xy 29.567641 -65.849015)
			(xy 29.54386 -65.765433) (xy 29.527892 -65.680013) (xy 29.519874 -65.593484) (xy 28.154884 -65.593484)
			(xy 28.154884 -68.133484) (xy 29.519874 -68.133484) (xy 29.519874 -68.046584) (xy 29.527892 -67.960055)
			(xy 29.54386 -67.874635) (xy 29.567641 -67.791053) (xy 29.599033 -67.710021) (xy 29.637767 -67.632232)
			(xy 29.683514 -67.558348) (xy 29.735883 -67.489001) (xy 29.794427 -67.424781) (xy 29.858647 -67.366237)
			(xy 29.927994 -67.313868) (xy 30.001878 -67.268121) (xy 30.079667 -67.229387) (xy 30.160699 -67.197995)
			(xy 30.244281 -67.174214) (xy 30.329701 -67.158246) (xy 30.41623 -67.150228) (xy 30.45968 -67.149726)
			(xy 30.50313 -67.150228) (xy 30.589659 -67.158246) (xy 30.675079 -67.174214) (xy 30.758661 -67.197995)
			(xy 30.839693 -67.229387) (xy 30.917482 -67.268121) (xy 30.991366 -67.313868) (xy 31.060713 -67.366237)
			(xy 31.124933 -67.424781) (xy 31.183477 -67.489001) (xy 31.235846 -67.558348) (xy 31.281593 -67.632232)
			(xy 31.320327 -67.710021) (xy 31.351719 -67.791053) (xy 31.3755 -67.874635) (xy 31.391468 -67.960055)
			(xy 31.399486 -68.046584) (xy 31.399486 -68.133484) (xy 34.599874 -68.133484) (xy 34.599874 -68.046584)
			(xy 34.607892 -67.960055) (xy 34.62386 -67.874635) (xy 34.647641 -67.791053) (xy 34.679033 -67.710021)
			(xy 34.717767 -67.632232) (xy 34.763514 -67.558348) (xy 34.815883 -67.489001) (xy 34.874427 -67.424781)
			(xy 34.938647 -67.366237) (xy 35.007994 -67.313868) (xy 35.081878 -67.268121) (xy 35.159667 -67.229387)
			(xy 35.240699 -67.197995) (xy 35.324281 -67.174214) (xy 35.409701 -67.158246) (xy 35.49623 -67.150228)
			(xy 35.53968 -67.149726) (xy 35.58313 -67.150228) (xy 35.669659 -67.158246) (xy 35.755079 -67.174214)
			(xy 35.838661 -67.197995) (xy 35.919693 -67.229387) (xy 35.997482 -67.268121) (xy 36.071366 -67.313868)
			(xy 36.140713 -67.366237) (xy 36.204933 -67.424781) (xy 36.263477 -67.489001) (xy 36.305421 -67.544543)
			(xy 41.522642 -67.544543) (xy 41.522642 -67.473221) (xy 41.530628 -67.402347) (xy 41.546498 -67.332812)
			(xy 41.570055 -67.265492) (xy 41.601 -67.201233) (xy 41.638946 -67.140842) (xy 41.683415 -67.08508)
			(xy 41.733848 -67.034647) (xy 41.78961 -66.990178) (xy 41.850001 -66.952232) (xy 41.91426 -66.921287)
			(xy 41.98158 -66.89773) (xy 42.051115 -66.88186) (xy 42.121989 -66.873874) (xy 42.15765 -66.873374)
			(xy 42.193311 -66.873874) (xy 42.264185 -66.88186) (xy 42.33372 -66.89773) (xy 42.40104 -66.921287)
			(xy 42.465299 -66.952232) (xy 42.52569 -66.990178) (xy 42.581452 -67.034647) (xy 42.631885 -67.08508)
			(xy 42.676354 -67.140842) (xy 42.7143 -67.201233) (xy 42.745245 -67.265492) (xy 42.768802 -67.332812)
			(xy 42.784672 -67.402347) (xy 42.792658 -67.473221) (xy 42.792658 -67.544543) (xy 42.784672 -67.615417)
			(xy 42.768802 -67.684952) (xy 42.745245 -67.752272) (xy 42.7143 -67.816531) (xy 42.676354 -67.876922)
			(xy 42.631885 -67.932684) (xy 42.581452 -67.983117) (xy 42.52569 -68.027586) (xy 42.465299 -68.065532)
			(xy 42.40104 -68.096477) (xy 42.33372 -68.120034) (xy 42.264185 -68.135904) (xy 42.193311 -68.14389)
			(xy 42.121989 -68.14389) (xy 42.051115 -68.135904) (xy 41.98158 -68.120034) (xy 41.91426 -68.096477)
			(xy 41.850001 -68.065532) (xy 41.78961 -68.027586) (xy 41.733848 -67.983117) (xy 41.683415 -67.932684)
			(xy 41.638946 -67.876922) (xy 41.601 -67.816531) (xy 41.570055 -67.752272) (xy 41.546498 -67.684952)
			(xy 41.530628 -67.615417) (xy 41.522642 -67.544543) (xy 36.305421 -67.544543) (xy 36.315846 -67.558348)
			(xy 36.361593 -67.632232) (xy 36.400327 -67.710021) (xy 36.431719 -67.791053) (xy 36.4555 -67.874635)
			(xy 36.471468 -67.960055) (xy 36.479486 -68.046584) (xy 36.479486 -68.133484) (xy 36.477454 -68.155413)
			(xy 63.580764 -68.155413) (xy 63.580764 -68.084091) (xy 63.58875 -68.013217) (xy 63.60462 -67.943682)
			(xy 63.628177 -67.876362) (xy 63.659122 -67.812103) (xy 63.697068 -67.751712) (xy 63.741537 -67.69595)
			(xy 63.79197 -67.645517) (xy 63.847732 -67.601048) (xy 63.908123 -67.563102) (xy 63.972382 -67.532157)
			(xy 64.039702 -67.5086) (xy 64.109237 -67.49273) (xy 64.180111 -67.484744) (xy 64.215772 -67.484244)
			(xy 64.251433 -67.484744) (xy 64.322307 -67.49273) (xy 64.391842 -67.5086) (xy 64.459162 -67.532157)
			(xy 64.523421 -67.563102) (xy 64.583812 -67.601048) (xy 64.639574 -67.645517) (xy 64.690007 -67.69595)
			(xy 64.734476 -67.751712) (xy 64.772422 -67.812103) (xy 64.803367 -67.876362) (xy 64.826924 -67.943682)
			(xy 64.842794 -68.013217) (xy 64.85078 -68.084091) (xy 64.85078 -68.155413) (xy 66.572376 -68.155413)
			(xy 66.572376 -68.084091) (xy 66.580362 -68.013217) (xy 66.596232 -67.943682) (xy 66.619789 -67.876362)
			(xy 66.650734 -67.812103) (xy 66.68868 -67.751712) (xy 66.733149 -67.69595) (xy 66.783582 -67.645517)
			(xy 66.839344 -67.601048) (xy 66.899735 -67.563102) (xy 66.963994 -67.532157) (xy 67.031314 -67.5086)
			(xy 67.100849 -67.49273) (xy 67.171723 -67.484744) (xy 67.207384 -67.484244) (xy 67.243045 -67.484744)
			(xy 67.313919 -67.49273) (xy 67.383454 -67.5086) (xy 67.450774 -67.532157) (xy 67.515033 -67.563102)
			(xy 67.575424 -67.601048) (xy 67.631186 -67.645517) (xy 67.681619 -67.69595) (xy 67.726088 -67.751712)
			(xy 67.764034 -67.812103) (xy 67.794979 -67.876362) (xy 67.818536 -67.943682) (xy 67.834406 -68.013217)
			(xy 67.842392 -68.084091) (xy 67.842392 -68.155413) (xy 67.834406 -68.226287) (xy 67.818536 -68.295822)
			(xy 67.794979 -68.363142) (xy 67.764034 -68.427401) (xy 67.726088 -68.487792) (xy 67.681619 -68.543554)
			(xy 67.631186 -68.593987) (xy 67.575424 -68.638456) (xy 67.515033 -68.676402) (xy 67.450774 -68.707347)
			(xy 67.383454 -68.730904) (xy 67.313919 -68.746774) (xy 67.243045 -68.75476) (xy 67.171723 -68.75476)
			(xy 67.100849 -68.746774) (xy 67.031314 -68.730904) (xy 66.963994 -68.707347) (xy 66.899735 -68.676402)
			(xy 66.839344 -68.638456) (xy 66.783582 -68.593987) (xy 66.733149 -68.543554) (xy 66.68868 -68.487792)
			(xy 66.650734 -68.427401) (xy 66.619789 -68.363142) (xy 66.596232 -68.295822) (xy 66.580362 -68.226287)
			(xy 66.572376 -68.155413) (xy 64.85078 -68.155413) (xy 64.842794 -68.226287) (xy 64.826924 -68.295822)
			(xy 64.803367 -68.363142) (xy 64.772422 -68.427401) (xy 64.734476 -68.487792) (xy 64.690007 -68.543554)
			(xy 64.639574 -68.593987) (xy 64.583812 -68.638456) (xy 64.523421 -68.676402) (xy 64.459162 -68.707347)
			(xy 64.391842 -68.730904) (xy 64.322307 -68.746774) (xy 64.251433 -68.75476) (xy 64.180111 -68.75476)
			(xy 64.109237 -68.746774) (xy 64.039702 -68.730904) (xy 63.972382 -68.707347) (xy 63.908123 -68.676402)
			(xy 63.847732 -68.638456) (xy 63.79197 -68.593987) (xy 63.741537 -68.543554) (xy 63.697068 -68.487792)
			(xy 63.659122 -68.427401) (xy 63.628177 -68.363142) (xy 63.60462 -68.295822) (xy 63.58875 -68.226287)
			(xy 63.580764 -68.155413) (xy 36.477454 -68.155413) (xy 36.471468 -68.220013) (xy 36.4555 -68.305433)
			(xy 36.431719 -68.389015) (xy 36.400327 -68.470047) (xy 36.361593 -68.547836) (xy 36.315846 -68.62172)
			(xy 36.263477 -68.691067) (xy 36.204933 -68.755287) (xy 36.140713 -68.813831) (xy 36.071366 -68.8662)
			(xy 35.997482 -68.911947) (xy 35.919693 -68.950681) (xy 35.838661 -68.982073) (xy 35.755079 -69.005854)
			(xy 35.669659 -69.021822) (xy 35.58313 -69.02984) (xy 35.49623 -69.02984) (xy 35.409701 -69.021822)
			(xy 35.324281 -69.005854) (xy 35.240699 -68.982073) (xy 35.159667 -68.950681) (xy 35.081878 -68.911947)
			(xy 35.007994 -68.8662) (xy 34.938647 -68.813831) (xy 34.874427 -68.755287) (xy 34.815883 -68.691067)
			(xy 34.763514 -68.62172) (xy 34.717767 -68.547836) (xy 34.679033 -68.470047) (xy 34.647641 -68.389015)
			(xy 34.62386 -68.305433) (xy 34.607892 -68.220013) (xy 34.599874 -68.133484) (xy 31.399486 -68.133484)
			(xy 31.391468 -68.220013) (xy 31.3755 -68.305433) (xy 31.351719 -68.389015) (xy 31.320327 -68.470047)
			(xy 31.281593 -68.547836) (xy 31.235846 -68.62172) (xy 31.183477 -68.691067) (xy 31.124933 -68.755287)
			(xy 31.060713 -68.813831) (xy 30.991366 -68.8662) (xy 30.917482 -68.911947) (xy 30.839693 -68.950681)
			(xy 30.758661 -68.982073) (xy 30.675079 -69.005854) (xy 30.589659 -69.021822) (xy 30.50313 -69.02984)
			(xy 30.41623 -69.02984) (xy 30.329701 -69.021822) (xy 30.244281 -69.005854) (xy 30.160699 -68.982073)
			(xy 30.079667 -68.950681) (xy 30.001878 -68.911947) (xy 29.927994 -68.8662) (xy 29.858647 -68.813831)
			(xy 29.794427 -68.755287) (xy 29.735883 -68.691067) (xy 29.683514 -68.62172) (xy 29.637767 -68.547836)
			(xy 29.599033 -68.470047) (xy 29.567641 -68.389015) (xy 29.54386 -68.305433) (xy 29.527892 -68.220013)
			(xy 29.519874 -68.133484) (xy 28.154884 -68.133484) (xy 28.154884 -70.673484) (xy 29.519874 -70.673484)
			(xy 29.519874 -70.586584) (xy 29.527892 -70.500055) (xy 29.54386 -70.414635) (xy 29.567641 -70.331053)
			(xy 29.599033 -70.250021) (xy 29.637767 -70.172232) (xy 29.683514 -70.098348) (xy 29.735883 -70.029001)
			(xy 29.794427 -69.964781) (xy 29.858647 -69.906237) (xy 29.927994 -69.853868) (xy 30.001878 -69.808121)
			(xy 30.079667 -69.769387) (xy 30.160699 -69.737995) (xy 30.244281 -69.714214) (xy 30.329701 -69.698246)
			(xy 30.41623 -69.690228) (xy 30.45968 -69.689726) (xy 30.50313 -69.690228) (xy 30.589659 -69.698246)
			(xy 30.675079 -69.714214) (xy 30.758661 -69.737995) (xy 30.839693 -69.769387) (xy 30.917482 -69.808121)
			(xy 30.991366 -69.853868) (xy 31.060713 -69.906237) (xy 31.124933 -69.964781) (xy 31.183477 -70.029001)
			(xy 31.235846 -70.098348) (xy 31.281593 -70.172232) (xy 31.320327 -70.250021) (xy 31.351719 -70.331053)
			(xy 31.3755 -70.414635) (xy 31.391468 -70.500055) (xy 31.399486 -70.586584) (xy 31.399486 -70.673484)
			(xy 34.599874 -70.673484) (xy 34.599874 -70.586584) (xy 34.607892 -70.500055) (xy 34.62386 -70.414635)
			(xy 34.647641 -70.331053) (xy 34.679033 -70.250021) (xy 34.717767 -70.172232) (xy 34.763514 -70.098348)
			(xy 34.815883 -70.029001) (xy 34.874427 -69.964781) (xy 34.938647 -69.906237) (xy 35.007994 -69.853868)
			(xy 35.081878 -69.808121) (xy 35.159667 -69.769387) (xy 35.240699 -69.737995) (xy 35.324281 -69.714214)
			(xy 35.409701 -69.698246) (xy 35.49623 -69.690228) (xy 35.53968 -69.689726) (xy 35.58313 -69.690228)
			(xy 35.669659 -69.698246) (xy 35.755079 -69.714214) (xy 35.838661 -69.737995) (xy 35.919693 -69.769387)
			(xy 35.997482 -69.808121) (xy 36.071366 -69.853868) (xy 36.140713 -69.906237) (xy 36.204933 -69.964781)
			(xy 36.263477 -70.029001) (xy 36.315846 -70.098348) (xy 36.361593 -70.172232) (xy 36.383065 -70.215353)
			(xy 41.522642 -70.215353) (xy 41.522642 -70.144031) (xy 41.530628 -70.073157) (xy 41.546498 -70.003622)
			(xy 41.570055 -69.936302) (xy 41.601 -69.872043) (xy 41.638946 -69.811652) (xy 41.683415 -69.75589)
			(xy 41.733848 -69.705457) (xy 41.78961 -69.660988) (xy 41.850001 -69.623042) (xy 41.91426 -69.592097)
			(xy 41.98158 -69.56854) (xy 42.051115 -69.55267) (xy 42.121989 -69.544684) (xy 42.15765 -69.544184)
			(xy 42.193311 -69.544684) (xy 42.264185 -69.55267) (xy 42.33372 -69.56854) (xy 42.40104 -69.592097)
			(xy 42.465299 -69.623042) (xy 42.52569 -69.660988) (xy 42.581452 -69.705457) (xy 42.631885 -69.75589)
			(xy 42.676354 -69.811652) (xy 42.7143 -69.872043) (xy 42.745245 -69.936302) (xy 42.768802 -70.003622)
			(xy 42.784672 -70.073157) (xy 42.792658 -70.144031) (xy 42.792658 -70.215353) (xy 42.784672 -70.286227)
			(xy 42.768802 -70.355762) (xy 42.745245 -70.423082) (xy 42.7143 -70.487341) (xy 42.676354 -70.547732)
			(xy 42.631885 -70.603494) (xy 42.581452 -70.653927) (xy 42.52569 -70.698396) (xy 42.465299 -70.736342)
			(xy 42.40104 -70.767287) (xy 42.33372 -70.790844) (xy 42.264185 -70.806714) (xy 42.193311 -70.8147)
			(xy 42.121989 -70.8147) (xy 42.051115 -70.806714) (xy 41.98158 -70.790844) (xy 41.91426 -70.767287)
			(xy 41.850001 -70.736342) (xy 41.78961 -70.698396) (xy 41.733848 -70.653927) (xy 41.683415 -70.603494)
			(xy 41.638946 -70.547732) (xy 41.601 -70.487341) (xy 41.570055 -70.423082) (xy 41.546498 -70.355762)
			(xy 41.530628 -70.286227) (xy 41.522642 -70.215353) (xy 36.383065 -70.215353) (xy 36.400327 -70.250021)
			(xy 36.431719 -70.331053) (xy 36.4555 -70.414635) (xy 36.471468 -70.500055) (xy 36.479486 -70.586584)
			(xy 36.479486 -70.673484) (xy 36.471468 -70.760013) (xy 36.4555 -70.845433) (xy 36.431719 -70.929015)
			(xy 36.400327 -71.010047) (xy 36.361593 -71.087836) (xy 36.315846 -71.16172) (xy 36.263477 -71.231067)
			(xy 36.204933 -71.295287) (xy 36.140713 -71.353831) (xy 36.071366 -71.4062) (xy 35.997482 -71.451947)
			(xy 35.919693 -71.490681) (xy 35.838661 -71.522073) (xy 35.755079 -71.545854) (xy 35.669659 -71.561822)
			(xy 35.58313 -71.56984) (xy 35.49623 -71.56984) (xy 35.409701 -71.561822) (xy 35.324281 -71.545854)
			(xy 35.240699 -71.522073) (xy 35.159667 -71.490681) (xy 35.081878 -71.451947) (xy 35.007994 -71.4062)
			(xy 34.938647 -71.353831) (xy 34.874427 -71.295287) (xy 34.815883 -71.231067) (xy 34.763514 -71.16172)
			(xy 34.717767 -71.087836) (xy 34.679033 -71.010047) (xy 34.647641 -70.929015) (xy 34.62386 -70.845433)
			(xy 34.607892 -70.760013) (xy 34.599874 -70.673484) (xy 31.399486 -70.673484) (xy 31.391468 -70.760013)
			(xy 31.3755 -70.845433) (xy 31.351719 -70.929015) (xy 31.320327 -71.010047) (xy 31.281593 -71.087836)
			(xy 31.235846 -71.16172) (xy 31.183477 -71.231067) (xy 31.124933 -71.295287) (xy 31.060713 -71.353831)
			(xy 30.991366 -71.4062) (xy 30.917482 -71.451947) (xy 30.839693 -71.490681) (xy 30.758661 -71.522073)
			(xy 30.675079 -71.545854) (xy 30.589659 -71.561822) (xy 30.50313 -71.56984) (xy 30.41623 -71.56984)
			(xy 30.329701 -71.561822) (xy 30.244281 -71.545854) (xy 30.160699 -71.522073) (xy 30.079667 -71.490681)
			(xy 30.001878 -71.451947) (xy 29.927994 -71.4062) (xy 29.858647 -71.353831) (xy 29.794427 -71.295287)
			(xy 29.735883 -71.231067) (xy 29.683514 -71.16172) (xy 29.637767 -71.087836) (xy 29.599033 -71.010047)
			(xy 29.567641 -70.929015) (xy 29.54386 -70.845433) (xy 29.527892 -70.760013) (xy 29.519874 -70.673484)
			(xy 28.154884 -70.673484) (xy 28.154884 -73.213484) (xy 29.519874 -73.213484) (xy 29.519874 -73.126584)
			(xy 29.527892 -73.040055) (xy 29.54386 -72.954635) (xy 29.567641 -72.871053) (xy 29.599033 -72.790021)
			(xy 29.637767 -72.712232) (xy 29.683514 -72.638348) (xy 29.735883 -72.569001) (xy 29.794427 -72.504781)
			(xy 29.858647 -72.446237) (xy 29.927994 -72.393868) (xy 30.001878 -72.348121) (xy 30.079667 -72.309387)
			(xy 30.160699 -72.277995) (xy 30.244281 -72.254214) (xy 30.329701 -72.238246) (xy 30.41623 -72.230228)
			(xy 30.45968 -72.229726) (xy 30.50313 -72.230228) (xy 30.589659 -72.238246) (xy 30.675079 -72.254214)
			(xy 30.758661 -72.277995) (xy 30.839693 -72.309387) (xy 30.917482 -72.348121) (xy 30.991366 -72.393868)
			(xy 31.060713 -72.446237) (xy 31.124933 -72.504781) (xy 31.183477 -72.569001) (xy 31.235846 -72.638348)
			(xy 31.281593 -72.712232) (xy 31.320327 -72.790021) (xy 31.351719 -72.871053) (xy 31.3755 -72.954635)
			(xy 31.391468 -73.040055) (xy 31.399486 -73.126584) (xy 31.399486 -73.213484) (xy 34.599874 -73.213484)
			(xy 34.599874 -73.126584) (xy 34.607892 -73.040055) (xy 34.62386 -72.954635) (xy 34.647641 -72.871053)
			(xy 34.679033 -72.790021) (xy 34.717767 -72.712232) (xy 34.763514 -72.638348) (xy 34.815883 -72.569001)
			(xy 34.874427 -72.504781) (xy 34.938647 -72.446237) (xy 35.007994 -72.393868) (xy 35.081878 -72.348121)
			(xy 35.159667 -72.309387) (xy 35.240699 -72.277995) (xy 35.324281 -72.254214) (xy 35.409701 -72.238246)
			(xy 35.49623 -72.230228) (xy 35.53968 -72.229726) (xy 35.58313 -72.230228) (xy 35.669659 -72.238246)
			(xy 35.755079 -72.254214) (xy 35.838661 -72.277995) (xy 35.919693 -72.309387) (xy 35.997482 -72.348121)
			(xy 36.071366 -72.393868) (xy 36.140713 -72.446237) (xy 36.204933 -72.504781) (xy 36.263477 -72.569001)
			(xy 36.315846 -72.638348) (xy 36.361593 -72.712232) (xy 36.400327 -72.790021) (xy 36.431719 -72.871053)
			(xy 36.435295 -72.883623) (xy 41.522642 -72.883623) (xy 41.522642 -72.812301) (xy 41.530628 -72.741427)
			(xy 41.546498 -72.671892) (xy 41.570055 -72.604572) (xy 41.601 -72.540313) (xy 41.638946 -72.479922)
			(xy 41.683415 -72.42416) (xy 41.733848 -72.373727) (xy 41.78961 -72.329258) (xy 41.850001 -72.291312)
			(xy 41.91426 -72.260367) (xy 41.98158 -72.23681) (xy 42.051115 -72.22094) (xy 42.121989 -72.212954)
			(xy 42.15765 -72.212454) (xy 42.193311 -72.212954) (xy 42.264185 -72.22094) (xy 42.33372 -72.23681)
			(xy 42.40104 -72.260367) (xy 42.465299 -72.291312) (xy 42.52569 -72.329258) (xy 42.581452 -72.373727)
			(xy 42.631885 -72.42416) (xy 42.676354 -72.479922) (xy 42.7143 -72.540313) (xy 42.745245 -72.604572)
			(xy 42.768802 -72.671892) (xy 42.784672 -72.741427) (xy 42.792658 -72.812301) (xy 42.792658 -72.883623)
			(xy 42.784672 -72.954497) (xy 42.768802 -73.024032) (xy 42.745245 -73.091352) (xy 42.7143 -73.155611)
			(xy 42.676354 -73.216002) (xy 42.631885 -73.271764) (xy 42.581452 -73.322197) (xy 42.52569 -73.366666)
			(xy 42.465299 -73.404612) (xy 42.40104 -73.435557) (xy 42.33372 -73.459114) (xy 42.264185 -73.474984)
			(xy 42.193311 -73.48297) (xy 42.121989 -73.48297) (xy 42.051115 -73.474984) (xy 41.98158 -73.459114)
			(xy 41.91426 -73.435557) (xy 41.850001 -73.404612) (xy 41.78961 -73.366666) (xy 41.733848 -73.322197)
			(xy 41.683415 -73.271764) (xy 41.638946 -73.216002) (xy 41.601 -73.155611) (xy 41.570055 -73.091352)
			(xy 41.546498 -73.024032) (xy 41.530628 -72.954497) (xy 41.522642 -72.883623) (xy 36.435295 -72.883623)
			(xy 36.4555 -72.954635) (xy 36.471468 -73.040055) (xy 36.479486 -73.126584) (xy 36.479486 -73.213484)
			(xy 36.471468 -73.300013) (xy 36.4555 -73.385433) (xy 36.431719 -73.469015) (xy 36.400327 -73.550047)
			(xy 36.361593 -73.627836) (xy 36.315846 -73.70172) (xy 36.263477 -73.771067) (xy 36.204933 -73.835287)
			(xy 36.140713 -73.893831) (xy 36.071366 -73.9462) (xy 35.997482 -73.991947) (xy 35.919693 -74.030681)
			(xy 35.838661 -74.062073) (xy 35.755079 -74.085854) (xy 35.669659 -74.101822) (xy 35.58313 -74.10984)
			(xy 35.49623 -74.10984) (xy 35.409701 -74.101822) (xy 35.324281 -74.085854) (xy 35.240699 -74.062073)
			(xy 35.159667 -74.030681) (xy 35.081878 -73.991947) (xy 35.007994 -73.9462) (xy 34.938647 -73.893831)
			(xy 34.874427 -73.835287) (xy 34.815883 -73.771067) (xy 34.763514 -73.70172) (xy 34.717767 -73.627836)
			(xy 34.679033 -73.550047) (xy 34.647641 -73.469015) (xy 34.62386 -73.385433) (xy 34.607892 -73.300013)
			(xy 34.599874 -73.213484) (xy 31.399486 -73.213484) (xy 31.391468 -73.300013) (xy 31.3755 -73.385433)
			(xy 31.351719 -73.469015) (xy 31.320327 -73.550047) (xy 31.281593 -73.627836) (xy 31.235846 -73.70172)
			(xy 31.183477 -73.771067) (xy 31.124933 -73.835287) (xy 31.060713 -73.893831) (xy 30.991366 -73.9462)
			(xy 30.917482 -73.991947) (xy 30.839693 -74.030681) (xy 30.758661 -74.062073) (xy 30.675079 -74.085854)
			(xy 30.589659 -74.101822) (xy 30.50313 -74.10984) (xy 30.41623 -74.10984) (xy 30.329701 -74.101822)
			(xy 30.244281 -74.085854) (xy 30.160699 -74.062073) (xy 30.079667 -74.030681) (xy 30.001878 -73.991947)
			(xy 29.927994 -73.9462) (xy 29.858647 -73.893831) (xy 29.794427 -73.835287) (xy 29.735883 -73.771067)
			(xy 29.683514 -73.70172) (xy 29.637767 -73.627836) (xy 29.599033 -73.550047) (xy 29.567641 -73.469015)
			(xy 29.54386 -73.385433) (xy 29.527892 -73.300013) (xy 29.519874 -73.213484) (xy 28.154884 -73.213484)
			(xy 28.154884 -75.753484) (xy 29.519874 -75.753484) (xy 29.519874 -75.666584) (xy 29.527892 -75.580055)
			(xy 29.54386 -75.494635) (xy 29.567641 -75.411053) (xy 29.599033 -75.330021) (xy 29.637767 -75.252232)
			(xy 29.683514 -75.178348) (xy 29.735883 -75.109001) (xy 29.794427 -75.044781) (xy 29.858647 -74.986237)
			(xy 29.927994 -74.933868) (xy 30.001878 -74.888121) (xy 30.079667 -74.849387) (xy 30.160699 -74.817995)
			(xy 30.244281 -74.794214) (xy 30.329701 -74.778246) (xy 30.41623 -74.770228) (xy 30.45968 -74.769726)
			(xy 30.50313 -74.770228) (xy 30.589659 -74.778246) (xy 30.675079 -74.794214) (xy 30.758661 -74.817995)
			(xy 30.839693 -74.849387) (xy 30.917482 -74.888121) (xy 30.991366 -74.933868) (xy 31.060713 -74.986237)
			(xy 31.124933 -75.044781) (xy 31.183477 -75.109001) (xy 31.235846 -75.178348) (xy 31.281593 -75.252232)
			(xy 31.320327 -75.330021) (xy 31.351719 -75.411053) (xy 31.3755 -75.494635) (xy 31.391468 -75.580055)
			(xy 31.399486 -75.666584) (xy 31.399486 -75.753484) (xy 34.599874 -75.753484) (xy 34.599874 -75.666584)
			(xy 34.607892 -75.580055) (xy 34.62386 -75.494635) (xy 34.647641 -75.411053) (xy 34.679033 -75.330021)
			(xy 34.717767 -75.252232) (xy 34.763514 -75.178348) (xy 34.815883 -75.109001) (xy 34.874427 -75.044781)
			(xy 34.938647 -74.986237) (xy 35.007994 -74.933868) (xy 35.081878 -74.888121) (xy 35.159667 -74.849387)
			(xy 35.240699 -74.817995) (xy 35.324281 -74.794214) (xy 35.409701 -74.778246) (xy 35.49623 -74.770228)
			(xy 35.53968 -74.769726) (xy 35.58313 -74.770228) (xy 35.669659 -74.778246) (xy 35.755079 -74.794214)
			(xy 35.838661 -74.817995) (xy 35.919693 -74.849387) (xy 35.997482 -74.888121) (xy 36.071366 -74.933868)
			(xy 36.140713 -74.986237) (xy 36.204933 -75.044781) (xy 36.263477 -75.109001) (xy 36.315846 -75.178348)
			(xy 36.361593 -75.252232) (xy 36.363081 -75.255221) (xy 41.522642 -75.255221) (xy 41.522642 -75.183899)
			(xy 41.530628 -75.113025) (xy 41.546498 -75.04349) (xy 41.570055 -74.97617) (xy 41.601 -74.911911)
			(xy 41.638946 -74.85152) (xy 41.683415 -74.795758) (xy 41.733848 -74.745325) (xy 41.78961 -74.700856)
			(xy 41.850001 -74.66291) (xy 41.91426 -74.631965) (xy 41.98158 -74.608408) (xy 42.051115 -74.592538)
			(xy 42.121989 -74.584552) (xy 42.15765 -74.584052) (xy 42.193311 -74.584552) (xy 42.264185 -74.592538)
			(xy 42.33372 -74.608408) (xy 42.40104 -74.631965) (xy 42.465299 -74.66291) (xy 42.52569 -74.700856)
			(xy 42.581452 -74.745325) (xy 42.631885 -74.795758) (xy 42.676354 -74.85152) (xy 42.7143 -74.911911)
			(xy 42.745245 -74.97617) (xy 42.768802 -75.04349) (xy 42.784672 -75.113025) (xy 42.792658 -75.183899)
			(xy 42.792658 -75.255221) (xy 42.784672 -75.326095) (xy 42.768802 -75.39563) (xy 42.745245 -75.46295)
			(xy 42.7143 -75.527209) (xy 42.676354 -75.5876) (xy 42.631885 -75.643362) (xy 42.581452 -75.693795)
			(xy 42.52569 -75.738264) (xy 42.465299 -75.77621) (xy 42.40104 -75.807155) (xy 42.33372 -75.830712)
			(xy 42.264185 -75.846582) (xy 42.193311 -75.854568) (xy 42.121989 -75.854568) (xy 42.051115 -75.846582)
			(xy 41.98158 -75.830712) (xy 41.91426 -75.807155) (xy 41.850001 -75.77621) (xy 41.78961 -75.738264)
			(xy 41.733848 -75.693795) (xy 41.683415 -75.643362) (xy 41.638946 -75.5876) (xy 41.601 -75.527209)
			(xy 41.570055 -75.46295) (xy 41.546498 -75.39563) (xy 41.530628 -75.326095) (xy 41.522642 -75.255221)
			(xy 36.363081 -75.255221) (xy 36.400327 -75.330021) (xy 36.431719 -75.411053) (xy 36.4555 -75.494635)
			(xy 36.471468 -75.580055) (xy 36.479486 -75.666584) (xy 36.479486 -75.753484) (xy 36.471468 -75.840013)
			(xy 36.4555 -75.925433) (xy 36.431719 -76.009015) (xy 36.400327 -76.090047) (xy 36.361593 -76.167836)
			(xy 36.315846 -76.24172) (xy 36.263477 -76.311067) (xy 36.204933 -76.375287) (xy 36.140713 -76.433831)
			(xy 36.071366 -76.4862) (xy 35.997482 -76.531947) (xy 35.919693 -76.570681) (xy 35.838661 -76.602073)
			(xy 35.755079 -76.625854) (xy 35.669659 -76.641822) (xy 35.58313 -76.64984) (xy 35.49623 -76.64984)
			(xy 35.409701 -76.641822) (xy 35.324281 -76.625854) (xy 35.240699 -76.602073) (xy 35.159667 -76.570681)
			(xy 35.081878 -76.531947) (xy 35.007994 -76.4862) (xy 34.938647 -76.433831) (xy 34.874427 -76.375287)
			(xy 34.815883 -76.311067) (xy 34.763514 -76.24172) (xy 34.717767 -76.167836) (xy 34.679033 -76.090047)
			(xy 34.647641 -76.009015) (xy 34.62386 -75.925433) (xy 34.607892 -75.840013) (xy 34.599874 -75.753484)
			(xy 31.399486 -75.753484) (xy 31.391468 -75.840013) (xy 31.3755 -75.925433) (xy 31.351719 -76.009015)
			(xy 31.320327 -76.090047) (xy 31.281593 -76.167836) (xy 31.235846 -76.24172) (xy 31.183477 -76.311067)
			(xy 31.124933 -76.375287) (xy 31.060713 -76.433831) (xy 30.991366 -76.4862) (xy 30.917482 -76.531947)
			(xy 30.839693 -76.570681) (xy 30.758661 -76.602073) (xy 30.675079 -76.625854) (xy 30.589659 -76.641822)
			(xy 30.50313 -76.64984) (xy 30.41623 -76.64984) (xy 30.329701 -76.641822) (xy 30.244281 -76.625854)
			(xy 30.160699 -76.602073) (xy 30.079667 -76.570681) (xy 30.001878 -76.531947) (xy 29.927994 -76.4862)
			(xy 29.858647 -76.433831) (xy 29.794427 -76.375287) (xy 29.735883 -76.311067) (xy 29.683514 -76.24172)
			(xy 29.637767 -76.167836) (xy 29.599033 -76.090047) (xy 29.567641 -76.009015) (xy 29.54386 -75.925433)
			(xy 29.527892 -75.840013) (xy 29.519874 -75.753484) (xy 28.154884 -75.753484) (xy 28.154884 -77.218133)
			(xy 41.522642 -77.218133) (xy 41.522642 -77.146811) (xy 41.530628 -77.075937) (xy 41.546498 -77.006402)
			(xy 41.570055 -76.939082) (xy 41.601 -76.874823) (xy 41.638946 -76.814432) (xy 41.683415 -76.75867)
			(xy 41.733848 -76.708237) (xy 41.78961 -76.663768) (xy 41.850001 -76.625822) (xy 41.91426 -76.594877)
			(xy 41.98158 -76.57132) (xy 42.051115 -76.55545) (xy 42.121989 -76.547464) (xy 42.15765 -76.546964)
			(xy 42.193311 -76.547464) (xy 42.264185 -76.55545) (xy 42.33372 -76.57132) (xy 42.40104 -76.594877)
			(xy 42.465299 -76.625822) (xy 42.52569 -76.663768) (xy 42.581452 -76.708237) (xy 42.631885 -76.75867)
			(xy 42.676354 -76.814432) (xy 42.7143 -76.874823) (xy 42.745245 -76.939082) (xy 42.768802 -77.006402)
			(xy 42.784672 -77.075937) (xy 42.792658 -77.146811) (xy 42.792658 -77.218133) (xy 42.784672 -77.289007)
			(xy 42.768802 -77.358542) (xy 42.745245 -77.425862) (xy 42.7143 -77.490121) (xy 42.676354 -77.550512)
			(xy 42.631885 -77.606274) (xy 42.581452 -77.656707) (xy 42.52569 -77.701176) (xy 42.465299 -77.739122)
			(xy 42.40104 -77.770067) (xy 42.33372 -77.793624) (xy 42.264185 -77.809494) (xy 42.193311 -77.81748)
			(xy 42.121989 -77.81748) (xy 42.051115 -77.809494) (xy 41.98158 -77.793624) (xy 41.91426 -77.770067)
			(xy 41.850001 -77.739122) (xy 41.78961 -77.701176) (xy 41.733848 -77.656707) (xy 41.683415 -77.606274)
			(xy 41.638946 -77.550512) (xy 41.601 -77.490121) (xy 41.570055 -77.425862) (xy 41.546498 -77.358542)
			(xy 41.530628 -77.289007) (xy 41.522642 -77.218133) (xy 28.154884 -77.218133) (xy 28.154884 -78.293484)
			(xy 29.519874 -78.293484) (xy 29.519874 -78.206584) (xy 29.527892 -78.120055) (xy 29.54386 -78.034635)
			(xy 29.567641 -77.951053) (xy 29.599033 -77.870021) (xy 29.637767 -77.792232) (xy 29.683514 -77.718348)
			(xy 29.735883 -77.649001) (xy 29.794427 -77.584781) (xy 29.858647 -77.526237) (xy 29.927994 -77.473868)
			(xy 30.001878 -77.428121) (xy 30.079667 -77.389387) (xy 30.160699 -77.357995) (xy 30.244281 -77.334214)
			(xy 30.329701 -77.318246) (xy 30.41623 -77.310228) (xy 30.45968 -77.309726) (xy 30.50313 -77.310228)
			(xy 30.589659 -77.318246) (xy 30.675079 -77.334214) (xy 30.758661 -77.357995) (xy 30.839693 -77.389387)
			(xy 30.917482 -77.428121) (xy 30.991366 -77.473868) (xy 31.060713 -77.526237) (xy 31.124933 -77.584781)
			(xy 31.183477 -77.649001) (xy 31.235846 -77.718348) (xy 31.281593 -77.792232) (xy 31.320327 -77.870021)
			(xy 31.351719 -77.951053) (xy 31.3755 -78.034635) (xy 31.391468 -78.120055) (xy 31.399486 -78.206584)
			(xy 31.399486 -78.293484) (xy 34.599874 -78.293484) (xy 34.599874 -78.206584) (xy 34.607892 -78.120055)
			(xy 34.62386 -78.034635) (xy 34.647641 -77.951053) (xy 34.679033 -77.870021) (xy 34.717767 -77.792232)
			(xy 34.763514 -77.718348) (xy 34.815883 -77.649001) (xy 34.874427 -77.584781) (xy 34.938647 -77.526237)
			(xy 35.007994 -77.473868) (xy 35.081878 -77.428121) (xy 35.159667 -77.389387) (xy 35.240699 -77.357995)
			(xy 35.324281 -77.334214) (xy 35.409701 -77.318246) (xy 35.49623 -77.310228) (xy 35.53968 -77.309726)
			(xy 35.58313 -77.310228) (xy 35.669659 -77.318246) (xy 35.755079 -77.334214) (xy 35.838661 -77.357995)
			(xy 35.919693 -77.389387) (xy 35.997482 -77.428121) (xy 36.071366 -77.473868) (xy 36.140713 -77.526237)
			(xy 36.204933 -77.584781) (xy 36.263477 -77.649001) (xy 36.315846 -77.718348) (xy 36.361593 -77.792232)
			(xy 36.400327 -77.870021) (xy 36.431719 -77.951053) (xy 36.4555 -78.034635) (xy 36.471468 -78.120055)
			(xy 36.479486 -78.206584) (xy 36.479486 -78.293484) (xy 36.474911 -78.342857) (xy 74.399146 -78.342857)
			(xy 74.401143 -78.172756) (xy 74.41117 -78.00294) (xy 74.429207 -77.833786) (xy 74.455211 -77.665673)
			(xy 74.489125 -77.498976) (xy 74.530873 -77.334066) (xy 74.580363 -77.171312) (xy 74.637483 -77.011076)
			(xy 74.702107 -76.853716) (xy 74.77409 -76.699584) (xy 74.853271 -76.549024) (xy 74.939474 -76.40237)
			(xy 75.032507 -76.259951) (xy 75.132161 -76.122085) (xy 75.238215 -75.989078) (xy 75.350432 -75.861228)
			(xy 75.468561 -75.73882) (xy 75.59234 -75.622127) (xy 75.72149 -75.51141) (xy 75.855725 -75.406916)
			(xy 75.994746 -75.308877) (xy 76.13824 -75.217512) (xy 76.28589 -75.133026) (xy 76.437364 -75.055607)
			(xy 76.592326 -74.985428) (xy 76.750428 -74.922645) (xy 76.91132 -74.867398) (xy 77.074641 -74.819811)
			(xy 77.240026 -74.77999) (xy 77.407108 -74.748023) (xy 77.575513 -74.723982) (xy 77.744866 -74.707922)
			(xy 77.914788 -74.699876) (xy 77.999844 -74.699368) (xy 78.0849 -74.699864) (xy 78.254823 -74.707886)
			(xy 78.424178 -74.723923) (xy 78.592587 -74.747939) (xy 78.759673 -74.779882) (xy 78.925064 -74.81968)
			(xy 79.088392 -74.867244) (xy 79.249291 -74.922469) (xy 79.407403 -74.985229) (xy 79.562374 -75.055387)
			(xy 79.713859 -75.132785) (xy 79.861521 -75.21725) (xy 80.005028 -75.308594) (xy 80.144062 -75.406613)
			(xy 80.278312 -75.511089) (xy 80.407479 -75.621788) (xy 80.531273 -75.738463) (xy 80.64942 -75.860854)
			(xy 80.761654 -75.988688) (xy 80.867727 -76.12168) (xy 80.967401 -76.259533) (xy 81.060454 -76.401938)
			(xy 81.146678 -76.54858) (xy 81.22588 -76.699129) (xy 81.297885 -76.853251) (xy 81.362531 -77.010601)
			(xy 81.419674 -77.170829) (xy 81.469186 -77.333576) (xy 81.510958 -77.498481) (xy 81.544896 -77.665173)
			(xy 81.570924 -77.833283) (xy 81.588984 -78.002434) (xy 81.599035 -78.172249) (xy 81.601056 -78.342349)
			(xy 81.595042 -78.512355) (xy 81.581006 -78.681887) (xy 81.55898 -78.850568) (xy 81.529013 -79.01802)
			(xy 81.491171 -79.18387) (xy 81.464799 -79.278581) (xy 83.869014 -79.278581) (xy 83.869014 -79.207259)
			(xy 83.877 -79.136385) (xy 83.89287 -79.06685) (xy 83.916427 -78.99953) (xy 83.947372 -78.935271)
			(xy 83.985318 -78.87488) (xy 84.029787 -78.819118) (xy 84.08022 -78.768685) (xy 84.135982 -78.724216)
			(xy 84.196373 -78.68627) (xy 84.260632 -78.655325) (xy 84.327952 -78.631768) (xy 84.397487 -78.615898)
			(xy 84.468361 -78.607912) (xy 84.504022 -78.607412) (xy 84.539683 -78.607912) (xy 84.610557 -78.615898)
			(xy 84.680092 -78.631768) (xy 84.747412 -78.655325) (xy 84.811671 -78.68627) (xy 84.872062 -78.724216)
			(xy 84.927824 -78.768685) (xy 84.978257 -78.819118) (xy 85.022726 -78.87488) (xy 85.060672 -78.935271)
			(xy 85.091617 -78.99953) (xy 85.115174 -79.06685) (xy 85.131044 -79.136385) (xy 85.13903 -79.207259)
			(xy 85.13903 -79.278581) (xy 86.673428 -79.278581) (xy 86.673428 -79.207259) (xy 86.681414 -79.136385)
			(xy 86.697284 -79.06685) (xy 86.720841 -78.99953) (xy 86.751786 -78.935271) (xy 86.789732 -78.87488)
			(xy 86.834201 -78.819118) (xy 86.884634 -78.768685) (xy 86.940396 -78.724216) (xy 87.000787 -78.68627)
			(xy 87.065046 -78.655325) (xy 87.132366 -78.631768) (xy 87.201901 -78.615898) (xy 87.272775 -78.607912)
			(xy 87.308436 -78.607412) (xy 87.344097 -78.607912) (xy 87.414971 -78.615898) (xy 87.484506 -78.631768)
			(xy 87.551826 -78.655325) (xy 87.616085 -78.68627) (xy 87.676476 -78.724216) (xy 87.732238 -78.768685)
			(xy 87.782671 -78.819118) (xy 87.82714 -78.87488) (xy 87.865086 -78.935271) (xy 87.896031 -78.99953)
			(xy 87.919588 -79.06685) (xy 87.935458 -79.136385) (xy 87.943444 -79.207259) (xy 87.943444 -79.278581)
			(xy 87.935458 -79.349455) (xy 87.919588 -79.41899) (xy 87.896031 -79.48631) (xy 87.865086 -79.550569)
			(xy 87.82714 -79.61096) (xy 87.782671 -79.666722) (xy 87.732238 -79.717155) (xy 87.676476 -79.761624)
			(xy 87.616085 -79.79957) (xy 87.551826 -79.830515) (xy 87.484506 -79.854072) (xy 87.414971 -79.869942)
			(xy 87.344097 -79.877928) (xy 87.272775 -79.877928) (xy 87.201901 -79.869942) (xy 87.132366 -79.854072)
			(xy 87.065046 -79.830515) (xy 87.000787 -79.79957) (xy 86.940396 -79.761624) (xy 86.884634 -79.717155)
			(xy 86.834201 -79.666722) (xy 86.789732 -79.61096) (xy 86.751786 -79.550569) (xy 86.720841 -79.48631)
			(xy 86.697284 -79.41899) (xy 86.681414 -79.349455) (xy 86.673428 -79.278581) (xy 85.13903 -79.278581)
			(xy 85.131044 -79.349455) (xy 85.115174 -79.41899) (xy 85.091617 -79.48631) (xy 85.060672 -79.550569)
			(xy 85.022726 -79.61096) (xy 84.978257 -79.666722) (xy 84.927824 -79.717155) (xy 84.872062 -79.761624)
			(xy 84.811671 -79.79957) (xy 84.747412 -79.830515) (xy 84.680092 -79.854072) (xy 84.610557 -79.869942)
			(xy 84.539683 -79.877928) (xy 84.468361 -79.877928) (xy 84.397487 -79.869942) (xy 84.327952 -79.854072)
			(xy 84.260632 -79.830515) (xy 84.196373 -79.79957) (xy 84.135982 -79.761624) (xy 84.08022 -79.717155)
			(xy 84.029787 -79.666722) (xy 83.985318 -79.61096) (xy 83.947372 -79.550569) (xy 83.916427 -79.48631)
			(xy 83.89287 -79.41899) (xy 83.877 -79.349455) (xy 83.869014 -79.278581) (xy 81.464799 -79.278581)
			(xy 81.445539 -79.347748) (xy 81.392219 -79.509288) (xy 81.33133 -79.668129) (xy 81.263008 -79.823919)
			(xy 81.187405 -79.976308) (xy 81.104689 -80.124956) (xy 81.015046 -80.269533) (xy 80.918676 -80.409714)
			(xy 80.815793 -80.545189) (xy 80.706627 -80.675654) (xy 80.591422 -80.800817) (xy 80.470435 -80.920401)
			(xy 80.416719 -80.968697) (xy 83.889842 -80.968697) (xy 83.889842 -80.897375) (xy 83.897828 -80.826501)
			(xy 83.913698 -80.756966) (xy 83.937255 -80.689646) (xy 83.9682 -80.625387) (xy 84.006146 -80.564996)
			(xy 84.050615 -80.509234) (xy 84.101048 -80.458801) (xy 84.15681 -80.414332) (xy 84.217201 -80.376386)
			(xy 84.28146 -80.345441) (xy 84.34878 -80.321884) (xy 84.418315 -80.306014) (xy 84.489189 -80.298028)
			(xy 84.52485 -80.297528) (xy 84.560511 -80.298028) (xy 84.631385 -80.306014) (xy 84.70092 -80.321884)
			(xy 84.76824 -80.345441) (xy 84.832499 -80.376386) (xy 84.89289 -80.414332) (xy 84.948652 -80.458801)
			(xy 84.999085 -80.509234) (xy 85.043554 -80.564996) (xy 85.0815 -80.625387) (xy 85.112445 -80.689646)
			(xy 85.136002 -80.756966) (xy 85.151872 -80.826501) (xy 85.159858 -80.897375) (xy 85.159858 -80.968697)
			(xy 86.694256 -80.968697) (xy 86.694256 -80.897375) (xy 86.702242 -80.826501) (xy 86.718112 -80.756966)
			(xy 86.741669 -80.689646) (xy 86.772614 -80.625387) (xy 86.81056 -80.564996) (xy 86.855029 -80.509234)
			(xy 86.905462 -80.458801) (xy 86.961224 -80.414332) (xy 87.021615 -80.376386) (xy 87.085874 -80.345441)
			(xy 87.153194 -80.321884) (xy 87.222729 -80.306014) (xy 87.293603 -80.298028) (xy 87.329264 -80.297528)
			(xy 87.364925 -80.298028) (xy 87.435799 -80.306014) (xy 87.505334 -80.321884) (xy 87.572654 -80.345441)
			(xy 87.636913 -80.376386) (xy 87.697304 -80.414332) (xy 87.753066 -80.458801) (xy 87.803499 -80.509234)
			(xy 87.847968 -80.564996) (xy 87.885914 -80.625387) (xy 87.916859 -80.689646) (xy 87.940416 -80.756966)
			(xy 87.956286 -80.826501) (xy 87.964272 -80.897375) (xy 87.964272 -80.968697) (xy 87.956286 -81.039571)
			(xy 87.940416 -81.109106) (xy 87.916859 -81.176426) (xy 87.885914 -81.240685) (xy 87.847968 -81.301076)
			(xy 87.803499 -81.356838) (xy 87.753066 -81.407271) (xy 87.697304 -81.45174) (xy 87.636913 -81.489686)
			(xy 87.572654 -81.520631) (xy 87.505334 -81.544188) (xy 87.435799 -81.560058) (xy 87.364925 -81.568044)
			(xy 87.293603 -81.568044) (xy 87.222729 -81.560058) (xy 87.153194 -81.544188) (xy 87.085874 -81.520631)
			(xy 87.021615 -81.489686) (xy 86.961224 -81.45174) (xy 86.905462 -81.407271) (xy 86.855029 -81.356838)
			(xy 86.81056 -81.301076) (xy 86.772614 -81.240685) (xy 86.741669 -81.176426) (xy 86.718112 -81.109106)
			(xy 86.702242 -81.039571) (xy 86.694256 -80.968697) (xy 85.159858 -80.968697) (xy 85.151872 -81.039571)
			(xy 85.136002 -81.109106) (xy 85.112445 -81.176426) (xy 85.0815 -81.240685) (xy 85.043554 -81.301076)
			(xy 84.999085 -81.356838) (xy 84.948652 -81.407271) (xy 84.89289 -81.45174) (xy 84.832499 -81.489686)
			(xy 84.76824 -81.520631) (xy 84.70092 -81.544188) (xy 84.631385 -81.560058) (xy 84.560511 -81.568044)
			(xy 84.489189 -81.568044) (xy 84.418315 -81.560058) (xy 84.34878 -81.544188) (xy 84.28146 -81.520631)
			(xy 84.217201 -81.489686) (xy 84.15681 -81.45174) (xy 84.101048 -81.407271) (xy 84.050615 -81.356838)
			(xy 84.006146 -81.301076) (xy 83.9682 -81.240685) (xy 83.937255 -81.176426) (xy 83.913698 -81.109106)
			(xy 83.897828 -81.039571) (xy 83.889842 -80.968697) (xy 80.416719 -80.968697) (xy 80.343935 -81.034138)
			(xy 80.212205 -81.141774) (xy 80.07554 -81.243069) (xy 79.934243 -81.337797) (xy 79.78863 -81.425747)
			(xy 79.639026 -81.506722) (xy 79.485766 -81.580542) (xy 79.32919 -81.647041) (xy 79.169648 -81.706073)
			(xy 79.007497 -81.757504) (xy 78.843098 -81.80122) (xy 78.676817 -81.837124) (xy 78.509027 -81.865136)
			(xy 78.340101 -81.885192) (xy 78.170417 -81.897249) (xy 78.000352 -81.901278) (xy 77.830287 -81.897273)
			(xy 77.660601 -81.88524) (xy 77.491672 -81.865208) (xy 77.323878 -81.83722) (xy 77.157592 -81.801339)
			(xy 76.993187 -81.757646) (xy 76.831028 -81.706238) (xy 76.671479 -81.647229) (xy 76.514893 -81.580751)
			(xy 76.361622 -81.506953) (xy 76.212007 -81.425999) (xy 76.066382 -81.33807) (xy 75.925072 -81.243362)
			(xy 75.788392 -81.142086) (xy 75.656647 -81.034469) (xy 75.530131 -80.92075) (xy 75.409127 -80.801183)
			(xy 75.293904 -80.676035) (xy 75.18472 -80.545586) (xy 75.081818 -80.410126) (xy 74.985428 -80.269958)
			(xy 74.895764 -80.125394) (xy 74.813028 -79.976757) (xy 74.737403 -79.824379) (xy 74.669059 -79.668599)
			(xy 74.608147 -79.509766) (xy 74.554805 -79.348234) (xy 74.50915 -79.184362) (xy 74.471285 -79.018518)
			(xy 74.441293 -78.85107) (xy 74.419243 -78.682393) (xy 74.405184 -78.512862) (xy 74.399146 -78.342857)
			(xy 36.474911 -78.342857) (xy 36.471468 -78.380013) (xy 36.4555 -78.465433) (xy 36.431719 -78.549015)
			(xy 36.400327 -78.630047) (xy 36.361593 -78.707836) (xy 36.315846 -78.78172) (xy 36.263477 -78.851067)
			(xy 36.204933 -78.915287) (xy 36.140713 -78.973831) (xy 36.071366 -79.0262) (xy 35.997482 -79.071947)
			(xy 35.919693 -79.110681) (xy 35.838661 -79.142073) (xy 35.755079 -79.165854) (xy 35.669659 -79.181822)
			(xy 35.58313 -79.18984) (xy 35.49623 -79.18984) (xy 35.409701 -79.181822) (xy 35.324281 -79.165854)
			(xy 35.240699 -79.142073) (xy 35.159667 -79.110681) (xy 35.081878 -79.071947) (xy 35.007994 -79.0262)
			(xy 34.938647 -78.973831) (xy 34.874427 -78.915287) (xy 34.815883 -78.851067) (xy 34.763514 -78.78172)
			(xy 34.717767 -78.707836) (xy 34.679033 -78.630047) (xy 34.647641 -78.549015) (xy 34.62386 -78.465433)
			(xy 34.607892 -78.380013) (xy 34.599874 -78.293484) (xy 31.399486 -78.293484) (xy 31.391468 -78.380013)
			(xy 31.3755 -78.465433) (xy 31.351719 -78.549015) (xy 31.320327 -78.630047) (xy 31.281593 -78.707836)
			(xy 31.235846 -78.78172) (xy 31.183477 -78.851067) (xy 31.124933 -78.915287) (xy 31.060713 -78.973831)
			(xy 30.991366 -79.0262) (xy 30.917482 -79.071947) (xy 30.839693 -79.110681) (xy 30.758661 -79.142073)
			(xy 30.675079 -79.165854) (xy 30.589659 -79.181822) (xy 30.50313 -79.18984) (xy 30.41623 -79.18984)
			(xy 30.329701 -79.181822) (xy 30.244281 -79.165854) (xy 30.160699 -79.142073) (xy 30.079667 -79.110681)
			(xy 30.001878 -79.071947) (xy 29.927994 -79.0262) (xy 29.858647 -78.973831) (xy 29.794427 -78.915287)
			(xy 29.735883 -78.851067) (xy 29.683514 -78.78172) (xy 29.637767 -78.707836) (xy 29.599033 -78.630047)
			(xy 29.567641 -78.549015) (xy 29.54386 -78.465433) (xy 29.527892 -78.380013) (xy 29.519874 -78.293484)
			(xy 28.154884 -78.293484) (xy 28.154884 -79.361639) (xy 41.522642 -79.361639) (xy 41.522642 -79.290317)
			(xy 41.530628 -79.219443) (xy 41.546498 -79.149908) (xy 41.570055 -79.082588) (xy 41.601 -79.018329)
			(xy 41.638946 -78.957938) (xy 41.683415 -78.902176) (xy 41.733848 -78.851743) (xy 41.78961 -78.807274)
			(xy 41.850001 -78.769328) (xy 41.91426 -78.738383) (xy 41.98158 -78.714826) (xy 42.051115 -78.698956)
			(xy 42.121989 -78.69097) (xy 42.15765 -78.69047) (xy 42.193311 -78.69097) (xy 42.264185 -78.698956)
			(xy 42.33372 -78.714826) (xy 42.40104 -78.738383) (xy 42.465299 -78.769328) (xy 42.52569 -78.807274)
			(xy 42.581452 -78.851743) (xy 42.631885 -78.902176) (xy 42.676354 -78.957938) (xy 42.7143 -79.018329)
			(xy 42.745245 -79.082588) (xy 42.768802 -79.149908) (xy 42.784672 -79.219443) (xy 42.792658 -79.290317)
			(xy 42.792658 -79.361639) (xy 42.784672 -79.432513) (xy 42.768802 -79.502048) (xy 42.745245 -79.569368)
			(xy 42.7143 -79.633627) (xy 42.676354 -79.694018) (xy 42.631885 -79.74978) (xy 42.581452 -79.800213)
			(xy 42.52569 -79.844682) (xy 42.465299 -79.882628) (xy 42.40104 -79.913573) (xy 42.33372 -79.93713)
			(xy 42.264185 -79.953) (xy 42.193311 -79.960986) (xy 42.121989 -79.960986) (xy 42.051115 -79.953)
			(xy 41.98158 -79.93713) (xy 41.91426 -79.913573) (xy 41.850001 -79.882628) (xy 41.78961 -79.844682)
			(xy 41.733848 -79.800213) (xy 41.683415 -79.74978) (xy 41.638946 -79.694018) (xy 41.601 -79.633627)
			(xy 41.570055 -79.569368) (xy 41.546498 -79.502048) (xy 41.530628 -79.432513) (xy 41.522642 -79.361639)
			(xy 28.154884 -79.361639) (xy 28.154884 -80.833484) (xy 29.519874 -80.833484) (xy 29.519874 -80.746584)
			(xy 29.527892 -80.660055) (xy 29.54386 -80.574635) (xy 29.567641 -80.491053) (xy 29.599033 -80.410021)
			(xy 29.637767 -80.332232) (xy 29.683514 -80.258348) (xy 29.735883 -80.189001) (xy 29.794427 -80.124781)
			(xy 29.858647 -80.066237) (xy 29.927994 -80.013868) (xy 30.001878 -79.968121) (xy 30.079667 -79.929387)
			(xy 30.160699 -79.897995) (xy 30.244281 -79.874214) (xy 30.329701 -79.858246) (xy 30.41623 -79.850228)
			(xy 30.45968 -79.849726) (xy 30.50313 -79.850228) (xy 30.589659 -79.858246) (xy 30.675079 -79.874214)
			(xy 30.758661 -79.897995) (xy 30.839693 -79.929387) (xy 30.917482 -79.968121) (xy 30.991366 -80.013868)
			(xy 31.060713 -80.066237) (xy 31.124933 -80.124781) (xy 31.183477 -80.189001) (xy 31.235846 -80.258348)
			(xy 31.281593 -80.332232) (xy 31.320327 -80.410021) (xy 31.351719 -80.491053) (xy 31.3755 -80.574635)
			(xy 31.391468 -80.660055) (xy 31.399486 -80.746584) (xy 31.399486 -80.833484) (xy 34.599874 -80.833484)
			(xy 34.599874 -80.746584) (xy 34.607892 -80.660055) (xy 34.62386 -80.574635) (xy 34.647641 -80.491053)
			(xy 34.679033 -80.410021) (xy 34.717767 -80.332232) (xy 34.763514 -80.258348) (xy 34.815883 -80.189001)
			(xy 34.874427 -80.124781) (xy 34.938647 -80.066237) (xy 35.007994 -80.013868) (xy 35.081878 -79.968121)
			(xy 35.159667 -79.929387) (xy 35.240699 -79.897995) (xy 35.324281 -79.874214) (xy 35.409701 -79.858246)
			(xy 35.49623 -79.850228) (xy 35.53968 -79.849726) (xy 35.58313 -79.850228) (xy 35.669659 -79.858246)
			(xy 35.755079 -79.874214) (xy 35.838661 -79.897995) (xy 35.919693 -79.929387) (xy 35.997482 -79.968121)
			(xy 36.071366 -80.013868) (xy 36.140713 -80.066237) (xy 36.204933 -80.124781) (xy 36.263477 -80.189001)
			(xy 36.315846 -80.258348) (xy 36.361593 -80.332232) (xy 36.400327 -80.410021) (xy 36.431719 -80.491053)
			(xy 36.4555 -80.574635) (xy 36.471468 -80.660055) (xy 36.479486 -80.746584) (xy 36.479486 -80.833484)
			(xy 36.471468 -80.920013) (xy 36.4555 -81.005433) (xy 36.431719 -81.089015) (xy 36.400327 -81.170047)
			(xy 36.361593 -81.247836) (xy 36.315846 -81.32172) (xy 36.263477 -81.391067) (xy 36.204933 -81.455287)
			(xy 36.140713 -81.513831) (xy 36.071366 -81.5662) (xy 35.997482 -81.611947) (xy 35.919693 -81.650681)
			(xy 35.838661 -81.682073) (xy 35.755079 -81.705854) (xy 35.669659 -81.721822) (xy 35.58313 -81.72984)
			(xy 35.49623 -81.72984) (xy 35.409701 -81.721822) (xy 35.324281 -81.705854) (xy 35.240699 -81.682073)
			(xy 35.159667 -81.650681) (xy 35.081878 -81.611947) (xy 35.007994 -81.5662) (xy 34.938647 -81.513831)
			(xy 34.874427 -81.455287) (xy 34.815883 -81.391067) (xy 34.763514 -81.32172) (xy 34.717767 -81.247836)
			(xy 34.679033 -81.170047) (xy 34.647641 -81.089015) (xy 34.62386 -81.005433) (xy 34.607892 -80.920013)
			(xy 34.599874 -80.833484) (xy 31.399486 -80.833484) (xy 31.391468 -80.920013) (xy 31.3755 -81.005433)
			(xy 31.351719 -81.089015) (xy 31.320327 -81.170047) (xy 31.281593 -81.247836) (xy 31.235846 -81.32172)
			(xy 31.183477 -81.391067) (xy 31.124933 -81.455287) (xy 31.060713 -81.513831) (xy 30.991366 -81.5662)
			(xy 30.917482 -81.611947) (xy 30.839693 -81.650681) (xy 30.758661 -81.682073) (xy 30.675079 -81.705854)
			(xy 30.589659 -81.721822) (xy 30.50313 -81.72984) (xy 30.41623 -81.72984) (xy 30.329701 -81.721822)
			(xy 30.244281 -81.705854) (xy 30.160699 -81.682073) (xy 30.079667 -81.650681) (xy 30.001878 -81.611947)
			(xy 29.927994 -81.5662) (xy 29.858647 -81.513831) (xy 29.794427 -81.455287) (xy 29.735883 -81.391067)
			(xy 29.683514 -81.32172) (xy 29.637767 -81.247836) (xy 29.599033 -81.170047) (xy 29.567641 -81.089015)
			(xy 29.54386 -81.005433) (xy 29.527892 -80.920013) (xy 29.519874 -80.833484) (xy 28.154884 -80.833484)
			(xy 28.154884 -83.082638) (xy 29.085794 -84.013802) (xy 29.102436 -84.029737) (xy 29.14035 -84.055908)
			(xy 29.182361 -84.074817) (xy 29.227092 -84.085843) (xy 29.273078 -84.088627) (xy 29.318812 -84.083075)
			(xy 29.362797 -84.069372) (xy 29.403591 -84.047964) (xy 29.439858 -84.019554) (xy 29.470411 -83.985072)
			(xy 29.494247 -83.945648) (xy 29.510587 -83.902574) (xy 29.518896 -83.857259) (xy 29.519372 -83.834224)
			(xy 29.519372 -82.38998) (xy 31.399988 -82.38998) (xy 31.399988 -83.373484) (xy 34.599874 -83.373484)
			(xy 34.599874 -83.286584) (xy 34.607892 -83.200055) (xy 34.62386 -83.114635) (xy 34.647641 -83.031053)
			(xy 34.679033 -82.950021) (xy 34.717767 -82.872232) (xy 34.763514 -82.798348) (xy 34.815883 -82.729001)
			(xy 34.874427 -82.664781) (xy 34.938647 -82.606237) (xy 35.007994 -82.553868) (xy 35.081878 -82.508121)
			(xy 35.159667 -82.469387) (xy 35.240699 -82.437995) (xy 35.324281 -82.414214) (xy 35.409701 -82.398246)
			(xy 35.49623 -82.390228) (xy 35.53968 -82.389726) (xy 35.58313 -82.390228) (xy 35.669659 -82.398246)
			(xy 35.755079 -82.414214) (xy 35.838661 -82.437995) (xy 35.919693 -82.469387) (xy 35.997482 -82.508121)
			(xy 36.071366 -82.553868) (xy 36.140713 -82.606237) (xy 36.204933 -82.664781) (xy 36.263477 -82.729001)
			(xy 36.315846 -82.798348) (xy 36.331203 -82.823151) (xy 83.889842 -82.823151) (xy 83.889842 -82.751829)
			(xy 83.897828 -82.680955) (xy 83.913698 -82.61142) (xy 83.937255 -82.5441) (xy 83.9682 -82.479841)
			(xy 84.006146 -82.41945) (xy 84.050615 -82.363688) (xy 84.101048 -82.313255) (xy 84.15681 -82.268786)
			(xy 84.217201 -82.23084) (xy 84.28146 -82.199895) (xy 84.34878 -82.176338) (xy 84.418315 -82.160468)
			(xy 84.489189 -82.152482) (xy 84.52485 -82.151982) (xy 84.560511 -82.152482) (xy 84.631385 -82.160468)
			(xy 84.70092 -82.176338) (xy 84.76824 -82.199895) (xy 84.832499 -82.23084) (xy 84.89289 -82.268786)
			(xy 84.948652 -82.313255) (xy 84.999085 -82.363688) (xy 85.043554 -82.41945) (xy 85.0815 -82.479841)
			(xy 85.112445 -82.5441) (xy 85.136002 -82.61142) (xy 85.151872 -82.680955) (xy 85.159858 -82.751829)
			(xy 85.159858 -82.823151) (xy 86.694256 -82.823151) (xy 86.694256 -82.751829) (xy 86.702242 -82.680955)
			(xy 86.718112 -82.61142) (xy 86.741669 -82.5441) (xy 86.772614 -82.479841) (xy 86.81056 -82.41945)
			(xy 86.855029 -82.363688) (xy 86.905462 -82.313255) (xy 86.961224 -82.268786) (xy 87.021615 -82.23084)
			(xy 87.085874 -82.199895) (xy 87.153194 -82.176338) (xy 87.222729 -82.160468) (xy 87.293603 -82.152482)
			(xy 87.329264 -82.151982) (xy 87.364925 -82.152482) (xy 87.435799 -82.160468) (xy 87.505334 -82.176338)
			(xy 87.572654 -82.199895) (xy 87.636913 -82.23084) (xy 87.697304 -82.268786) (xy 87.753066 -82.313255)
			(xy 87.803499 -82.363688) (xy 87.847968 -82.41945) (xy 87.885914 -82.479841) (xy 87.916859 -82.5441)
			(xy 87.940416 -82.61142) (xy 87.956286 -82.680955) (xy 87.964272 -82.751829) (xy 87.964272 -82.823151)
			(xy 87.956286 -82.894025) (xy 87.940416 -82.96356) (xy 87.916859 -83.03088) (xy 87.885914 -83.095139)
			(xy 87.847968 -83.15553) (xy 87.803499 -83.211292) (xy 87.753066 -83.261725) (xy 87.697304 -83.306194)
			(xy 87.636913 -83.34414) (xy 87.572654 -83.375085) (xy 87.505334 -83.398642) (xy 87.435799 -83.414512)
			(xy 87.364925 -83.422498) (xy 87.293603 -83.422498) (xy 87.222729 -83.414512) (xy 87.153194 -83.398642)
			(xy 87.085874 -83.375085) (xy 87.021615 -83.34414) (xy 86.961224 -83.306194) (xy 86.905462 -83.261725)
			(xy 86.855029 -83.211292) (xy 86.81056 -83.15553) (xy 86.772614 -83.095139) (xy 86.741669 -83.03088)
			(xy 86.718112 -82.96356) (xy 86.702242 -82.894025) (xy 86.694256 -82.823151) (xy 85.159858 -82.823151)
			(xy 85.151872 -82.894025) (xy 85.136002 -82.96356) (xy 85.112445 -83.03088) (xy 85.0815 -83.095139)
			(xy 85.043554 -83.15553) (xy 84.999085 -83.211292) (xy 84.948652 -83.261725) (xy 84.89289 -83.306194)
			(xy 84.832499 -83.34414) (xy 84.76824 -83.375085) (xy 84.70092 -83.398642) (xy 84.631385 -83.414512)
			(xy 84.560511 -83.422498) (xy 84.489189 -83.422498) (xy 84.418315 -83.414512) (xy 84.34878 -83.398642)
			(xy 84.28146 -83.375085) (xy 84.217201 -83.34414) (xy 84.15681 -83.306194) (xy 84.101048 -83.261725)
			(xy 84.050615 -83.211292) (xy 84.006146 -83.15553) (xy 83.9682 -83.095139) (xy 83.937255 -83.03088)
			(xy 83.913698 -82.96356) (xy 83.897828 -82.894025) (xy 83.889842 -82.823151) (xy 36.331203 -82.823151)
			(xy 36.361593 -82.872232) (xy 36.400327 -82.950021) (xy 36.431719 -83.031053) (xy 36.4555 -83.114635)
			(xy 36.471468 -83.200055) (xy 36.479486 -83.286584) (xy 36.479486 -83.373484) (xy 36.472615 -83.447636)
			(xy 51.141884 -83.447636) (xy 52.793392 -83.447636) (xy 52.793392 -85.099652) (xy 51.141884 -85.099652)
			(xy 51.141884 -83.447636) (xy 36.472615 -83.447636) (xy 36.471468 -83.460013) (xy 36.4555 -83.545433)
			(xy 36.431719 -83.629015) (xy 36.400327 -83.710047) (xy 36.361593 -83.787836) (xy 36.315846 -83.86172)
			(xy 36.263477 -83.931067) (xy 36.204933 -83.995287) (xy 36.140713 -84.053831) (xy 36.071366 -84.1062)
			(xy 35.997482 -84.151947) (xy 35.919693 -84.190681) (xy 35.838661 -84.222073) (xy 35.755079 -84.245854)
			(xy 35.669659 -84.261822) (xy 35.58313 -84.26984) (xy 35.49623 -84.26984) (xy 35.409701 -84.261822)
			(xy 35.324281 -84.245854) (xy 35.240699 -84.222073) (xy 35.159667 -84.190681) (xy 35.081878 -84.151947)
			(xy 35.007994 -84.1062) (xy 34.938647 -84.053831) (xy 34.874427 -83.995287) (xy 34.815883 -83.931067)
			(xy 34.763514 -83.86172) (xy 34.717767 -83.787836) (xy 34.679033 -83.710047) (xy 34.647641 -83.629015)
			(xy 34.62386 -83.545433) (xy 34.607892 -83.460013) (xy 34.599874 -83.373484) (xy 31.399988 -83.373484)
			(xy 31.399988 -84.270342) (xy 29.95549 -84.270342) (xy 29.932457 -84.270843) (xy 29.887147 -84.279149)
			(xy 29.844076 -84.295486) (xy 29.804655 -84.319319) (xy 29.770177 -84.349868) (xy 29.74177 -84.386131)
			(xy 29.720365 -84.426921) (xy 29.706663 -84.470902) (xy 29.701114 -84.516632) (xy 29.703898 -84.562613)
			(xy 29.714926 -84.607338) (xy 29.733835 -84.649344) (xy 29.760006 -84.687252) (xy 29.775912 -84.70392)
			(xy 30.266771 -85.194749) (xy 83.889842 -85.194749) (xy 83.889842 -85.123427) (xy 83.897828 -85.052553)
			(xy 83.913698 -84.983018) (xy 83.937255 -84.915698) (xy 83.9682 -84.851439) (xy 84.006146 -84.791048)
			(xy 84.050615 -84.735286) (xy 84.101048 -84.684853) (xy 84.15681 -84.640384) (xy 84.217201 -84.602438)
			(xy 84.28146 -84.571493) (xy 84.34878 -84.547936) (xy 84.418315 -84.532066) (xy 84.489189 -84.52408)
			(xy 84.52485 -84.52358) (xy 84.560511 -84.52408) (xy 84.631385 -84.532066) (xy 84.70092 -84.547936)
			(xy 84.76824 -84.571493) (xy 84.832499 -84.602438) (xy 84.89289 -84.640384) (xy 84.948652 -84.684853)
			(xy 84.999085 -84.735286) (xy 85.043554 -84.791048) (xy 85.0815 -84.851439) (xy 85.112445 -84.915698)
			(xy 85.136002 -84.983018) (xy 85.151872 -85.052553) (xy 85.159858 -85.123427) (xy 85.159858 -85.194749)
			(xy 86.694256 -85.194749) (xy 86.694256 -85.123427) (xy 86.702242 -85.052553) (xy 86.718112 -84.983018)
			(xy 86.741669 -84.915698) (xy 86.772614 -84.851439) (xy 86.81056 -84.791048) (xy 86.855029 -84.735286)
			(xy 86.905462 -84.684853) (xy 86.961224 -84.640384) (xy 87.021615 -84.602438) (xy 87.085874 -84.571493)
			(xy 87.153194 -84.547936) (xy 87.222729 -84.532066) (xy 87.293603 -84.52408) (xy 87.329264 -84.52358)
			(xy 87.364925 -84.52408) (xy 87.435799 -84.532066) (xy 87.505334 -84.547936) (xy 87.572654 -84.571493)
			(xy 87.636913 -84.602438) (xy 87.697304 -84.640384) (xy 87.753066 -84.684853) (xy 87.803499 -84.735286)
			(xy 87.847968 -84.791048) (xy 87.885914 -84.851439) (xy 87.916859 -84.915698) (xy 87.940416 -84.983018)
			(xy 87.956286 -85.052553) (xy 87.964272 -85.123427) (xy 87.964272 -85.194749) (xy 87.956286 -85.265623)
			(xy 87.940416 -85.335158) (xy 87.916859 -85.402478) (xy 87.885914 -85.466737) (xy 87.847968 -85.527128)
			(xy 87.803499 -85.58289) (xy 87.753066 -85.633323) (xy 87.697304 -85.677792) (xy 87.636913 -85.715738)
			(xy 87.572654 -85.746683) (xy 87.505334 -85.77024) (xy 87.435799 -85.78611) (xy 87.364925 -85.794096)
			(xy 87.293603 -85.794096) (xy 87.222729 -85.78611) (xy 87.153194 -85.77024) (xy 87.085874 -85.746683)
			(xy 87.021615 -85.715738) (xy 86.961224 -85.677792) (xy 86.905462 -85.633323) (xy 86.855029 -85.58289)
			(xy 86.81056 -85.527128) (xy 86.772614 -85.466737) (xy 86.741669 -85.402478) (xy 86.718112 -85.335158)
			(xy 86.702242 -85.265623) (xy 86.694256 -85.194749) (xy 85.159858 -85.194749) (xy 85.151872 -85.265623)
			(xy 85.136002 -85.335158) (xy 85.112445 -85.402478) (xy 85.0815 -85.466737) (xy 85.043554 -85.527128)
			(xy 84.999085 -85.58289) (xy 84.948652 -85.633323) (xy 84.89289 -85.677792) (xy 84.832499 -85.715738)
			(xy 84.76824 -85.746683) (xy 84.70092 -85.77024) (xy 84.631385 -85.78611) (xy 84.560511 -85.794096)
			(xy 84.489189 -85.794096) (xy 84.418315 -85.78611) (xy 84.34878 -85.77024) (xy 84.28146 -85.746683)
			(xy 84.217201 -85.715738) (xy 84.15681 -85.677792) (xy 84.101048 -85.633323) (xy 84.050615 -85.58289)
			(xy 84.006146 -85.527128) (xy 83.9682 -85.466737) (xy 83.937255 -85.402478) (xy 83.913698 -85.335158)
			(xy 83.897828 -85.265623) (xy 83.889842 -85.194749) (xy 30.266771 -85.194749) (xy 32.092888 -87.020755)
			(xy 83.889842 -87.020755) (xy 83.889842 -86.949433) (xy 83.897828 -86.878559) (xy 83.913698 -86.809024)
			(xy 83.937255 -86.741704) (xy 83.9682 -86.677445) (xy 84.006146 -86.617054) (xy 84.050615 -86.561292)
			(xy 84.101048 -86.510859) (xy 84.15681 -86.46639) (xy 84.217201 -86.428444) (xy 84.28146 -86.397499)
			(xy 84.34878 -86.373942) (xy 84.418315 -86.358072) (xy 84.489189 -86.350086) (xy 84.52485 -86.349586)
			(xy 84.560511 -86.350086) (xy 84.631385 -86.358072) (xy 84.70092 -86.373942) (xy 84.76824 -86.397499)
			(xy 84.832499 -86.428444) (xy 84.89289 -86.46639) (xy 84.948652 -86.510859) (xy 84.999085 -86.561292)
			(xy 85.043554 -86.617054) (xy 85.0815 -86.677445) (xy 85.112445 -86.741704) (xy 85.136002 -86.809024)
			(xy 85.151872 -86.878559) (xy 85.159858 -86.949433) (xy 85.159858 -87.020755) (xy 86.694256 -87.020755)
			(xy 86.694256 -86.949433) (xy 86.702242 -86.878559) (xy 86.718112 -86.809024) (xy 86.741669 -86.741704)
			(xy 86.772614 -86.677445) (xy 86.81056 -86.617054) (xy 86.855029 -86.561292) (xy 86.905462 -86.510859)
			(xy 86.961224 -86.46639) (xy 87.021615 -86.428444) (xy 87.085874 -86.397499) (xy 87.153194 -86.373942)
			(xy 87.222729 -86.358072) (xy 87.293603 -86.350086) (xy 87.329264 -86.349586) (xy 87.364925 -86.350086)
			(xy 87.435799 -86.358072) (xy 87.505334 -86.373942) (xy 87.572654 -86.397499) (xy 87.636913 -86.428444)
			(xy 87.697304 -86.46639) (xy 87.753066 -86.510859) (xy 87.803499 -86.561292) (xy 87.847968 -86.617054)
			(xy 87.885914 -86.677445) (xy 87.916859 -86.741704) (xy 87.940416 -86.809024) (xy 87.956286 -86.878559)
			(xy 87.964272 -86.949433) (xy 87.964272 -87.020755) (xy 87.956286 -87.091629) (xy 87.940416 -87.161164)
			(xy 87.916859 -87.228484) (xy 87.885914 -87.292743) (xy 87.847968 -87.353134) (xy 87.803499 -87.408896)
			(xy 87.753066 -87.459329) (xy 87.697304 -87.503798) (xy 87.636913 -87.541744) (xy 87.572654 -87.572689)
			(xy 87.505334 -87.596246) (xy 87.435799 -87.612116) (xy 87.364925 -87.620102) (xy 87.293603 -87.620102)
			(xy 87.222729 -87.612116) (xy 87.153194 -87.596246) (xy 87.085874 -87.572689) (xy 87.021615 -87.541744)
			(xy 86.961224 -87.503798) (xy 86.905462 -87.459329) (xy 86.855029 -87.408896) (xy 86.81056 -87.353134)
			(xy 86.772614 -87.292743) (xy 86.741669 -87.228484) (xy 86.718112 -87.161164) (xy 86.702242 -87.091629)
			(xy 86.694256 -87.020755) (xy 85.159858 -87.020755) (xy 85.151872 -87.091629) (xy 85.136002 -87.161164)
			(xy 85.112445 -87.228484) (xy 85.0815 -87.292743) (xy 85.043554 -87.353134) (xy 84.999085 -87.408896)
			(xy 84.948652 -87.459329) (xy 84.89289 -87.503798) (xy 84.832499 -87.541744) (xy 84.76824 -87.572689)
			(xy 84.70092 -87.596246) (xy 84.631385 -87.612116) (xy 84.560511 -87.620102) (xy 84.489189 -87.620102)
			(xy 84.418315 -87.612116) (xy 84.34878 -87.596246) (xy 84.28146 -87.572689) (xy 84.217201 -87.541744)
			(xy 84.15681 -87.503798) (xy 84.101048 -87.459329) (xy 84.050615 -87.408896) (xy 84.006146 -87.353134)
			(xy 83.9682 -87.292743) (xy 83.937255 -87.228484) (xy 83.913698 -87.161164) (xy 83.897828 -87.091629)
			(xy 83.889842 -87.020755) (xy 32.092888 -87.020755) (xy 33.666259 -88.594031) (xy 83.866982 -88.594031)
			(xy 83.866982 -88.522709) (xy 83.874968 -88.451835) (xy 83.890838 -88.3823) (xy 83.914395 -88.31498)
			(xy 83.94534 -88.250721) (xy 83.983286 -88.19033) (xy 84.027755 -88.134568) (xy 84.078188 -88.084135)
			(xy 84.13395 -88.039666) (xy 84.194341 -88.00172) (xy 84.2586 -87.970775) (xy 84.32592 -87.947218)
			(xy 84.395455 -87.931348) (xy 84.466329 -87.923362) (xy 84.50199 -87.922862) (xy 84.537651 -87.923362)
			(xy 84.608525 -87.931348) (xy 84.67806 -87.947218) (xy 84.74538 -87.970775) (xy 84.809639 -88.00172)
			(xy 84.87003 -88.039666) (xy 84.925792 -88.084135) (xy 84.976225 -88.134568) (xy 85.020694 -88.19033)
			(xy 85.05864 -88.250721) (xy 85.089585 -88.31498) (xy 85.113142 -88.3823) (xy 85.129012 -88.451835)
			(xy 85.136998 -88.522709) (xy 85.136998 -88.594031) (xy 86.671396 -88.594031) (xy 86.671396 -88.522709)
			(xy 86.679382 -88.451835) (xy 86.695252 -88.3823) (xy 86.718809 -88.31498) (xy 86.749754 -88.250721)
			(xy 86.7877 -88.19033) (xy 86.832169 -88.134568) (xy 86.882602 -88.084135) (xy 86.938364 -88.039666)
			(xy 86.998755 -88.00172) (xy 87.063014 -87.970775) (xy 87.130334 -87.947218) (xy 87.199869 -87.931348)
			(xy 87.270743 -87.923362) (xy 87.306404 -87.922862) (xy 87.342065 -87.923362) (xy 87.412939 -87.931348)
			(xy 87.482474 -87.947218) (xy 87.549794 -87.970775) (xy 87.614053 -88.00172) (xy 87.674444 -88.039666)
			(xy 87.730206 -88.084135) (xy 87.780639 -88.134568) (xy 87.825108 -88.19033) (xy 87.863054 -88.250721)
			(xy 87.893999 -88.31498) (xy 87.917556 -88.3823) (xy 87.933426 -88.451835) (xy 87.941412 -88.522709)
			(xy 87.941412 -88.594031) (xy 87.933426 -88.664905) (xy 87.917556 -88.73444) (xy 87.893999 -88.80176)
			(xy 87.863054 -88.866019) (xy 87.825108 -88.92641) (xy 87.780639 -88.982172) (xy 87.730206 -89.032605)
			(xy 87.674444 -89.077074) (xy 87.614053 -89.11502) (xy 87.549794 -89.145965) (xy 87.482474 -89.169522)
			(xy 87.412939 -89.185392) (xy 87.342065 -89.193378) (xy 87.270743 -89.193378) (xy 87.199869 -89.185392)
			(xy 87.130334 -89.169522) (xy 87.063014 -89.145965) (xy 86.998755 -89.11502) (xy 86.938364 -89.077074)
			(xy 86.882602 -89.032605) (xy 86.832169 -88.982172) (xy 86.7877 -88.92641) (xy 86.749754 -88.866019)
			(xy 86.718809 -88.80176) (xy 86.695252 -88.73444) (xy 86.679382 -88.664905) (xy 86.671396 -88.594031)
			(xy 85.136998 -88.594031) (xy 85.129012 -88.664905) (xy 85.113142 -88.73444) (xy 85.089585 -88.80176)
			(xy 85.05864 -88.866019) (xy 85.020694 -88.92641) (xy 84.976225 -88.982172) (xy 84.925792 -89.032605)
			(xy 84.87003 -89.077074) (xy 84.809639 -89.11502) (xy 84.74538 -89.145965) (xy 84.67806 -89.169522)
			(xy 84.608525 -89.185392) (xy 84.537651 -89.193378) (xy 84.466329 -89.193378) (xy 84.395455 -89.185392)
			(xy 84.32592 -89.169522) (xy 84.2586 -89.145965) (xy 84.194341 -89.11502) (xy 84.13395 -89.077074)
			(xy 84.078188 -89.032605) (xy 84.027755 -88.982172) (xy 83.983286 -88.92641) (xy 83.94534 -88.866019)
			(xy 83.914395 -88.80176) (xy 83.890838 -88.73444) (xy 83.874968 -88.664905) (xy 83.866982 -88.594031)
			(xy 33.666259 -88.594031) (xy 33.954466 -88.88222) (xy 35.71494 -88.88222) (xy 39.359332 -92.526612)
			(xy 39.359332 -95.781047) (xy 39.818567 -95.781047) (xy 39.824576 -95.665126) (xy 39.838567 -95.549897)
			(xy 39.860475 -95.435907) (xy 39.890195 -95.3237) (xy 39.927585 -95.213811) (xy 39.972468 -95.106764)
			(xy 40.024629 -95.003068) (xy 40.08382 -94.903218) (xy 40.149759 -94.807689) (xy 40.222131 -94.716938)
			(xy 40.300592 -94.631395) (xy 40.384767 -94.551469) (xy 40.474256 -94.477542) (xy 40.568632 -94.409964)
			(xy 40.667446 -94.349058) (xy 40.770226 -94.295115) (xy 40.876483 -94.248391) (xy 40.98571 -94.20911)
			(xy 41.097387 -94.177458) (xy 41.210982 -94.153585) (xy 41.325953 -94.137607) (xy 41.441752 -94.129599)
			(xy 41.49979 -94.129098) (xy 41.557828 -94.129599) (xy 41.673627 -94.137607) (xy 41.788598 -94.153585)
			(xy 41.902193 -94.177458) (xy 42.01387 -94.20911) (xy 42.123097 -94.248391) (xy 42.229354 -94.295115)
			(xy 42.332134 -94.349058) (xy 42.430948 -94.409964) (xy 42.474432 -94.441101) (xy 63.647829 -94.441101)
			(xy 63.653878 -94.365531) (xy 63.667925 -94.291033) (xy 63.689811 -94.21845) (xy 63.719288 -94.148604)
			(xy 63.756023 -94.082287) (xy 63.799598 -94.020251) (xy 63.84952 -93.963198) (xy 63.905224 -93.911774)
			(xy 63.966079 -93.866563) (xy 64.031394 -93.828076) (xy 64.10043 -93.79675) (xy 64.172405 -93.77294)
			(xy 64.246503 -93.756915) (xy 64.321884 -93.748856) (xy 64.35979 -93.748352) (xy 64.397696 -93.748856)
			(xy 64.473077 -93.756915) (xy 64.547175 -93.77294) (xy 64.61915 -93.79675) (xy 64.688186 -93.828076)
			(xy 64.753501 -93.866563) (xy 64.814356 -93.911774) (xy 64.87006 -93.963198) (xy 64.919982 -94.020251)
			(xy 64.963557 -94.082287) (xy 65.000292 -94.148604) (xy 65.029769 -94.21845) (xy 65.051655 -94.291033)
			(xy 65.065702 -94.365531) (xy 65.071751 -94.441101) (xy 66.187829 -94.441101) (xy 66.193878 -94.365531)
			(xy 66.207925 -94.291033) (xy 66.229811 -94.21845) (xy 66.259288 -94.148604) (xy 66.296023 -94.082287)
			(xy 66.339598 -94.020251) (xy 66.38952 -93.963198) (xy 66.445224 -93.911774) (xy 66.506079 -93.866563)
			(xy 66.571394 -93.828076) (xy 66.64043 -93.79675) (xy 66.712405 -93.77294) (xy 66.786503 -93.756915)
			(xy 66.861884 -93.748856) (xy 66.89979 -93.748352) (xy 66.937696 -93.748856) (xy 67.013077 -93.756915)
			(xy 67.087175 -93.77294) (xy 67.15915 -93.79675) (xy 67.228186 -93.828076) (xy 67.293501 -93.866563)
			(xy 67.354356 -93.911774) (xy 67.41006 -93.963198) (xy 67.459982 -94.020251) (xy 67.503557 -94.082287)
			(xy 67.540292 -94.148604) (xy 67.569769 -94.21845) (xy 67.591655 -94.291033) (xy 67.605702 -94.365531)
			(xy 67.611751 -94.441101) (xy 68.727829 -94.441101) (xy 68.733878 -94.365531) (xy 68.747925 -94.291033)
			(xy 68.769811 -94.21845) (xy 68.799288 -94.148604) (xy 68.836023 -94.082287) (xy 68.879598 -94.020251)
			(xy 68.92952 -93.963198) (xy 68.985224 -93.911774) (xy 69.046079 -93.866563) (xy 69.111394 -93.828076)
			(xy 69.18043 -93.79675) (xy 69.252405 -93.77294) (xy 69.326503 -93.756915) (xy 69.401884 -93.748856)
			(xy 69.43979 -93.748352) (xy 69.477696 -93.748856) (xy 69.553077 -93.756915) (xy 69.627175 -93.77294)
			(xy 69.69915 -93.79675) (xy 69.768186 -93.828076) (xy 69.833501 -93.866563) (xy 69.894356 -93.911774)
			(xy 69.95006 -93.963198) (xy 69.999982 -94.020251) (xy 70.043557 -94.082287) (xy 70.080292 -94.148604)
			(xy 70.109769 -94.21845) (xy 70.131655 -94.291033) (xy 70.145702 -94.365531) (xy 70.151751 -94.441101)
			(xy 71.267829 -94.441101) (xy 71.273878 -94.365531) (xy 71.287925 -94.291033) (xy 71.309811 -94.21845)
			(xy 71.339288 -94.148604) (xy 71.376023 -94.082287) (xy 71.419598 -94.020251) (xy 71.46952 -93.963198)
			(xy 71.525224 -93.911774) (xy 71.586079 -93.866563) (xy 71.651394 -93.828076) (xy 71.72043 -93.79675)
			(xy 71.792405 -93.77294) (xy 71.866503 -93.756915) (xy 71.941884 -93.748856) (xy 71.97979 -93.748352)
			(xy 72.017696 -93.748856) (xy 72.093077 -93.756915) (xy 72.167175 -93.77294) (xy 72.23915 -93.79675)
			(xy 72.308186 -93.828076) (xy 72.373501 -93.866563) (xy 72.434356 -93.911774) (xy 72.49006 -93.963198)
			(xy 72.539982 -94.020251) (xy 72.583557 -94.082287) (xy 72.620292 -94.148604) (xy 72.649769 -94.21845)
			(xy 72.671655 -94.291033) (xy 72.685702 -94.365531) (xy 72.691751 -94.441101) (xy 73.807829 -94.441101)
			(xy 73.813878 -94.365531) (xy 73.827925 -94.291033) (xy 73.849811 -94.21845) (xy 73.879288 -94.148604)
			(xy 73.916023 -94.082287) (xy 73.959598 -94.020251) (xy 74.00952 -93.963198) (xy 74.065224 -93.911774)
			(xy 74.126079 -93.866563) (xy 74.191394 -93.828076) (xy 74.26043 -93.79675) (xy 74.332405 -93.77294)
			(xy 74.406503 -93.756915) (xy 74.481884 -93.748856) (xy 74.51979 -93.748352) (xy 74.557696 -93.748856)
			(xy 74.633077 -93.756915) (xy 74.707175 -93.77294) (xy 74.77915 -93.79675) (xy 74.848186 -93.828076)
			(xy 74.913501 -93.866563) (xy 74.974356 -93.911774) (xy 75.03006 -93.963198) (xy 75.079982 -94.020251)
			(xy 75.123557 -94.082287) (xy 75.160292 -94.148604) (xy 75.189769 -94.21845) (xy 75.211655 -94.291033)
			(xy 75.225702 -94.365531) (xy 75.231751 -94.441101) (xy 76.347829 -94.441101) (xy 76.353878 -94.365531)
			(xy 76.367925 -94.291033) (xy 76.389811 -94.21845) (xy 76.419288 -94.148604) (xy 76.456023 -94.082287)
			(xy 76.499598 -94.020251) (xy 76.54952 -93.963198) (xy 76.605224 -93.911774) (xy 76.666079 -93.866563)
			(xy 76.731394 -93.828076) (xy 76.80043 -93.79675) (xy 76.872405 -93.77294) (xy 76.946503 -93.756915)
			(xy 77.021884 -93.748856) (xy 77.05979 -93.748352) (xy 77.097696 -93.748856) (xy 77.173077 -93.756915)
			(xy 77.247175 -93.77294) (xy 77.31915 -93.79675) (xy 77.388186 -93.828076) (xy 77.453501 -93.866563)
			(xy 77.514356 -93.911774) (xy 77.57006 -93.963198) (xy 77.619982 -94.020251) (xy 77.663557 -94.082287)
			(xy 77.700292 -94.148604) (xy 77.729769 -94.21845) (xy 77.751655 -94.291033) (xy 77.765702 -94.365531)
			(xy 77.771751 -94.441101) (xy 78.887829 -94.441101) (xy 78.893878 -94.365531) (xy 78.907925 -94.291033)
			(xy 78.929811 -94.21845) (xy 78.959288 -94.148604) (xy 78.996023 -94.082287) (xy 79.039598 -94.020251)
			(xy 79.08952 -93.963198) (xy 79.145224 -93.911774) (xy 79.206079 -93.866563) (xy 79.271394 -93.828076)
			(xy 79.34043 -93.79675) (xy 79.412405 -93.77294) (xy 79.486503 -93.756915) (xy 79.561884 -93.748856)
			(xy 79.59979 -93.748352) (xy 79.637696 -93.748856) (xy 79.713077 -93.756915) (xy 79.787175 -93.77294)
			(xy 79.85915 -93.79675) (xy 79.928186 -93.828076) (xy 79.993501 -93.866563) (xy 80.054356 -93.911774)
			(xy 80.11006 -93.963198) (xy 80.159982 -94.020251) (xy 80.203557 -94.082287) (xy 80.240292 -94.148604)
			(xy 80.269769 -94.21845) (xy 80.291655 -94.291033) (xy 80.305702 -94.365531) (xy 80.311751 -94.441101)
			(xy 81.427829 -94.441101) (xy 81.433878 -94.365531) (xy 81.447925 -94.291033) (xy 81.469811 -94.21845)
			(xy 81.499288 -94.148604) (xy 81.536023 -94.082287) (xy 81.579598 -94.020251) (xy 81.62952 -93.963198)
			(xy 81.685224 -93.911774) (xy 81.746079 -93.866563) (xy 81.811394 -93.828076) (xy 81.88043 -93.79675)
			(xy 81.952405 -93.77294) (xy 82.026503 -93.756915) (xy 82.101884 -93.748856) (xy 82.13979 -93.748352)
			(xy 82.177696 -93.748856) (xy 82.253077 -93.756915) (xy 82.327175 -93.77294) (xy 82.39915 -93.79675)
			(xy 82.468186 -93.828076) (xy 82.533501 -93.866563) (xy 82.559813 -93.886111) (xy 86.197949 -93.886111)
			(xy 86.203998 -93.810541) (xy 86.218045 -93.736043) (xy 86.239931 -93.66346) (xy 86.269408 -93.593614)
			(xy 86.306143 -93.527297) (xy 86.349718 -93.465261) (xy 86.39964 -93.408208) (xy 86.455344 -93.356784)
			(xy 86.516199 -93.311573) (xy 86.581514 -93.273086) (xy 86.65055 -93.24176) (xy 86.722525 -93.21795)
			(xy 86.796623 -93.201925) (xy 86.872004 -93.193866) (xy 86.90991 -93.193362) (xy 86.947816 -93.193866)
			(xy 87.023197 -93.201925) (xy 87.097295 -93.21795) (xy 87.16927 -93.24176) (xy 87.238306 -93.273086)
			(xy 87.303621 -93.311573) (xy 87.364476 -93.356784) (xy 87.42018 -93.408208) (xy 87.470102 -93.465261)
			(xy 87.513677 -93.527297) (xy 87.550412 -93.593614) (xy 87.579889 -93.66346) (xy 87.601775 -93.736043)
			(xy 87.615822 -93.810541) (xy 87.621871 -93.886111) (xy 88.737949 -93.886111) (xy 88.743998 -93.810541)
			(xy 88.758045 -93.736043) (xy 88.779931 -93.66346) (xy 88.809408 -93.593614) (xy 88.846143 -93.527297)
			(xy 88.889718 -93.465261) (xy 88.93964 -93.408208) (xy 88.995344 -93.356784) (xy 89.056199 -93.311573)
			(xy 89.121514 -93.273086) (xy 89.19055 -93.24176) (xy 89.262525 -93.21795) (xy 89.336623 -93.201925)
			(xy 89.412004 -93.193866) (xy 89.44991 -93.193362) (xy 89.487816 -93.193866) (xy 89.563197 -93.201925)
			(xy 89.637295 -93.21795) (xy 89.70927 -93.24176) (xy 89.778306 -93.273086) (xy 89.843621 -93.311573)
			(xy 89.904476 -93.356784) (xy 89.96018 -93.408208) (xy 90.010102 -93.465261) (xy 90.053677 -93.527297)
			(xy 90.090412 -93.593614) (xy 90.119889 -93.66346) (xy 90.141775 -93.736043) (xy 90.155822 -93.810541)
			(xy 90.161871 -93.886111) (xy 91.277949 -93.886111) (xy 91.283998 -93.810541) (xy 91.298045 -93.736043)
			(xy 91.319931 -93.66346) (xy 91.349408 -93.593614) (xy 91.386143 -93.527297) (xy 91.429718 -93.465261)
			(xy 91.47964 -93.408208) (xy 91.535344 -93.356784) (xy 91.596199 -93.311573) (xy 91.661514 -93.273086)
			(xy 91.73055 -93.24176) (xy 91.802525 -93.21795) (xy 91.876623 -93.201925) (xy 91.952004 -93.193866)
			(xy 91.98991 -93.193362) (xy 92.027816 -93.193866) (xy 92.103197 -93.201925) (xy 92.177295 -93.21795)
			(xy 92.24927 -93.24176) (xy 92.318306 -93.273086) (xy 92.383621 -93.311573) (xy 92.444476 -93.356784)
			(xy 92.50018 -93.408208) (xy 92.550102 -93.465261) (xy 92.593677 -93.527297) (xy 92.630412 -93.593614)
			(xy 92.659889 -93.66346) (xy 92.681775 -93.736043) (xy 92.695822 -93.810541) (xy 92.701871 -93.886111)
			(xy 92.699852 -93.961895) (xy 92.68979 -94.037035) (xy 92.671798 -94.11068) (xy 92.64608 -94.181996)
			(xy 92.612928 -94.250173) (xy 92.572716 -94.314441) (xy 92.525901 -94.37407) (xy 92.473013 -94.428386)
			(xy 92.414651 -94.476772) (xy 92.351476 -94.51868) (xy 92.284205 -94.553636) (xy 92.2136 -94.581243)
			(xy 92.140459 -94.601189) (xy 92.065614 -94.613248) (xy 91.98991 -94.617283) (xy 91.914206 -94.613248)
			(xy 91.839361 -94.601189) (xy 91.76622 -94.581243) (xy 91.695615 -94.553636) (xy 91.628344 -94.51868)
			(xy 91.565169 -94.476772) (xy 91.506807 -94.428386) (xy 91.453919 -94.37407) (xy 91.407104 -94.314441)
			(xy 91.366892 -94.250173) (xy 91.33374 -94.181996) (xy 91.308022 -94.11068) (xy 91.29003 -94.037035)
			(xy 91.279968 -93.961895) (xy 91.277949 -93.886111) (xy 90.161871 -93.886111) (xy 90.159852 -93.961895)
			(xy 90.14979 -94.037035) (xy 90.131798 -94.11068) (xy 90.10608 -94.181996) (xy 90.072928 -94.250173)
			(xy 90.032716 -94.314441) (xy 89.985901 -94.37407) (xy 89.933013 -94.428386) (xy 89.874651 -94.476772)
			(xy 89.811476 -94.51868) (xy 89.744205 -94.553636) (xy 89.6736 -94.581243) (xy 89.600459 -94.601189)
			(xy 89.525614 -94.613248) (xy 89.44991 -94.617283) (xy 89.374206 -94.613248) (xy 89.299361 -94.601189)
			(xy 89.22622 -94.581243) (xy 89.155615 -94.553636) (xy 89.088344 -94.51868) (xy 89.025169 -94.476772)
			(xy 88.966807 -94.428386) (xy 88.913919 -94.37407) (xy 88.867104 -94.314441) (xy 88.826892 -94.250173)
			(xy 88.79374 -94.181996) (xy 88.768022 -94.11068) (xy 88.75003 -94.037035) (xy 88.739968 -93.961895)
			(xy 88.737949 -93.886111) (xy 87.621871 -93.886111) (xy 87.619852 -93.961895) (xy 87.60979 -94.037035)
			(xy 87.591798 -94.11068) (xy 87.56608 -94.181996) (xy 87.532928 -94.250173) (xy 87.492716 -94.314441)
			(xy 87.445901 -94.37407) (xy 87.393013 -94.428386) (xy 87.334651 -94.476772) (xy 87.271476 -94.51868)
			(xy 87.204205 -94.553636) (xy 87.1336 -94.581243) (xy 87.060459 -94.601189) (xy 86.985614 -94.613248)
			(xy 86.90991 -94.617283) (xy 86.834206 -94.613248) (xy 86.759361 -94.601189) (xy 86.68622 -94.581243)
			(xy 86.615615 -94.553636) (xy 86.548344 -94.51868) (xy 86.485169 -94.476772) (xy 86.426807 -94.428386)
			(xy 86.373919 -94.37407) (xy 86.327104 -94.314441) (xy 86.286892 -94.250173) (xy 86.25374 -94.181996)
			(xy 86.228022 -94.11068) (xy 86.21003 -94.037035) (xy 86.199968 -93.961895) (xy 86.197949 -93.886111)
			(xy 82.559813 -93.886111) (xy 82.594356 -93.911774) (xy 82.65006 -93.963198) (xy 82.699982 -94.020251)
			(xy 82.743557 -94.082287) (xy 82.780292 -94.148604) (xy 82.809769 -94.21845) (xy 82.831655 -94.291033)
			(xy 82.845702 -94.365531) (xy 82.851751 -94.441101) (xy 82.849732 -94.516885) (xy 82.83967 -94.592025)
			(xy 82.821678 -94.66567) (xy 82.79596 -94.736986) (xy 82.762808 -94.805163) (xy 82.722596 -94.869431)
			(xy 82.675781 -94.92906) (xy 82.622893 -94.983376) (xy 82.564531 -95.031762) (xy 82.501356 -95.07367)
			(xy 82.434085 -95.108626) (xy 82.36348 -95.136233) (xy 82.290588 -95.156111) (xy 84.927949 -95.156111)
			(xy 84.933998 -95.080541) (xy 84.948045 -95.006043) (xy 84.969931 -94.93346) (xy 84.999408 -94.863614)
			(xy 85.036143 -94.797297) (xy 85.079718 -94.735261) (xy 85.12964 -94.678208) (xy 85.185344 -94.626784)
			(xy 85.246199 -94.581573) (xy 85.311514 -94.543086) (xy 85.38055 -94.51176) (xy 85.452525 -94.48795)
			(xy 85.526623 -94.471925) (xy 85.602004 -94.463866) (xy 85.63991 -94.463362) (xy 85.677816 -94.463866)
			(xy 85.753197 -94.471925) (xy 85.827295 -94.48795) (xy 85.89927 -94.51176) (xy 85.968306 -94.543086)
			(xy 86.033621 -94.581573) (xy 86.094476 -94.626784) (xy 86.15018 -94.678208) (xy 86.200102 -94.735261)
			(xy 86.243677 -94.797297) (xy 86.280412 -94.863614) (xy 86.309889 -94.93346) (xy 86.331775 -95.006043)
			(xy 86.345822 -95.080541) (xy 86.351871 -95.156111) (xy 87.467949 -95.156111) (xy 87.473998 -95.080541)
			(xy 87.488045 -95.006043) (xy 87.509931 -94.93346) (xy 87.539408 -94.863614) (xy 87.576143 -94.797297)
			(xy 87.619718 -94.735261) (xy 87.66964 -94.678208) (xy 87.725344 -94.626784) (xy 87.786199 -94.581573)
			(xy 87.851514 -94.543086) (xy 87.92055 -94.51176) (xy 87.992525 -94.48795) (xy 88.066623 -94.471925)
			(xy 88.142004 -94.463866) (xy 88.17991 -94.463362) (xy 88.217816 -94.463866) (xy 88.293197 -94.471925)
			(xy 88.367295 -94.48795) (xy 88.43927 -94.51176) (xy 88.508306 -94.543086) (xy 88.573621 -94.581573)
			(xy 88.634476 -94.626784) (xy 88.69018 -94.678208) (xy 88.740102 -94.735261) (xy 88.783677 -94.797297)
			(xy 88.820412 -94.863614) (xy 88.849889 -94.93346) (xy 88.871775 -95.006043) (xy 88.885822 -95.080541)
			(xy 88.891871 -95.156111) (xy 90.007949 -95.156111) (xy 90.013998 -95.080541) (xy 90.028045 -95.006043)
			(xy 90.049931 -94.93346) (xy 90.079408 -94.863614) (xy 90.116143 -94.797297) (xy 90.159718 -94.735261)
			(xy 90.20964 -94.678208) (xy 90.265344 -94.626784) (xy 90.326199 -94.581573) (xy 90.391514 -94.543086)
			(xy 90.46055 -94.51176) (xy 90.532525 -94.48795) (xy 90.606623 -94.471925) (xy 90.682004 -94.463866)
			(xy 90.71991 -94.463362) (xy 90.757816 -94.463866) (xy 90.833197 -94.471925) (xy 90.907295 -94.48795)
			(xy 90.97927 -94.51176) (xy 91.048306 -94.543086) (xy 91.113621 -94.581573) (xy 91.174476 -94.626784)
			(xy 91.23018 -94.678208) (xy 91.280102 -94.735261) (xy 91.323677 -94.797297) (xy 91.360412 -94.863614)
			(xy 91.389889 -94.93346) (xy 91.411775 -95.006043) (xy 91.425822 -95.080541) (xy 91.431871 -95.156111)
			(xy 91.429852 -95.231895) (xy 91.41979 -95.307035) (xy 91.401798 -95.38068) (xy 91.37608 -95.451996)
			(xy 91.342928 -95.520173) (xy 91.302716 -95.584441) (xy 91.255901 -95.64407) (xy 91.203013 -95.698386)
			(xy 91.144651 -95.746772) (xy 91.081476 -95.78868) (xy 91.014205 -95.823636) (xy 90.9436 -95.851243)
			(xy 90.870459 -95.871189) (xy 90.795614 -95.883248) (xy 90.71991 -95.887283) (xy 90.644206 -95.883248)
			(xy 90.569361 -95.871189) (xy 90.49622 -95.851243) (xy 90.425615 -95.823636) (xy 90.358344 -95.78868)
			(xy 90.295169 -95.746772) (xy 90.236807 -95.698386) (xy 90.183919 -95.64407) (xy 90.137104 -95.584441)
			(xy 90.096892 -95.520173) (xy 90.06374 -95.451996) (xy 90.038022 -95.38068) (xy 90.02003 -95.307035)
			(xy 90.009968 -95.231895) (xy 90.007949 -95.156111) (xy 88.891871 -95.156111) (xy 88.889852 -95.231895)
			(xy 88.87979 -95.307035) (xy 88.861798 -95.38068) (xy 88.83608 -95.451996) (xy 88.802928 -95.520173)
			(xy 88.762716 -95.584441) (xy 88.715901 -95.64407) (xy 88.663013 -95.698386) (xy 88.604651 -95.746772)
			(xy 88.541476 -95.78868) (xy 88.474205 -95.823636) (xy 88.4036 -95.851243) (xy 88.330459 -95.871189)
			(xy 88.255614 -95.883248) (xy 88.17991 -95.887283) (xy 88.104206 -95.883248) (xy 88.029361 -95.871189)
			(xy 87.95622 -95.851243) (xy 87.885615 -95.823636) (xy 87.818344 -95.78868) (xy 87.755169 -95.746772)
			(xy 87.696807 -95.698386) (xy 87.643919 -95.64407) (xy 87.597104 -95.584441) (xy 87.556892 -95.520173)
			(xy 87.52374 -95.451996) (xy 87.498022 -95.38068) (xy 87.48003 -95.307035) (xy 87.469968 -95.231895)
			(xy 87.467949 -95.156111) (xy 86.351871 -95.156111) (xy 86.349852 -95.231895) (xy 86.33979 -95.307035)
			(xy 86.321798 -95.38068) (xy 86.29608 -95.451996) (xy 86.262928 -95.520173) (xy 86.222716 -95.584441)
			(xy 86.175901 -95.64407) (xy 86.123013 -95.698386) (xy 86.064651 -95.746772) (xy 86.001476 -95.78868)
			(xy 85.934205 -95.823636) (xy 85.8636 -95.851243) (xy 85.790459 -95.871189) (xy 85.715614 -95.883248)
			(xy 85.63991 -95.887283) (xy 85.564206 -95.883248) (xy 85.489361 -95.871189) (xy 85.41622 -95.851243)
			(xy 85.345615 -95.823636) (xy 85.278344 -95.78868) (xy 85.215169 -95.746772) (xy 85.156807 -95.698386)
			(xy 85.103919 -95.64407) (xy 85.057104 -95.584441) (xy 85.016892 -95.520173) (xy 84.98374 -95.451996)
			(xy 84.958022 -95.38068) (xy 84.94003 -95.307035) (xy 84.929968 -95.231895) (xy 84.927949 -95.156111)
			(xy 82.290588 -95.156111) (xy 82.290339 -95.156179) (xy 82.215494 -95.168238) (xy 82.13979 -95.172273)
			(xy 82.064086 -95.168238) (xy 81.989241 -95.156179) (xy 81.9161 -95.136233) (xy 81.845495 -95.108626)
			(xy 81.778224 -95.07367) (xy 81.715049 -95.031762) (xy 81.656687 -94.983376) (xy 81.603799 -94.92906)
			(xy 81.556984 -94.869431) (xy 81.516772 -94.805163) (xy 81.48362 -94.736986) (xy 81.457902 -94.66567)
			(xy 81.43991 -94.592025) (xy 81.429848 -94.516885) (xy 81.427829 -94.441101) (xy 80.311751 -94.441101)
			(xy 80.309732 -94.516885) (xy 80.29967 -94.592025) (xy 80.281678 -94.66567) (xy 80.25596 -94.736986)
			(xy 80.222808 -94.805163) (xy 80.182596 -94.869431) (xy 80.135781 -94.92906) (xy 80.082893 -94.983376)
			(xy 80.024531 -95.031762) (xy 79.961356 -95.07367) (xy 79.894085 -95.108626) (xy 79.82348 -95.136233)
			(xy 79.750339 -95.156179) (xy 79.675494 -95.168238) (xy 79.59979 -95.172273) (xy 79.524086 -95.168238)
			(xy 79.449241 -95.156179) (xy 79.3761 -95.136233) (xy 79.305495 -95.108626) (xy 79.238224 -95.07367)
			(xy 79.175049 -95.031762) (xy 79.116687 -94.983376) (xy 79.063799 -94.92906) (xy 79.016984 -94.869431)
			(xy 78.976772 -94.805163) (xy 78.94362 -94.736986) (xy 78.917902 -94.66567) (xy 78.89991 -94.592025)
			(xy 78.889848 -94.516885) (xy 78.887829 -94.441101) (xy 77.771751 -94.441101) (xy 77.769732 -94.516885)
			(xy 77.75967 -94.592025) (xy 77.741678 -94.66567) (xy 77.71596 -94.736986) (xy 77.682808 -94.805163)
			(xy 77.642596 -94.869431) (xy 77.595781 -94.92906) (xy 77.542893 -94.983376) (xy 77.484531 -95.031762)
			(xy 77.421356 -95.07367) (xy 77.354085 -95.108626) (xy 77.28348 -95.136233) (xy 77.210339 -95.156179)
			(xy 77.135494 -95.168238) (xy 77.05979 -95.172273) (xy 76.984086 -95.168238) (xy 76.909241 -95.156179)
			(xy 76.8361 -95.136233) (xy 76.765495 -95.108626) (xy 76.698224 -95.07367) (xy 76.635049 -95.031762)
			(xy 76.576687 -94.983376) (xy 76.523799 -94.92906) (xy 76.476984 -94.869431) (xy 76.436772 -94.805163)
			(xy 76.40362 -94.736986) (xy 76.377902 -94.66567) (xy 76.35991 -94.592025) (xy 76.349848 -94.516885)
			(xy 76.347829 -94.441101) (xy 75.231751 -94.441101) (xy 75.229732 -94.516885) (xy 75.21967 -94.592025)
			(xy 75.201678 -94.66567) (xy 75.17596 -94.736986) (xy 75.142808 -94.805163) (xy 75.102596 -94.869431)
			(xy 75.055781 -94.92906) (xy 75.002893 -94.983376) (xy 74.944531 -95.031762) (xy 74.881356 -95.07367)
			(xy 74.814085 -95.108626) (xy 74.74348 -95.136233) (xy 74.670339 -95.156179) (xy 74.595494 -95.168238)
			(xy 74.51979 -95.172273) (xy 74.444086 -95.168238) (xy 74.369241 -95.156179) (xy 74.2961 -95.136233)
			(xy 74.225495 -95.108626) (xy 74.158224 -95.07367) (xy 74.095049 -95.031762) (xy 74.036687 -94.983376)
			(xy 73.983799 -94.92906) (xy 73.936984 -94.869431) (xy 73.896772 -94.805163) (xy 73.86362 -94.736986)
			(xy 73.837902 -94.66567) (xy 73.81991 -94.592025) (xy 73.809848 -94.516885) (xy 73.807829 -94.441101)
			(xy 72.691751 -94.441101) (xy 72.689732 -94.516885) (xy 72.67967 -94.592025) (xy 72.661678 -94.66567)
			(xy 72.63596 -94.736986) (xy 72.602808 -94.805163) (xy 72.562596 -94.869431) (xy 72.515781 -94.92906)
			(xy 72.462893 -94.983376) (xy 72.404531 -95.031762) (xy 72.341356 -95.07367) (xy 72.274085 -95.108626)
			(xy 72.20348 -95.136233) (xy 72.130339 -95.156179) (xy 72.055494 -95.168238) (xy 71.97979 -95.172273)
			(xy 71.904086 -95.168238) (xy 71.829241 -95.156179) (xy 71.7561 -95.136233) (xy 71.685495 -95.108626)
			(xy 71.618224 -95.07367) (xy 71.555049 -95.031762) (xy 71.496687 -94.983376) (xy 71.443799 -94.92906)
			(xy 71.396984 -94.869431) (xy 71.356772 -94.805163) (xy 71.32362 -94.736986) (xy 71.297902 -94.66567)
			(xy 71.27991 -94.592025) (xy 71.269848 -94.516885) (xy 71.267829 -94.441101) (xy 70.151751 -94.441101)
			(xy 70.149732 -94.516885) (xy 70.13967 -94.592025) (xy 70.121678 -94.66567) (xy 70.09596 -94.736986)
			(xy 70.062808 -94.805163) (xy 70.022596 -94.869431) (xy 69.975781 -94.92906) (xy 69.922893 -94.983376)
			(xy 69.864531 -95.031762) (xy 69.801356 -95.07367) (xy 69.734085 -95.108626) (xy 69.66348 -95.136233)
			(xy 69.590339 -95.156179) (xy 69.515494 -95.168238) (xy 69.43979 -95.172273) (xy 69.364086 -95.168238)
			(xy 69.289241 -95.156179) (xy 69.2161 -95.136233) (xy 69.145495 -95.108626) (xy 69.078224 -95.07367)
			(xy 69.015049 -95.031762) (xy 68.956687 -94.983376) (xy 68.903799 -94.92906) (xy 68.856984 -94.869431)
			(xy 68.816772 -94.805163) (xy 68.78362 -94.736986) (xy 68.757902 -94.66567) (xy 68.73991 -94.592025)
			(xy 68.729848 -94.516885) (xy 68.727829 -94.441101) (xy 67.611751 -94.441101) (xy 67.609732 -94.516885)
			(xy 67.59967 -94.592025) (xy 67.581678 -94.66567) (xy 67.55596 -94.736986) (xy 67.522808 -94.805163)
			(xy 67.482596 -94.869431) (xy 67.435781 -94.92906) (xy 67.382893 -94.983376) (xy 67.324531 -95.031762)
			(xy 67.261356 -95.07367) (xy 67.194085 -95.108626) (xy 67.12348 -95.136233) (xy 67.050339 -95.156179)
			(xy 66.975494 -95.168238) (xy 66.89979 -95.172273) (xy 66.824086 -95.168238) (xy 66.749241 -95.156179)
			(xy 66.6761 -95.136233) (xy 66.605495 -95.108626) (xy 66.538224 -95.07367) (xy 66.475049 -95.031762)
			(xy 66.416687 -94.983376) (xy 66.363799 -94.92906) (xy 66.316984 -94.869431) (xy 66.276772 -94.805163)
			(xy 66.24362 -94.736986) (xy 66.217902 -94.66567) (xy 66.19991 -94.592025) (xy 66.189848 -94.516885)
			(xy 66.187829 -94.441101) (xy 65.071751 -94.441101) (xy 65.069732 -94.516885) (xy 65.05967 -94.592025)
			(xy 65.041678 -94.66567) (xy 65.01596 -94.736986) (xy 64.982808 -94.805163) (xy 64.942596 -94.869431)
			(xy 64.895781 -94.92906) (xy 64.842893 -94.983376) (xy 64.784531 -95.031762) (xy 64.721356 -95.07367)
			(xy 64.654085 -95.108626) (xy 64.58348 -95.136233) (xy 64.510339 -95.156179) (xy 64.435494 -95.168238)
			(xy 64.35979 -95.172273) (xy 64.284086 -95.168238) (xy 64.209241 -95.156179) (xy 64.1361 -95.136233)
			(xy 64.065495 -95.108626) (xy 63.998224 -95.07367) (xy 63.935049 -95.031762) (xy 63.876687 -94.983376)
			(xy 63.823799 -94.92906) (xy 63.776984 -94.869431) (xy 63.736772 -94.805163) (xy 63.70362 -94.736986)
			(xy 63.677902 -94.66567) (xy 63.65991 -94.592025) (xy 63.649848 -94.516885) (xy 63.647829 -94.441101)
			(xy 42.474432 -94.441101) (xy 42.525324 -94.477542) (xy 42.614813 -94.551469) (xy 42.698988 -94.631395)
			(xy 42.777449 -94.716938) (xy 42.849821 -94.807689) (xy 42.91576 -94.903218) (xy 42.974951 -95.003068)
			(xy 43.027112 -95.106764) (xy 43.071995 -95.213811) (xy 43.109385 -95.3237) (xy 43.139105 -95.435907)
			(xy 43.161013 -95.549897) (xy 43.175004 -95.665126) (xy 43.181013 -95.781047) (xy 43.179009 -95.897105)
			(xy 43.169003 -96.012749) (xy 43.151043 -96.127427) (xy 43.125213 -96.240593) (xy 43.091638 -96.351707)
			(xy 43.06342 -96.426111) (xy 86.197949 -96.426111) (xy 86.203998 -96.350541) (xy 86.218045 -96.276043)
			(xy 86.239931 -96.20346) (xy 86.269408 -96.133614) (xy 86.306143 -96.067297) (xy 86.349718 -96.005261)
			(xy 86.39964 -95.948208) (xy 86.455344 -95.896784) (xy 86.516199 -95.851573) (xy 86.581514 -95.813086)
			(xy 86.65055 -95.78176) (xy 86.722525 -95.75795) (xy 86.796623 -95.741925) (xy 86.872004 -95.733866)
			(xy 86.90991 -95.733362) (xy 86.947816 -95.733866) (xy 87.023197 -95.741925) (xy 87.097295 -95.75795)
			(xy 87.16927 -95.78176) (xy 87.238306 -95.813086) (xy 87.303621 -95.851573) (xy 87.364476 -95.896784)
			(xy 87.42018 -95.948208) (xy 87.470102 -96.005261) (xy 87.513677 -96.067297) (xy 87.550412 -96.133614)
			(xy 87.579889 -96.20346) (xy 87.601775 -96.276043) (xy 87.615822 -96.350541) (xy 87.621871 -96.426111)
			(xy 88.737949 -96.426111) (xy 88.743998 -96.350541) (xy 88.758045 -96.276043) (xy 88.779931 -96.20346)
			(xy 88.809408 -96.133614) (xy 88.846143 -96.067297) (xy 88.889718 -96.005261) (xy 88.93964 -95.948208)
			(xy 88.995344 -95.896784) (xy 89.056199 -95.851573) (xy 89.121514 -95.813086) (xy 89.19055 -95.78176)
			(xy 89.262525 -95.75795) (xy 89.336623 -95.741925) (xy 89.412004 -95.733866) (xy 89.44991 -95.733362)
			(xy 89.487816 -95.733866) (xy 89.563197 -95.741925) (xy 89.637295 -95.75795) (xy 89.70927 -95.78176)
			(xy 89.778306 -95.813086) (xy 89.843621 -95.851573) (xy 89.904476 -95.896784) (xy 89.96018 -95.948208)
			(xy 90.010102 -96.005261) (xy 90.053677 -96.067297) (xy 90.090412 -96.133614) (xy 90.119889 -96.20346)
			(xy 90.141775 -96.276043) (xy 90.155822 -96.350541) (xy 90.161871 -96.426111) (xy 91.277949 -96.426111)
			(xy 91.283998 -96.350541) (xy 91.298045 -96.276043) (xy 91.319931 -96.20346) (xy 91.349408 -96.133614)
			(xy 91.386143 -96.067297) (xy 91.429718 -96.005261) (xy 91.47964 -95.948208) (xy 91.535344 -95.896784)
			(xy 91.596199 -95.851573) (xy 91.661514 -95.813086) (xy 91.73055 -95.78176) (xy 91.802525 -95.75795)
			(xy 91.876623 -95.741925) (xy 91.952004 -95.733866) (xy 91.98991 -95.733362) (xy 92.027816 -95.733866)
			(xy 92.103197 -95.741925) (xy 92.177295 -95.75795) (xy 92.24927 -95.78176) (xy 92.318306 -95.813086)
			(xy 92.383621 -95.851573) (xy 92.444476 -95.896784) (xy 92.50018 -95.948208) (xy 92.550102 -96.005261)
			(xy 92.593677 -96.067297) (xy 92.630412 -96.133614) (xy 92.659889 -96.20346) (xy 92.681775 -96.276043)
			(xy 92.695822 -96.350541) (xy 92.701871 -96.426111) (xy 92.699852 -96.501895) (xy 92.68979 -96.577035)
			(xy 92.671798 -96.65068) (xy 92.64608 -96.721996) (xy 92.612928 -96.790173) (xy 92.572716 -96.854441)
			(xy 92.525901 -96.91407) (xy 92.473013 -96.968386) (xy 92.414651 -97.016772) (xy 92.351476 -97.05868)
			(xy 92.284205 -97.093636) (xy 92.2136 -97.121243) (xy 92.177855 -97.130991) (xy 93.154757 -97.130991)
			(xy 93.160779 -97.014808) (xy 93.174802 -96.899317) (xy 93.19676 -96.785069) (xy 93.226547 -96.672608)
			(xy 93.264022 -96.56247) (xy 93.309007 -96.45518) (xy 93.361286 -96.351249) (xy 93.420611 -96.251173)
			(xy 93.486699 -96.155427) (xy 93.559235 -96.06447) (xy 93.637874 -95.978734) (xy 93.72224 -95.898627)
			(xy 93.811932 -95.824531) (xy 93.906522 -95.756801) (xy 94.00556 -95.695757) (xy 94.108573 -95.641692)
			(xy 94.21507 -95.594862) (xy 94.324545 -95.555491) (xy 94.436475 -95.523767) (xy 94.550327 -95.499841)
			(xy 94.665559 -95.483827) (xy 94.781621 -95.4758) (xy 94.83979 -95.475298) (xy 94.897959 -95.4758)
			(xy 95.014021 -95.483827) (xy 95.129253 -95.499841) (xy 95.243105 -95.523767) (xy 95.355035 -95.555491)
			(xy 95.46451 -95.594862) (xy 95.571007 -95.641692) (xy 95.67402 -95.695757) (xy 95.773058 -95.756801)
			(xy 95.867648 -95.824531) (xy 95.95734 -95.898627) (xy 96.041706 -95.978734) (xy 96.120345 -96.06447)
			(xy 96.192881 -96.155427) (xy 96.258969 -96.251173) (xy 96.318294 -96.351249) (xy 96.370573 -96.45518)
			(xy 96.415558 -96.56247) (xy 96.453033 -96.672608) (xy 96.48282 -96.785069) (xy 96.504778 -96.899317)
			(xy 96.518801 -97.014808) (xy 96.524823 -97.130991) (xy 96.522815 -97.247313) (xy 96.512786 -97.363219)
			(xy 96.494785 -97.478156) (xy 96.468897 -97.591579) (xy 96.435246 -97.702944) (xy 96.393992 -97.811723)
			(xy 96.345331 -97.917397) (xy 96.289495 -98.019461) (xy 96.226752 -98.11743) (xy 96.157398 -98.210837)
			(xy 96.081766 -98.299237) (xy 96.000215 -98.382208) (xy 95.913134 -98.459355) (xy 95.820938 -98.53031)
			(xy 95.724066 -98.594736) (xy 95.622981 -98.652325) (xy 95.518163 -98.702802) (xy 95.410112 -98.745928)
			(xy 95.299344 -98.781497) (xy 95.186385 -98.809339) (xy 95.071775 -98.829321) (xy 94.95606 -98.841348)
			(xy 94.83979 -98.845364) (xy 94.72352 -98.841348) (xy 94.607805 -98.829321) (xy 94.493195 -98.809339)
			(xy 94.380236 -98.781497) (xy 94.269468 -98.745928) (xy 94.161417 -98.702802) (xy 94.056599 -98.652325)
			(xy 93.955514 -98.594736) (xy 93.858642 -98.53031) (xy 93.766446 -98.459355) (xy 93.679365 -98.382208)
			(xy 93.597814 -98.299237) (xy 93.522182 -98.210837) (xy 93.452828 -98.11743) (xy 93.390085 -98.019461)
			(xy 93.334249 -97.917397) (xy 93.285588 -97.811723) (xy 93.244334 -97.702944) (xy 93.210683 -97.591579)
			(xy 93.184795 -97.478156) (xy 93.166794 -97.363219) (xy 93.156765 -97.247313) (xy 93.154757 -97.130991)
			(xy 92.177855 -97.130991) (xy 92.140459 -97.141189) (xy 92.065614 -97.153248) (xy 91.98991 -97.157283)
			(xy 91.914206 -97.153248) (xy 91.839361 -97.141189) (xy 91.76622 -97.121243) (xy 91.695615 -97.093636)
			(xy 91.628344 -97.05868) (xy 91.565169 -97.016772) (xy 91.506807 -96.968386) (xy 91.453919 -96.91407)
			(xy 91.407104 -96.854441) (xy 91.366892 -96.790173) (xy 91.33374 -96.721996) (xy 91.308022 -96.65068)
			(xy 91.29003 -96.577035) (xy 91.279968 -96.501895) (xy 91.277949 -96.426111) (xy 90.161871 -96.426111)
			(xy 90.159852 -96.501895) (xy 90.14979 -96.577035) (xy 90.131798 -96.65068) (xy 90.10608 -96.721996)
			(xy 90.072928 -96.790173) (xy 90.032716 -96.854441) (xy 89.985901 -96.91407) (xy 89.933013 -96.968386)
			(xy 89.874651 -97.016772) (xy 89.811476 -97.05868) (xy 89.744205 -97.093636) (xy 89.6736 -97.121243)
			(xy 89.600459 -97.141189) (xy 89.525614 -97.153248) (xy 89.44991 -97.157283) (xy 89.374206 -97.153248)
			(xy 89.299361 -97.141189) (xy 89.22622 -97.121243) (xy 89.155615 -97.093636) (xy 89.088344 -97.05868)
			(xy 89.025169 -97.016772) (xy 88.966807 -96.968386) (xy 88.913919 -96.91407) (xy 88.867104 -96.854441)
			(xy 88.826892 -96.790173) (xy 88.79374 -96.721996) (xy 88.768022 -96.65068) (xy 88.75003 -96.577035)
			(xy 88.739968 -96.501895) (xy 88.737949 -96.426111) (xy 87.621871 -96.426111) (xy 87.619852 -96.501895)
			(xy 87.60979 -96.577035) (xy 87.591798 -96.65068) (xy 87.56608 -96.721996) (xy 87.532928 -96.790173)
			(xy 87.492716 -96.854441) (xy 87.445901 -96.91407) (xy 87.393013 -96.968386) (xy 87.334651 -97.016772)
			(xy 87.271476 -97.05868) (xy 87.204205 -97.093636) (xy 87.1336 -97.121243) (xy 87.060459 -97.141189)
			(xy 86.985614 -97.153248) (xy 86.90991 -97.157283) (xy 86.834206 -97.153248) (xy 86.759361 -97.141189)
			(xy 86.68622 -97.121243) (xy 86.615615 -97.093636) (xy 86.548344 -97.05868) (xy 86.485169 -97.016772)
			(xy 86.426807 -96.968386) (xy 86.373919 -96.91407) (xy 86.327104 -96.854441) (xy 86.286892 -96.790173)
			(xy 86.25374 -96.721996) (xy 86.228022 -96.65068) (xy 86.21003 -96.577035) (xy 86.199968 -96.501895)
			(xy 86.197949 -96.426111) (xy 43.06342 -96.426111) (xy 43.050477 -96.46024) (xy 43.001926 -96.565674)
			(xy 42.946217 -96.667508) (xy 42.883615 -96.765256) (xy 42.814419 -96.858451) (xy 42.738957 -96.946651)
			(xy 42.65759 -97.029434) (xy 42.570706 -97.106407) (xy 42.525601 -97.141121) (xy 63.647829 -97.141121)
			(xy 63.653878 -97.065551) (xy 63.667925 -96.991053) (xy 63.689811 -96.91847) (xy 63.719288 -96.848624)
			(xy 63.756023 -96.782307) (xy 63.799598 -96.720271) (xy 63.84952 -96.663218) (xy 63.905224 -96.611794)
			(xy 63.966079 -96.566583) (xy 64.031394 -96.528096) (xy 64.10043 -96.49677) (xy 64.172405 -96.47296)
			(xy 64.246503 -96.456935) (xy 64.321884 -96.448876) (xy 64.35979 -96.448372) (xy 64.397696 -96.448876)
			(xy 64.473077 -96.456935) (xy 64.547175 -96.47296) (xy 64.61915 -96.49677) (xy 64.688186 -96.528096)
			(xy 64.753501 -96.566583) (xy 64.814356 -96.611794) (xy 64.87006 -96.663218) (xy 64.919982 -96.720271)
			(xy 64.963557 -96.782307) (xy 65.000292 -96.848624) (xy 65.029769 -96.91847) (xy 65.051655 -96.991053)
			(xy 65.065702 -97.065551) (xy 65.071751 -97.141121) (xy 66.187829 -97.141121) (xy 66.193878 -97.065551)
			(xy 66.207925 -96.991053) (xy 66.229811 -96.91847) (xy 66.259288 -96.848624) (xy 66.296023 -96.782307)
			(xy 66.339598 -96.720271) (xy 66.38952 -96.663218) (xy 66.445224 -96.611794) (xy 66.506079 -96.566583)
			(xy 66.571394 -96.528096) (xy 66.64043 -96.49677) (xy 66.712405 -96.47296) (xy 66.786503 -96.456935)
			(xy 66.861884 -96.448876) (xy 66.89979 -96.448372) (xy 66.937696 -96.448876) (xy 67.013077 -96.456935)
			(xy 67.087175 -96.47296) (xy 67.15915 -96.49677) (xy 67.228186 -96.528096) (xy 67.293501 -96.566583)
			(xy 67.354356 -96.611794) (xy 67.41006 -96.663218) (xy 67.459982 -96.720271) (xy 67.503557 -96.782307)
			(xy 67.540292 -96.848624) (xy 67.569769 -96.91847) (xy 67.591655 -96.991053) (xy 67.605702 -97.065551)
			(xy 67.611751 -97.141121) (xy 68.727829 -97.141121) (xy 68.733878 -97.065551) (xy 68.747925 -96.991053)
			(xy 68.769811 -96.91847) (xy 68.799288 -96.848624) (xy 68.836023 -96.782307) (xy 68.879598 -96.720271)
			(xy 68.92952 -96.663218) (xy 68.985224 -96.611794) (xy 69.046079 -96.566583) (xy 69.111394 -96.528096)
			(xy 69.18043 -96.49677) (xy 69.252405 -96.47296) (xy 69.326503 -96.456935) (xy 69.401884 -96.448876)
			(xy 69.43979 -96.448372) (xy 69.477696 -96.448876) (xy 69.553077 -96.456935) (xy 69.627175 -96.47296)
			(xy 69.69915 -96.49677) (xy 69.768186 -96.528096) (xy 69.833501 -96.566583) (xy 69.894356 -96.611794)
			(xy 69.95006 -96.663218) (xy 69.999982 -96.720271) (xy 70.043557 -96.782307) (xy 70.080292 -96.848624)
			(xy 70.109769 -96.91847) (xy 70.131655 -96.991053) (xy 70.145702 -97.065551) (xy 70.151751 -97.141121)
			(xy 71.267829 -97.141121) (xy 71.273878 -97.065551) (xy 71.287925 -96.991053) (xy 71.309811 -96.91847)
			(xy 71.339288 -96.848624) (xy 71.376023 -96.782307) (xy 71.419598 -96.720271) (xy 71.46952 -96.663218)
			(xy 71.525224 -96.611794) (xy 71.586079 -96.566583) (xy 71.651394 -96.528096) (xy 71.72043 -96.49677)
			(xy 71.792405 -96.47296) (xy 71.866503 -96.456935) (xy 71.941884 -96.448876) (xy 71.97979 -96.448372)
			(xy 72.017696 -96.448876) (xy 72.093077 -96.456935) (xy 72.167175 -96.47296) (xy 72.23915 -96.49677)
			(xy 72.308186 -96.528096) (xy 72.373501 -96.566583) (xy 72.434356 -96.611794) (xy 72.49006 -96.663218)
			(xy 72.539982 -96.720271) (xy 72.583557 -96.782307) (xy 72.620292 -96.848624) (xy 72.649769 -96.91847)
			(xy 72.671655 -96.991053) (xy 72.685702 -97.065551) (xy 72.691751 -97.141121) (xy 73.807829 -97.141121)
			(xy 73.813878 -97.065551) (xy 73.827925 -96.991053) (xy 73.849811 -96.91847) (xy 73.879288 -96.848624)
			(xy 73.916023 -96.782307) (xy 73.959598 -96.720271) (xy 74.00952 -96.663218) (xy 74.065224 -96.611794)
			(xy 74.126079 -96.566583) (xy 74.191394 -96.528096) (xy 74.26043 -96.49677) (xy 74.332405 -96.47296)
			(xy 74.406503 -96.456935) (xy 74.481884 -96.448876) (xy 74.51979 -96.448372) (xy 74.557696 -96.448876)
			(xy 74.633077 -96.456935) (xy 74.707175 -96.47296) (xy 74.77915 -96.49677) (xy 74.848186 -96.528096)
			(xy 74.913501 -96.566583) (xy 74.974356 -96.611794) (xy 75.03006 -96.663218) (xy 75.079982 -96.720271)
			(xy 75.123557 -96.782307) (xy 75.160292 -96.848624) (xy 75.189769 -96.91847) (xy 75.211655 -96.991053)
			(xy 75.225702 -97.065551) (xy 75.231751 -97.141121) (xy 76.347829 -97.141121) (xy 76.353878 -97.065551)
			(xy 76.367925 -96.991053) (xy 76.389811 -96.91847) (xy 76.419288 -96.848624) (xy 76.456023 -96.782307)
			(xy 76.499598 -96.720271) (xy 76.54952 -96.663218) (xy 76.605224 -96.611794) (xy 76.666079 -96.566583)
			(xy 76.731394 -96.528096) (xy 76.80043 -96.49677) (xy 76.872405 -96.47296) (xy 76.946503 -96.456935)
			(xy 77.021884 -96.448876) (xy 77.05979 -96.448372) (xy 77.097696 -96.448876) (xy 77.173077 -96.456935)
			(xy 77.247175 -96.47296) (xy 77.31915 -96.49677) (xy 77.388186 -96.528096) (xy 77.453501 -96.566583)
			(xy 77.514356 -96.611794) (xy 77.57006 -96.663218) (xy 77.619982 -96.720271) (xy 77.663557 -96.782307)
			(xy 77.700292 -96.848624) (xy 77.729769 -96.91847) (xy 77.751655 -96.991053) (xy 77.765702 -97.065551)
			(xy 77.771751 -97.141121) (xy 78.887829 -97.141121) (xy 78.893878 -97.065551) (xy 78.907925 -96.991053)
			(xy 78.929811 -96.91847) (xy 78.959288 -96.848624) (xy 78.996023 -96.782307) (xy 79.039598 -96.720271)
			(xy 79.08952 -96.663218) (xy 79.145224 -96.611794) (xy 79.206079 -96.566583) (xy 79.271394 -96.528096)
			(xy 79.34043 -96.49677) (xy 79.412405 -96.47296) (xy 79.486503 -96.456935) (xy 79.561884 -96.448876)
			(xy 79.59979 -96.448372) (xy 79.637696 -96.448876) (xy 79.713077 -96.456935) (xy 79.787175 -96.47296)
			(xy 79.85915 -96.49677) (xy 79.928186 -96.528096) (xy 79.993501 -96.566583) (xy 80.054356 -96.611794)
			(xy 80.11006 -96.663218) (xy 80.159982 -96.720271) (xy 80.203557 -96.782307) (xy 80.240292 -96.848624)
			(xy 80.269769 -96.91847) (xy 80.291655 -96.991053) (xy 80.305702 -97.065551) (xy 80.311751 -97.141121)
			(xy 81.427829 -97.141121) (xy 81.433878 -97.065551) (xy 81.447925 -96.991053) (xy 81.469811 -96.91847)
			(xy 81.499288 -96.848624) (xy 81.536023 -96.782307) (xy 81.579598 -96.720271) (xy 81.62952 -96.663218)
			(xy 81.685224 -96.611794) (xy 81.746079 -96.566583) (xy 81.811394 -96.528096) (xy 81.88043 -96.49677)
			(xy 81.952405 -96.47296) (xy 82.026503 -96.456935) (xy 82.101884 -96.448876) (xy 82.13979 -96.448372)
			(xy 82.177696 -96.448876) (xy 82.253077 -96.456935) (xy 82.327175 -96.47296) (xy 82.39915 -96.49677)
			(xy 82.468186 -96.528096) (xy 82.533501 -96.566583) (xy 82.594356 -96.611794) (xy 82.65006 -96.663218)
			(xy 82.699982 -96.720271) (xy 82.743557 -96.782307) (xy 82.780292 -96.848624) (xy 82.809769 -96.91847)
			(xy 82.831655 -96.991053) (xy 82.845702 -97.065551) (xy 82.851751 -97.141121) (xy 82.849732 -97.216905)
			(xy 82.83967 -97.292045) (xy 82.821678 -97.36569) (xy 82.79596 -97.437006) (xy 82.762808 -97.505183)
			(xy 82.722596 -97.569451) (xy 82.675781 -97.62908) (xy 82.622893 -97.683396) (xy 82.607556 -97.696111)
			(xy 84.927949 -97.696111) (xy 84.933998 -97.620541) (xy 84.948045 -97.546043) (xy 84.969931 -97.47346)
			(xy 84.999408 -97.403614) (xy 85.036143 -97.337297) (xy 85.079718 -97.275261) (xy 85.12964 -97.218208)
			(xy 85.185344 -97.166784) (xy 85.246199 -97.121573) (xy 85.311514 -97.083086) (xy 85.38055 -97.05176)
			(xy 85.452525 -97.02795) (xy 85.526623 -97.011925) (xy 85.602004 -97.003866) (xy 85.63991 -97.003362)
			(xy 85.677816 -97.003866) (xy 85.753197 -97.011925) (xy 85.827295 -97.02795) (xy 85.89927 -97.05176)
			(xy 85.968306 -97.083086) (xy 86.033621 -97.121573) (xy 86.094476 -97.166784) (xy 86.15018 -97.218208)
			(xy 86.200102 -97.275261) (xy 86.243677 -97.337297) (xy 86.280412 -97.403614) (xy 86.309889 -97.47346)
			(xy 86.331775 -97.546043) (xy 86.345822 -97.620541) (xy 86.351871 -97.696111) (xy 87.467949 -97.696111)
			(xy 87.473998 -97.620541) (xy 87.488045 -97.546043) (xy 87.509931 -97.47346) (xy 87.539408 -97.403614)
			(xy 87.576143 -97.337297) (xy 87.619718 -97.275261) (xy 87.66964 -97.218208) (xy 87.725344 -97.166784)
			(xy 87.786199 -97.121573) (xy 87.851514 -97.083086) (xy 87.92055 -97.05176) (xy 87.992525 -97.02795)
			(xy 88.066623 -97.011925) (xy 88.142004 -97.003866) (xy 88.17991 -97.003362) (xy 88.217816 -97.003866)
			(xy 88.293197 -97.011925) (xy 88.367295 -97.02795) (xy 88.43927 -97.05176) (xy 88.508306 -97.083086)
			(xy 88.573621 -97.121573) (xy 88.634476 -97.166784) (xy 88.69018 -97.218208) (xy 88.740102 -97.275261)
			(xy 88.783677 -97.337297) (xy 88.820412 -97.403614) (xy 88.849889 -97.47346) (xy 88.871775 -97.546043)
			(xy 88.885822 -97.620541) (xy 88.891871 -97.696111) (xy 90.007949 -97.696111) (xy 90.013998 -97.620541)
			(xy 90.028045 -97.546043) (xy 90.049931 -97.47346) (xy 90.079408 -97.403614) (xy 90.116143 -97.337297)
			(xy 90.159718 -97.275261) (xy 90.20964 -97.218208) (xy 90.265344 -97.166784) (xy 90.326199 -97.121573)
			(xy 90.391514 -97.083086) (xy 90.46055 -97.05176) (xy 90.532525 -97.02795) (xy 90.606623 -97.011925)
			(xy 90.682004 -97.003866) (xy 90.71991 -97.003362) (xy 90.757816 -97.003866) (xy 90.833197 -97.011925)
			(xy 90.907295 -97.02795) (xy 90.97927 -97.05176) (xy 91.048306 -97.083086) (xy 91.113621 -97.121573)
			(xy 91.174476 -97.166784) (xy 91.23018 -97.218208) (xy 91.280102 -97.275261) (xy 91.323677 -97.337297)
			(xy 91.360412 -97.403614) (xy 91.389889 -97.47346) (xy 91.411775 -97.546043) (xy 91.425822 -97.620541)
			(xy 91.431871 -97.696111) (xy 91.429852 -97.771895) (xy 91.41979 -97.847035) (xy 91.401798 -97.92068)
			(xy 91.37608 -97.991996) (xy 91.342928 -98.060173) (xy 91.302716 -98.124441) (xy 91.255901 -98.18407)
			(xy 91.203013 -98.238386) (xy 91.144651 -98.286772) (xy 91.081476 -98.32868) (xy 91.014205 -98.363636)
			(xy 90.9436 -98.391243) (xy 90.870459 -98.411189) (xy 90.795614 -98.423248) (xy 90.71991 -98.427283)
			(xy 90.644206 -98.423248) (xy 90.569361 -98.411189) (xy 90.49622 -98.391243) (xy 90.425615 -98.363636)
			(xy 90.358344 -98.32868) (xy 90.295169 -98.286772) (xy 90.236807 -98.238386) (xy 90.183919 -98.18407)
			(xy 90.137104 -98.124441) (xy 90.096892 -98.060173) (xy 90.06374 -97.991996) (xy 90.038022 -97.92068)
			(xy 90.02003 -97.847035) (xy 90.009968 -97.771895) (xy 90.007949 -97.696111) (xy 88.891871 -97.696111)
			(xy 88.889852 -97.771895) (xy 88.87979 -97.847035) (xy 88.861798 -97.92068) (xy 88.83608 -97.991996)
			(xy 88.802928 -98.060173) (xy 88.762716 -98.124441) (xy 88.715901 -98.18407) (xy 88.663013 -98.238386)
			(xy 88.604651 -98.286772) (xy 88.541476 -98.32868) (xy 88.474205 -98.363636) (xy 88.4036 -98.391243)
			(xy 88.330459 -98.411189) (xy 88.255614 -98.423248) (xy 88.17991 -98.427283) (xy 88.104206 -98.423248)
			(xy 88.029361 -98.411189) (xy 87.95622 -98.391243) (xy 87.885615 -98.363636) (xy 87.818344 -98.32868)
			(xy 87.755169 -98.286772) (xy 87.696807 -98.238386) (xy 87.643919 -98.18407) (xy 87.597104 -98.124441)
			(xy 87.556892 -98.060173) (xy 87.52374 -97.991996) (xy 87.498022 -97.92068) (xy 87.48003 -97.847035)
			(xy 87.469968 -97.771895) (xy 87.467949 -97.696111) (xy 86.351871 -97.696111) (xy 86.349852 -97.771895)
			(xy 86.33979 -97.847035) (xy 86.321798 -97.92068) (xy 86.29608 -97.991996) (xy 86.262928 -98.060173)
			(xy 86.222716 -98.124441) (xy 86.175901 -98.18407) (xy 86.123013 -98.238386) (xy 86.064651 -98.286772)
			(xy 86.001476 -98.32868) (xy 85.934205 -98.363636) (xy 85.8636 -98.391243) (xy 85.790459 -98.411189)
			(xy 85.715614 -98.423248) (xy 85.63991 -98.427283) (xy 85.564206 -98.423248) (xy 85.489361 -98.411189)
			(xy 85.41622 -98.391243) (xy 85.345615 -98.363636) (xy 85.278344 -98.32868) (xy 85.215169 -98.286772)
			(xy 85.156807 -98.238386) (xy 85.103919 -98.18407) (xy 85.057104 -98.124441) (xy 85.016892 -98.060173)
			(xy 84.98374 -97.991996) (xy 84.958022 -97.92068) (xy 84.94003 -97.847035) (xy 84.929968 -97.771895)
			(xy 84.927949 -97.696111) (xy 82.607556 -97.696111) (xy 82.564531 -97.731782) (xy 82.501356 -97.77369)
			(xy 82.434085 -97.808646) (xy 82.36348 -97.836253) (xy 82.290339 -97.856199) (xy 82.215494 -97.868258)
			(xy 82.13979 -97.872293) (xy 82.064086 -97.868258) (xy 81.989241 -97.856199) (xy 81.9161 -97.836253)
			(xy 81.845495 -97.808646) (xy 81.778224 -97.77369) (xy 81.715049 -97.731782) (xy 81.656687 -97.683396)
			(xy 81.603799 -97.62908) (xy 81.556984 -97.569451) (xy 81.516772 -97.505183) (xy 81.48362 -97.437006)
			(xy 81.457902 -97.36569) (xy 81.43991 -97.292045) (xy 81.429848 -97.216905) (xy 81.427829 -97.141121)
			(xy 80.311751 -97.141121) (xy 80.309732 -97.216905) (xy 80.29967 -97.292045) (xy 80.281678 -97.36569)
			(xy 80.25596 -97.437006) (xy 80.222808 -97.505183) (xy 80.182596 -97.569451) (xy 80.135781 -97.62908)
			(xy 80.082893 -97.683396) (xy 80.024531 -97.731782) (xy 79.961356 -97.77369) (xy 79.894085 -97.808646)
			(xy 79.82348 -97.836253) (xy 79.750339 -97.856199) (xy 79.675494 -97.868258) (xy 79.59979 -97.872293)
			(xy 79.524086 -97.868258) (xy 79.449241 -97.856199) (xy 79.3761 -97.836253) (xy 79.305495 -97.808646)
			(xy 79.238224 -97.77369) (xy 79.175049 -97.731782) (xy 79.116687 -97.683396) (xy 79.063799 -97.62908)
			(xy 79.016984 -97.569451) (xy 78.976772 -97.505183) (xy 78.94362 -97.437006) (xy 78.917902 -97.36569)
			(xy 78.89991 -97.292045) (xy 78.889848 -97.216905) (xy 78.887829 -97.141121) (xy 77.771751 -97.141121)
			(xy 77.769732 -97.216905) (xy 77.75967 -97.292045) (xy 77.741678 -97.36569) (xy 77.71596 -97.437006)
			(xy 77.682808 -97.505183) (xy 77.642596 -97.569451) (xy 77.595781 -97.62908) (xy 77.542893 -97.683396)
			(xy 77.484531 -97.731782) (xy 77.421356 -97.77369) (xy 77.354085 -97.808646) (xy 77.28348 -97.836253)
			(xy 77.210339 -97.856199) (xy 77.135494 -97.868258) (xy 77.05979 -97.872293) (xy 76.984086 -97.868258)
			(xy 76.909241 -97.856199) (xy 76.8361 -97.836253) (xy 76.765495 -97.808646) (xy 76.698224 -97.77369)
			(xy 76.635049 -97.731782) (xy 76.576687 -97.683396) (xy 76.523799 -97.62908) (xy 76.476984 -97.569451)
			(xy 76.436772 -97.505183) (xy 76.40362 -97.437006) (xy 76.377902 -97.36569) (xy 76.35991 -97.292045)
			(xy 76.349848 -97.216905) (xy 76.347829 -97.141121) (xy 75.231751 -97.141121) (xy 75.229732 -97.216905)
			(xy 75.21967 -97.292045) (xy 75.201678 -97.36569) (xy 75.17596 -97.437006) (xy 75.142808 -97.505183)
			(xy 75.102596 -97.569451) (xy 75.055781 -97.62908) (xy 75.002893 -97.683396) (xy 74.944531 -97.731782)
			(xy 74.881356 -97.77369) (xy 74.814085 -97.808646) (xy 74.74348 -97.836253) (xy 74.670339 -97.856199)
			(xy 74.595494 -97.868258) (xy 74.51979 -97.872293) (xy 74.444086 -97.868258) (xy 74.369241 -97.856199)
			(xy 74.2961 -97.836253) (xy 74.225495 -97.808646) (xy 74.158224 -97.77369) (xy 74.095049 -97.731782)
			(xy 74.036687 -97.683396) (xy 73.983799 -97.62908) (xy 73.936984 -97.569451) (xy 73.896772 -97.505183)
			(xy 73.86362 -97.437006) (xy 73.837902 -97.36569) (xy 73.81991 -97.292045) (xy 73.809848 -97.216905)
			(xy 73.807829 -97.141121) (xy 72.691751 -97.141121) (xy 72.689732 -97.216905) (xy 72.67967 -97.292045)
			(xy 72.661678 -97.36569) (xy 72.63596 -97.437006) (xy 72.602808 -97.505183) (xy 72.562596 -97.569451)
			(xy 72.515781 -97.62908) (xy 72.462893 -97.683396) (xy 72.404531 -97.731782) (xy 72.341356 -97.77369)
			(xy 72.274085 -97.808646) (xy 72.20348 -97.836253) (xy 72.130339 -97.856199) (xy 72.055494 -97.868258)
			(xy 71.97979 -97.872293) (xy 71.904086 -97.868258) (xy 71.829241 -97.856199) (xy 71.7561 -97.836253)
			(xy 71.685495 -97.808646) (xy 71.618224 -97.77369) (xy 71.555049 -97.731782) (xy 71.496687 -97.683396)
			(xy 71.443799 -97.62908) (xy 71.396984 -97.569451) (xy 71.356772 -97.505183) (xy 71.32362 -97.437006)
			(xy 71.297902 -97.36569) (xy 71.27991 -97.292045) (xy 71.269848 -97.216905) (xy 71.267829 -97.141121)
			(xy 70.151751 -97.141121) (xy 70.149732 -97.216905) (xy 70.13967 -97.292045) (xy 70.121678 -97.36569)
			(xy 70.09596 -97.437006) (xy 70.062808 -97.505183) (xy 70.022596 -97.569451) (xy 69.975781 -97.62908)
			(xy 69.922893 -97.683396) (xy 69.864531 -97.731782) (xy 69.801356 -97.77369) (xy 69.734085 -97.808646)
			(xy 69.66348 -97.836253) (xy 69.590339 -97.856199) (xy 69.515494 -97.868258) (xy 69.43979 -97.872293)
			(xy 69.364086 -97.868258) (xy 69.289241 -97.856199) (xy 69.2161 -97.836253) (xy 69.145495 -97.808646)
			(xy 69.078224 -97.77369) (xy 69.015049 -97.731782) (xy 68.956687 -97.683396) (xy 68.903799 -97.62908)
			(xy 68.856984 -97.569451) (xy 68.816772 -97.505183) (xy 68.78362 -97.437006) (xy 68.757902 -97.36569)
			(xy 68.73991 -97.292045) (xy 68.729848 -97.216905) (xy 68.727829 -97.141121) (xy 67.611751 -97.141121)
			(xy 67.609732 -97.216905) (xy 67.59967 -97.292045) (xy 67.581678 -97.36569) (xy 67.55596 -97.437006)
			(xy 67.522808 -97.505183) (xy 67.482596 -97.569451) (xy 67.435781 -97.62908) (xy 67.382893 -97.683396)
			(xy 67.324531 -97.731782) (xy 67.261356 -97.77369) (xy 67.194085 -97.808646) (xy 67.12348 -97.836253)
			(xy 67.050339 -97.856199) (xy 66.975494 -97.868258) (xy 66.89979 -97.872293) (xy 66.824086 -97.868258)
			(xy 66.749241 -97.856199) (xy 66.6761 -97.836253) (xy 66.605495 -97.808646) (xy 66.538224 -97.77369)
			(xy 66.475049 -97.731782) (xy 66.416687 -97.683396) (xy 66.363799 -97.62908) (xy 66.316984 -97.569451)
			(xy 66.276772 -97.505183) (xy 66.24362 -97.437006) (xy 66.217902 -97.36569) (xy 66.19991 -97.292045)
			(xy 66.189848 -97.216905) (xy 66.187829 -97.141121) (xy 65.071751 -97.141121) (xy 65.069732 -97.216905)
			(xy 65.05967 -97.292045) (xy 65.041678 -97.36569) (xy 65.01596 -97.437006) (xy 64.982808 -97.505183)
			(xy 64.942596 -97.569451) (xy 64.895781 -97.62908) (xy 64.842893 -97.683396) (xy 64.784531 -97.731782)
			(xy 64.721356 -97.77369) (xy 64.654085 -97.808646) (xy 64.58348 -97.836253) (xy 64.510339 -97.856199)
			(xy 64.435494 -97.868258) (xy 64.35979 -97.872293) (xy 64.284086 -97.868258) (xy 64.209241 -97.856199)
			(xy 64.1361 -97.836253) (xy 64.065495 -97.808646) (xy 63.998224 -97.77369) (xy 63.935049 -97.731782)
			(xy 63.876687 -97.683396) (xy 63.823799 -97.62908) (xy 63.776984 -97.569451) (xy 63.736772 -97.505183)
			(xy 63.70362 -97.437006) (xy 63.677902 -97.36569) (xy 63.65991 -97.292045) (xy 63.649848 -97.216905)
			(xy 63.647829 -97.141121) (xy 42.525601 -97.141121) (xy 42.478719 -97.177202) (xy 42.382066 -97.241482)
			(xy 42.281209 -97.29894) (xy 42.176629 -97.349304) (xy 42.068822 -97.392332) (xy 41.958305 -97.42782)
			(xy 41.845602 -97.455599) (xy 41.731251 -97.475536) (xy 41.615797 -97.487537) (xy 41.49979 -97.491543)
			(xy 41.383783 -97.487537) (xy 41.268329 -97.475536) (xy 41.153978 -97.455599) (xy 41.041275 -97.42782)
			(xy 40.930758 -97.392332) (xy 40.822951 -97.349304) (xy 40.718371 -97.29894) (xy 40.617514 -97.241482)
			(xy 40.520861 -97.177202) (xy 40.428874 -97.106407) (xy 40.34199 -97.029434) (xy 40.260623 -96.946651)
			(xy 40.185161 -96.858451) (xy 40.115965 -96.765256) (xy 40.053363 -96.667508) (xy 39.997654 -96.565674)
			(xy 39.949103 -96.46024) (xy 39.907942 -96.351707) (xy 39.874367 -96.240593) (xy 39.848537 -96.127427)
			(xy 39.830577 -96.012749) (xy 39.820571 -95.897105) (xy 39.818567 -95.781047) (xy 39.359332 -95.781047)
			(xy 39.359332 -96.628204) (xy 43.120564 -100.389436) (xy 43.120564 -100.842673) (xy 60.260476 -100.842673)
			(xy 60.260476 -100.771351) (xy 60.268462 -100.700477) (xy 60.284332 -100.630942) (xy 60.307889 -100.563622)
			(xy 60.338834 -100.499363) (xy 60.37678 -100.438972) (xy 60.421249 -100.38321) (xy 60.471682 -100.332777)
			(xy 60.527444 -100.288308) (xy 60.587835 -100.250362) (xy 60.652094 -100.219417) (xy 60.719414 -100.19586)
			(xy 60.788949 -100.17999) (xy 60.859823 -100.172004) (xy 60.895484 -100.171504) (xy 60.931145 -100.172004)
			(xy 61.002019 -100.17999) (xy 61.071554 -100.19586) (xy 61.138874 -100.219417) (xy 61.203133 -100.250362)
			(xy 61.263524 -100.288308) (xy 61.319286 -100.332777) (xy 61.369719 -100.38321) (xy 61.414188 -100.438972)
			(xy 61.452134 -100.499363) (xy 61.483079 -100.563622) (xy 61.506636 -100.630942) (xy 61.522506 -100.700477)
			(xy 61.530492 -100.771351) (xy 61.530492 -100.842673) (xy 61.526399 -100.878995) (xy 62.538348 -100.878995)
			(xy 62.538348 -100.807673) (xy 62.546334 -100.736799) (xy 62.562204 -100.667264) (xy 62.585761 -100.599944)
			(xy 62.616706 -100.535685) (xy 62.654652 -100.475294) (xy 62.699121 -100.419532) (xy 62.749554 -100.369099)
			(xy 62.805316 -100.32463) (xy 62.865707 -100.286684) (xy 62.929966 -100.255739) (xy 62.997286 -100.232182)
			(xy 63.066821 -100.216312) (xy 63.137695 -100.208326) (xy 63.173356 -100.207826) (xy 63.209017 -100.208326)
			(xy 63.279891 -100.216312) (xy 63.349426 -100.232182) (xy 63.416746 -100.255739) (xy 63.481005 -100.286684)
			(xy 63.541396 -100.32463) (xy 63.597158 -100.369099) (xy 63.647591 -100.419532) (xy 63.69206 -100.475294)
			(xy 63.730006 -100.535685) (xy 63.760951 -100.599944) (xy 63.784508 -100.667264) (xy 63.800378 -100.736799)
			(xy 63.80521 -100.779681) (xy 64.78828 -100.779681) (xy 64.78828 -100.708359) (xy 64.796266 -100.637485)
			(xy 64.812136 -100.56795) (xy 64.835693 -100.50063) (xy 64.866638 -100.436371) (xy 64.904584 -100.37598)
			(xy 64.949053 -100.320218) (xy 64.999486 -100.269785) (xy 65.055248 -100.225316) (xy 65.115639 -100.18737)
			(xy 65.179898 -100.156425) (xy 65.247218 -100.132868) (xy 65.316753 -100.116998) (xy 65.387627 -100.109012)
			(xy 65.423288 -100.108512) (xy 65.458949 -100.109012) (xy 65.529823 -100.116998) (xy 65.599358 -100.132868)
			(xy 65.666678 -100.156425) (xy 65.730937 -100.18737) (xy 65.791328 -100.225316) (xy 65.84709 -100.269785)
			(xy 65.897523 -100.320218) (xy 65.941992 -100.37598) (xy 65.979938 -100.436371) (xy 66.010883 -100.50063)
			(xy 66.03444 -100.56795) (xy 66.05031 -100.637485) (xy 66.058296 -100.708359) (xy 66.058296 -100.779681)
			(xy 66.058267 -100.779935) (xy 66.939152 -100.779935) (xy 66.939152 -100.708613) (xy 66.947138 -100.637739)
			(xy 66.963008 -100.568204) (xy 66.986565 -100.500884) (xy 67.01751 -100.436625) (xy 67.055456 -100.376234)
			(xy 67.099925 -100.320472) (xy 67.150358 -100.270039) (xy 67.20612 -100.22557) (xy 67.266511 -100.187624)
			(xy 67.33077 -100.156679) (xy 67.39809 -100.133122) (xy 67.467625 -100.117252) (xy 67.538499 -100.109266)
			(xy 67.57416 -100.108766) (xy 67.609821 -100.109266) (xy 67.680695 -100.117252) (xy 67.75023 -100.133122)
			(xy 67.81755 -100.156679) (xy 67.881809 -100.187624) (xy 67.9422 -100.22557) (xy 67.997962 -100.270039)
			(xy 68.048395 -100.320472) (xy 68.092864 -100.376234) (xy 68.13081 -100.436625) (xy 68.161755 -100.500884)
			(xy 68.185312 -100.568204) (xy 68.201182 -100.637739) (xy 68.209168 -100.708613) (xy 68.209168 -100.779935)
			(xy 68.205075 -100.816257) (xy 69.095866 -100.816257) (xy 69.095866 -100.744935) (xy 69.103852 -100.674061)
			(xy 69.119722 -100.604526) (xy 69.143279 -100.537206) (xy 69.174224 -100.472947) (xy 69.21217 -100.412556)
			(xy 69.256639 -100.356794) (xy 69.307072 -100.306361) (xy 69.362834 -100.261892) (xy 69.423225 -100.223946)
			(xy 69.487484 -100.193001) (xy 69.554804 -100.169444) (xy 69.624339 -100.153574) (xy 69.695213 -100.145588)
			(xy 69.730874 -100.145088) (xy 69.766535 -100.145588) (xy 69.837409 -100.153574) (xy 69.906944 -100.169444)
			(xy 69.974264 -100.193001) (xy 70.038523 -100.223946) (xy 70.098914 -100.261892) (xy 70.154676 -100.306361)
			(xy 70.205109 -100.356794) (xy 70.249578 -100.412556) (xy 70.287524 -100.472947) (xy 70.318469 -100.537206)
			(xy 70.342026 -100.604526) (xy 70.357896 -100.674061) (xy 70.365882 -100.744935) (xy 70.365882 -100.816257)
			(xy 70.357896 -100.887131) (xy 70.342026 -100.956666) (xy 70.318469 -101.023986) (xy 70.287524 -101.088245)
			(xy 70.249578 -101.148636) (xy 70.205109 -101.204398) (xy 70.154676 -101.254831) (xy 70.098914 -101.2993)
			(xy 70.038523 -101.337246) (xy 69.974264 -101.368191) (xy 69.906944 -101.391748) (xy 69.837409 -101.407618)
			(xy 69.766535 -101.415604) (xy 69.695213 -101.415604) (xy 69.624339 -101.407618) (xy 69.554804 -101.391748)
			(xy 69.487484 -101.368191) (xy 69.423225 -101.337246) (xy 69.362834 -101.2993) (xy 69.307072 -101.254831)
			(xy 69.256639 -101.204398) (xy 69.21217 -101.148636) (xy 69.174224 -101.088245) (xy 69.143279 -101.023986)
			(xy 69.119722 -100.956666) (xy 69.103852 -100.887131) (xy 69.095866 -100.816257) (xy 68.205075 -100.816257)
			(xy 68.201182 -100.850809) (xy 68.185312 -100.920344) (xy 68.161755 -100.987664) (xy 68.13081 -101.051923)
			(xy 68.092864 -101.112314) (xy 68.048395 -101.168076) (xy 67.997962 -101.218509) (xy 67.9422 -101.262978)
			(xy 67.881809 -101.300924) (xy 67.81755 -101.331869) (xy 67.75023 -101.355426) (xy 67.680695 -101.371296)
			(xy 67.609821 -101.379282) (xy 67.538499 -101.379282) (xy 67.467625 -101.371296) (xy 67.39809 -101.355426)
			(xy 67.33077 -101.331869) (xy 67.266511 -101.300924) (xy 67.20612 -101.262978) (xy 67.150358 -101.218509)
			(xy 67.099925 -101.168076) (xy 67.055456 -101.112314) (xy 67.01751 -101.051923) (xy 66.986565 -100.987664)
			(xy 66.963008 -100.920344) (xy 66.947138 -100.850809) (xy 66.939152 -100.779935) (xy 66.058267 -100.779935)
			(xy 66.05031 -100.850555) (xy 66.03444 -100.92009) (xy 66.010883 -100.98741) (xy 65.979938 -101.051669)
			(xy 65.941992 -101.11206) (xy 65.897523 -101.167822) (xy 65.84709 -101.218255) (xy 65.791328 -101.262724)
			(xy 65.730937 -101.30067) (xy 65.666678 -101.331615) (xy 65.599358 -101.355172) (xy 65.529823 -101.371042)
			(xy 65.458949 -101.379028) (xy 65.387627 -101.379028) (xy 65.316753 -101.371042) (xy 65.247218 -101.355172)
			(xy 65.179898 -101.331615) (xy 65.115639 -101.30067) (xy 65.055248 -101.262724) (xy 64.999486 -101.218255)
			(xy 64.949053 -101.167822) (xy 64.904584 -101.11206) (xy 64.866638 -101.051669) (xy 64.835693 -100.98741)
			(xy 64.812136 -100.92009) (xy 64.796266 -100.850555) (xy 64.78828 -100.779681) (xy 63.80521 -100.779681)
			(xy 63.808364 -100.807673) (xy 63.808364 -100.878995) (xy 63.800378 -100.949869) (xy 63.784508 -101.019404)
			(xy 63.760951 -101.086724) (xy 63.730006 -101.150983) (xy 63.69206 -101.211374) (xy 63.647591 -101.267136)
			(xy 63.597158 -101.317569) (xy 63.541396 -101.362038) (xy 63.481005 -101.399984) (xy 63.416746 -101.430929)
			(xy 63.349426 -101.454486) (xy 63.279891 -101.470356) (xy 63.209017 -101.478342) (xy 63.137695 -101.478342)
			(xy 63.066821 -101.470356) (xy 62.997286 -101.454486) (xy 62.929966 -101.430929) (xy 62.865707 -101.399984)
			(xy 62.805316 -101.362038) (xy 62.749554 -101.317569) (xy 62.699121 -101.267136) (xy 62.654652 -101.211374)
			(xy 62.616706 -101.150983) (xy 62.585761 -101.086724) (xy 62.562204 -101.019404) (xy 62.546334 -100.949869)
			(xy 62.538348 -100.878995) (xy 61.526399 -100.878995) (xy 61.522506 -100.913547) (xy 61.506636 -100.983082)
			(xy 61.483079 -101.050402) (xy 61.452134 -101.114661) (xy 61.414188 -101.175052) (xy 61.369719 -101.230814)
			(xy 61.319286 -101.281247) (xy 61.263524 -101.325716) (xy 61.203133 -101.363662) (xy 61.138874 -101.394607)
			(xy 61.071554 -101.418164) (xy 61.002019 -101.434034) (xy 60.931145 -101.44202) (xy 60.859823 -101.44202)
			(xy 60.788949 -101.434034) (xy 60.719414 -101.418164) (xy 60.652094 -101.394607) (xy 60.587835 -101.363662)
			(xy 60.527444 -101.325716) (xy 60.471682 -101.281247) (xy 60.421249 -101.230814) (xy 60.37678 -101.175052)
			(xy 60.338834 -101.114661) (xy 60.307889 -101.050402) (xy 60.284332 -100.983082) (xy 60.268462 -100.913547)
			(xy 60.260476 -100.842673) (xy 43.120564 -100.842673) (xy 43.120564 -102.057704) (xy 86.43542 -102.057704)
			(xy 86.43542 -101.997768) (xy 86.443243 -101.938346) (xy 86.458756 -101.880453) (xy 86.481692 -101.82508)
			(xy 86.511659 -101.773174) (xy 86.548146 -101.725624) (xy 86.590526 -101.683244) (xy 86.638076 -101.646757)
			(xy 86.689982 -101.61679) (xy 86.745355 -101.593854) (xy 86.803248 -101.578341) (xy 86.86267 -101.570518)
			(xy 86.892638 -101.570028) (xy 86.922606 -101.570518) (xy 86.982028 -101.578341) (xy 87.039921 -101.593854)
			(xy 87.095294 -101.61679) (xy 87.1472 -101.646757) (xy 87.19475 -101.683244) (xy 87.23713 -101.725624)
			(xy 87.273617 -101.773174) (xy 87.303584 -101.82508) (xy 87.32652 -101.880453) (xy 87.342033 -101.938346)
			(xy 87.349856 -101.997768) (xy 87.349856 -102.057704) (xy 87.347047 -102.07904) (xy 91.954332 -102.07904)
			(xy 91.954332 -102.019104) (xy 91.962155 -101.959682) (xy 91.977668 -101.901789) (xy 92.000604 -101.846416)
			(xy 92.030571 -101.79451) (xy 92.067058 -101.74696) (xy 92.109438 -101.70458) (xy 92.156988 -101.668093)
			(xy 92.208894 -101.638126) (xy 92.264267 -101.61519) (xy 92.32216 -101.599677) (xy 92.381582 -101.591854)
			(xy 92.41155 -101.591364) (xy 92.441518 -101.591854) (xy 92.50094 -101.599677) (xy 92.558833 -101.61519)
			(xy 92.614206 -101.638126) (xy 92.666112 -101.668093) (xy 92.713662 -101.70458) (xy 92.756042 -101.74696)
			(xy 92.792529 -101.79451) (xy 92.822496 -101.846416) (xy 92.845432 -101.901789) (xy 92.85985 -101.955596)
			(xy 94.67645 -101.955596) (xy 94.67645 -101.89566) (xy 94.684273 -101.836238) (xy 94.699786 -101.778345)
			(xy 94.722722 -101.722972) (xy 94.752689 -101.671066) (xy 94.789176 -101.623516) (xy 94.831556 -101.581136)
			(xy 94.879106 -101.544649) (xy 94.931012 -101.514682) (xy 94.986385 -101.491746) (xy 95.044278 -101.476233)
			(xy 95.1037 -101.46841) (xy 95.133668 -101.46792) (xy 95.163636 -101.46841) (xy 95.223058 -101.476233)
			(xy 95.280951 -101.491746) (xy 95.336324 -101.514682) (xy 95.38823 -101.544649) (xy 95.43578 -101.581136)
			(xy 95.47816 -101.623516) (xy 95.514647 -101.671066) (xy 95.544614 -101.722972) (xy 95.56755 -101.778345)
			(xy 95.583063 -101.836238) (xy 95.590886 -101.89566) (xy 95.590886 -101.955596) (xy 95.583063 -102.015018)
			(xy 95.56755 -102.072911) (xy 95.544614 -102.128284) (xy 95.514647 -102.18019) (xy 95.47816 -102.22774)
			(xy 95.43578 -102.27012) (xy 95.38823 -102.306607) (xy 95.336324 -102.336574) (xy 95.280951 -102.35951)
			(xy 95.223058 -102.375023) (xy 95.163636 -102.382846) (xy 95.1037 -102.382846) (xy 95.044278 -102.375023)
			(xy 94.986385 -102.35951) (xy 94.931012 -102.336574) (xy 94.879106 -102.306607) (xy 94.831556 -102.27012)
			(xy 94.789176 -102.22774) (xy 94.752689 -102.18019) (xy 94.722722 -102.128284) (xy 94.699786 -102.072911)
			(xy 94.684273 -102.015018) (xy 94.67645 -101.955596) (xy 92.85985 -101.955596) (xy 92.860945 -101.959682)
			(xy 92.868768 -102.019104) (xy 92.868768 -102.07904) (xy 92.860945 -102.138462) (xy 92.845432 -102.196355)
			(xy 92.822496 -102.251728) (xy 92.792529 -102.303634) (xy 92.756042 -102.351184) (xy 92.713662 -102.393564)
			(xy 92.666112 -102.430051) (xy 92.614206 -102.460018) (xy 92.558833 -102.482954) (xy 92.50094 -102.498467)
			(xy 92.441518 -102.50629) (xy 92.381582 -102.50629) (xy 92.32216 -102.498467) (xy 92.264267 -102.482954)
			(xy 92.208894 -102.460018) (xy 92.156988 -102.430051) (xy 92.109438 -102.393564) (xy 92.067058 -102.351184)
			(xy 92.030571 -102.303634) (xy 92.000604 -102.251728) (xy 91.977668 -102.196355) (xy 91.962155 -102.138462)
			(xy 91.954332 -102.07904) (xy 87.347047 -102.07904) (xy 87.342033 -102.117126) (xy 87.32652 -102.175019)
			(xy 87.303584 -102.230392) (xy 87.273617 -102.282298) (xy 87.23713 -102.329848) (xy 87.19475 -102.372228)
			(xy 87.1472 -102.408715) (xy 87.095294 -102.438682) (xy 87.039921 -102.461618) (xy 86.982028 -102.477131)
			(xy 86.922606 -102.484954) (xy 86.86267 -102.484954) (xy 86.803248 -102.477131) (xy 86.745355 -102.461618)
			(xy 86.689982 -102.438682) (xy 86.638076 -102.408715) (xy 86.590526 -102.372228) (xy 86.548146 -102.329848)
			(xy 86.511659 -102.282298) (xy 86.481692 -102.230392) (xy 86.458756 -102.175019) (xy 86.443243 -102.117126)
			(xy 86.43542 -102.057704) (xy 43.120564 -102.057704) (xy 43.120564 -102.65435) (xy 84.76537 -102.65435)
			(xy 84.76537 -102.594414) (xy 84.773193 -102.534992) (xy 84.788706 -102.477099) (xy 84.811642 -102.421726)
			(xy 84.841609 -102.36982) (xy 84.878096 -102.32227) (xy 84.920476 -102.27989) (xy 84.968026 -102.243403)
			(xy 85.019932 -102.213436) (xy 85.075305 -102.1905) (xy 85.133198 -102.174987) (xy 85.19262 -102.167164)
			(xy 85.222588 -102.166674) (xy 85.252556 -102.167164) (xy 85.311978 -102.174987) (xy 85.369871 -102.1905)
			(xy 85.425244 -102.213436) (xy 85.47715 -102.243403) (xy 85.5247 -102.27989) (xy 85.56708 -102.32227)
			(xy 85.603567 -102.36982) (xy 85.633534 -102.421726) (xy 85.65647 -102.477099) (xy 85.671983 -102.534992)
			(xy 85.679806 -102.594414) (xy 85.679806 -102.65435) (xy 85.671983 -102.713772) (xy 85.669189 -102.7242)
			(xy 93.24516 -102.7242) (xy 93.24516 -102.664264) (xy 93.252983 -102.604842) (xy 93.268496 -102.546949)
			(xy 93.291432 -102.491576) (xy 93.321399 -102.43967) (xy 93.357886 -102.39212) (xy 93.400266 -102.34974)
			(xy 93.447816 -102.313253) (xy 93.499722 -102.283286) (xy 93.555095 -102.26035) (xy 93.612988 -102.244837)
			(xy 93.67241 -102.237014) (xy 93.702378 -102.236524) (xy 93.732346 -102.237014) (xy 93.791768 -102.244837)
			(xy 93.849661 -102.26035) (xy 93.905034 -102.283286) (xy 93.95694 -102.313253) (xy 94.00449 -102.34974)
			(xy 94.04687 -102.39212) (xy 94.083357 -102.43967) (xy 94.113324 -102.491576) (xy 94.13626 -102.546949)
			(xy 94.151773 -102.604842) (xy 94.157154 -102.645714) (xy 96.285794 -102.645714) (xy 96.285794 -102.585778)
			(xy 96.293617 -102.526356) (xy 96.30913 -102.468463) (xy 96.332066 -102.41309) (xy 96.362033 -102.361184)
			(xy 96.39852 -102.313634) (xy 96.4409 -102.271254) (xy 96.48845 -102.234767) (xy 96.540356 -102.2048)
			(xy 96.595729 -102.181864) (xy 96.653622 -102.166351) (xy 96.713044 -102.158528) (xy 96.743012 -102.158038)
			(xy 96.77298 -102.158528) (xy 96.832402 -102.166351) (xy 96.890295 -102.181864) (xy 96.945668 -102.2048)
			(xy 96.997574 -102.234767) (xy 97.045124 -102.271254) (xy 97.087504 -102.313634) (xy 97.123991 -102.361184)
			(xy 97.153958 -102.41309) (xy 97.176894 -102.468463) (xy 97.192407 -102.526356) (xy 97.20023 -102.585778)
			(xy 97.20023 -102.645714) (xy 97.192407 -102.705136) (xy 97.176894 -102.763029) (xy 97.153958 -102.818402)
			(xy 97.123991 -102.870308) (xy 97.087504 -102.917858) (xy 97.045124 -102.960238) (xy 96.997574 -102.996725)
			(xy 96.945668 -103.026692) (xy 96.890295 -103.049628) (xy 96.832402 -103.065141) (xy 96.77298 -103.072964)
			(xy 96.713044 -103.072964) (xy 96.653622 -103.065141) (xy 96.595729 -103.049628) (xy 96.540356 -103.026692)
			(xy 96.48845 -102.996725) (xy 96.4409 -102.960238) (xy 96.39852 -102.917858) (xy 96.362033 -102.870308)
			(xy 96.332066 -102.818402) (xy 96.30913 -102.763029) (xy 96.293617 -102.705136) (xy 96.285794 -102.645714)
			(xy 94.157154 -102.645714) (xy 94.159596 -102.664264) (xy 94.159596 -102.7242) (xy 94.151773 -102.783622)
			(xy 94.13626 -102.841515) (xy 94.113324 -102.896888) (xy 94.083357 -102.948794) (xy 94.04687 -102.996344)
			(xy 94.00449 -103.038724) (xy 93.95694 -103.075211) (xy 93.905034 -103.105178) (xy 93.849661 -103.128114)
			(xy 93.791768 -103.143627) (xy 93.732346 -103.15145) (xy 93.67241 -103.15145) (xy 93.612988 -103.143627)
			(xy 93.555095 -103.128114) (xy 93.499722 -103.105178) (xy 93.447816 -103.075211) (xy 93.400266 -103.038724)
			(xy 93.357886 -102.996344) (xy 93.321399 -102.948794) (xy 93.291432 -102.896888) (xy 93.268496 -102.841515)
			(xy 93.252983 -102.783622) (xy 93.24516 -102.7242) (xy 85.669189 -102.7242) (xy 85.65647 -102.771665)
			(xy 85.633534 -102.827038) (xy 85.603567 -102.878944) (xy 85.56708 -102.926494) (xy 85.5247 -102.968874)
			(xy 85.47715 -103.005361) (xy 85.425244 -103.035328) (xy 85.369871 -103.058264) (xy 85.311978 -103.073777)
			(xy 85.252556 -103.0816) (xy 85.19262 -103.0816) (xy 85.133198 -103.073777) (xy 85.075305 -103.058264)
			(xy 85.019932 -103.035328) (xy 84.968026 -103.005361) (xy 84.920476 -102.968874) (xy 84.878096 -102.926494)
			(xy 84.841609 -102.878944) (xy 84.811642 -102.827038) (xy 84.788706 -102.771665) (xy 84.773193 -102.713772)
			(xy 84.76537 -102.65435) (xy 43.120564 -102.65435) (xy 43.120564 -103.513483) (xy 60.260476 -103.513483)
			(xy 60.260476 -103.442161) (xy 60.268462 -103.371287) (xy 60.284332 -103.301752) (xy 60.307889 -103.234432)
			(xy 60.338834 -103.170173) (xy 60.37678 -103.109782) (xy 60.421249 -103.05402) (xy 60.471682 -103.003587)
			(xy 60.527444 -102.959118) (xy 60.587835 -102.921172) (xy 60.652094 -102.890227) (xy 60.719414 -102.86667)
			(xy 60.788949 -102.8508) (xy 60.859823 -102.842814) (xy 60.895484 -102.842314) (xy 60.931145 -102.842814)
			(xy 61.002019 -102.8508) (xy 61.071554 -102.86667) (xy 61.138874 -102.890227) (xy 61.203133 -102.921172)
			(xy 61.263524 -102.959118) (xy 61.319286 -103.003587) (xy 61.369719 -103.05402) (xy 61.414188 -103.109782)
			(xy 61.452134 -103.170173) (xy 61.483079 -103.234432) (xy 61.506636 -103.301752) (xy 61.522506 -103.371287)
			(xy 61.530492 -103.442161) (xy 61.530492 -103.513483) (xy 61.526399 -103.549805) (xy 62.538348 -103.549805)
			(xy 62.538348 -103.478483) (xy 62.546334 -103.407609) (xy 62.562204 -103.338074) (xy 62.585761 -103.270754)
			(xy 62.616706 -103.206495) (xy 62.654652 -103.146104) (xy 62.699121 -103.090342) (xy 62.749554 -103.039909)
			(xy 62.805316 -102.99544) (xy 62.865707 -102.957494) (xy 62.929966 -102.926549) (xy 62.997286 -102.902992)
			(xy 63.066821 -102.887122) (xy 63.137695 -102.879136) (xy 63.173356 -102.878636) (xy 63.209017 -102.879136)
			(xy 63.279891 -102.887122) (xy 63.349426 -102.902992) (xy 63.416746 -102.926549) (xy 63.481005 -102.957494)
			(xy 63.541396 -102.99544) (xy 63.597158 -103.039909) (xy 63.647591 -103.090342) (xy 63.69206 -103.146104)
			(xy 63.730006 -103.206495) (xy 63.760951 -103.270754) (xy 63.784508 -103.338074) (xy 63.800378 -103.407609)
			(xy 63.80521 -103.450491) (xy 64.78828 -103.450491) (xy 64.78828 -103.379169) (xy 64.796266 -103.308295)
			(xy 64.812136 -103.23876) (xy 64.835693 -103.17144) (xy 64.866638 -103.107181) (xy 64.904584 -103.04679)
			(xy 64.949053 -102.991028) (xy 64.999486 -102.940595) (xy 65.055248 -102.896126) (xy 65.115639 -102.85818)
			(xy 65.179898 -102.827235) (xy 65.247218 -102.803678) (xy 65.316753 -102.787808) (xy 65.387627 -102.779822)
			(xy 65.423288 -102.779322) (xy 65.458949 -102.779822) (xy 65.529823 -102.787808) (xy 65.599358 -102.803678)
			(xy 65.666678 -102.827235) (xy 65.730937 -102.85818) (xy 65.791328 -102.896126) (xy 65.84709 -102.940595)
			(xy 65.897523 -102.991028) (xy 65.941992 -103.04679) (xy 65.979938 -103.107181) (xy 66.010883 -103.17144)
			(xy 66.03444 -103.23876) (xy 66.05031 -103.308295) (xy 66.058296 -103.379169) (xy 66.058296 -103.450491)
			(xy 66.058267 -103.450745) (xy 66.939152 -103.450745) (xy 66.939152 -103.379423) (xy 66.947138 -103.308549)
			(xy 66.963008 -103.239014) (xy 66.986565 -103.171694) (xy 67.01751 -103.107435) (xy 67.055456 -103.047044)
			(xy 67.099925 -102.991282) (xy 67.150358 -102.940849) (xy 67.20612 -102.89638) (xy 67.266511 -102.858434)
			(xy 67.33077 -102.827489) (xy 67.39809 -102.803932) (xy 67.467625 -102.788062) (xy 67.538499 -102.780076)
			(xy 67.57416 -102.779576) (xy 67.609821 -102.780076) (xy 67.680695 -102.788062) (xy 67.75023 -102.803932)
			(xy 67.81755 -102.827489) (xy 67.881809 -102.858434) (xy 67.9422 -102.89638) (xy 67.997962 -102.940849)
			(xy 68.048395 -102.991282) (xy 68.092864 -103.047044) (xy 68.13081 -103.107435) (xy 68.161755 -103.171694)
			(xy 68.185312 -103.239014) (xy 68.201182 -103.308549) (xy 68.209168 -103.379423) (xy 68.209168 -103.450745)
			(xy 68.205075 -103.487067) (xy 69.095866 -103.487067) (xy 69.095866 -103.415745) (xy 69.103852 -103.344871)
			(xy 69.119722 -103.275336) (xy 69.143279 -103.208016) (xy 69.174224 -103.143757) (xy 69.21217 -103.083366)
			(xy 69.256639 -103.027604) (xy 69.307072 -102.977171) (xy 69.362834 -102.932702) (xy 69.423225 -102.894756)
			(xy 69.487484 -102.863811) (xy 69.554804 -102.840254) (xy 69.624339 -102.824384) (xy 69.695213 -102.816398)
			(xy 69.730874 -102.815898) (xy 69.766535 -102.816398) (xy 69.837409 -102.824384) (xy 69.906944 -102.840254)
			(xy 69.974264 -102.863811) (xy 70.038523 -102.894756) (xy 70.098914 -102.932702) (xy 70.154676 -102.977171)
			(xy 70.205109 -103.027604) (xy 70.249578 -103.083366) (xy 70.287524 -103.143757) (xy 70.318469 -103.208016)
			(xy 70.342026 -103.275336) (xy 70.357896 -103.344871) (xy 70.360913 -103.371646) (xy 94.65105 -103.371646)
			(xy 94.65105 -103.31171) (xy 94.658873 -103.252288) (xy 94.674386 -103.194395) (xy 94.697322 -103.139022)
			(xy 94.727289 -103.087116) (xy 94.763776 -103.039566) (xy 94.806156 -102.997186) (xy 94.853706 -102.960699)
			(xy 94.905612 -102.930732) (xy 94.960985 -102.907796) (xy 95.018878 -102.892283) (xy 95.0783 -102.88446)
			(xy 95.108268 -102.88397) (xy 95.138236 -102.88446) (xy 95.197658 -102.892283) (xy 95.255551 -102.907796)
			(xy 95.310924 -102.930732) (xy 95.36283 -102.960699) (xy 95.41038 -102.997186) (xy 95.45276 -103.039566)
			(xy 95.489247 -103.087116) (xy 95.519214 -103.139022) (xy 95.54215 -103.194395) (xy 95.557663 -103.252288)
			(xy 95.565486 -103.31171) (xy 95.565486 -103.371646) (xy 95.557663 -103.431068) (xy 95.54215 -103.488961)
			(xy 95.519214 -103.544334) (xy 95.489247 -103.59624) (xy 95.45276 -103.64379) (xy 95.41038 -103.68617)
			(xy 95.36283 -103.722657) (xy 95.310924 -103.752624) (xy 95.255551 -103.77556) (xy 95.197658 -103.791073)
			(xy 95.138236 -103.798896) (xy 95.0783 -103.798896) (xy 95.018878 -103.791073) (xy 94.960985 -103.77556)
			(xy 94.905612 -103.752624) (xy 94.853706 -103.722657) (xy 94.806156 -103.68617) (xy 94.763776 -103.64379)
			(xy 94.727289 -103.59624) (xy 94.697322 -103.544334) (xy 94.674386 -103.488961) (xy 94.658873 -103.431068)
			(xy 94.65105 -103.371646) (xy 70.360913 -103.371646) (xy 70.365882 -103.415745) (xy 70.365882 -103.487067)
			(xy 70.357896 -103.557941) (xy 70.342026 -103.627476) (xy 70.318469 -103.694796) (xy 70.287524 -103.759055)
			(xy 70.249578 -103.819446) (xy 70.205109 -103.875208) (xy 70.154676 -103.925641) (xy 70.098914 -103.97011)
			(xy 70.097765 -103.970832) (xy 83.096082 -103.970832) (xy 83.096082 -103.910896) (xy 83.103905 -103.851474)
			(xy 83.119418 -103.793581) (xy 83.142354 -103.738208) (xy 83.172321 -103.686302) (xy 83.208808 -103.638752)
			(xy 83.251188 -103.596372) (xy 83.298738 -103.559885) (xy 83.350644 -103.529918) (xy 83.406017 -103.506982)
			(xy 83.46391 -103.491469) (xy 83.523332 -103.483646) (xy 83.5533 -103.483156) (xy 83.583268 -103.483646)
			(xy 83.64269 -103.491469) (xy 83.700583 -103.506982) (xy 83.755956 -103.529918) (xy 83.807862 -103.559885)
			(xy 83.855412 -103.596372) (xy 83.897792 -103.638752) (xy 83.934279 -103.686302) (xy 83.964246 -103.738208)
			(xy 83.987182 -103.793581) (xy 84.002695 -103.851474) (xy 84.010518 -103.910896) (xy 84.010518 -103.970832)
			(xy 84.002695 -104.030254) (xy 83.987182 -104.088147) (xy 83.964246 -104.14352) (xy 83.934279 -104.195426)
			(xy 83.897792 -104.242976) (xy 83.855412 -104.285356) (xy 83.807862 -104.321843) (xy 83.755956 -104.35181)
			(xy 83.700583 -104.374746) (xy 83.64269 -104.390259) (xy 83.583268 -104.398082) (xy 83.523332 -104.398082)
			(xy 83.46391 -104.390259) (xy 83.406017 -104.374746) (xy 83.350644 -104.35181) (xy 83.298738 -104.321843)
			(xy 83.251188 -104.285356) (xy 83.208808 -104.242976) (xy 83.172321 -104.195426) (xy 83.142354 -104.14352)
			(xy 83.119418 -104.088147) (xy 83.103905 -104.030254) (xy 83.096082 -103.970832) (xy 70.097765 -103.970832)
			(xy 70.038523 -104.008056) (xy 69.974264 -104.039001) (xy 69.906944 -104.062558) (xy 69.837409 -104.078428)
			(xy 69.766535 -104.086414) (xy 69.695213 -104.086414) (xy 69.624339 -104.078428) (xy 69.554804 -104.062558)
			(xy 69.487484 -104.039001) (xy 69.423225 -104.008056) (xy 69.362834 -103.97011) (xy 69.307072 -103.925641)
			(xy 69.256639 -103.875208) (xy 69.21217 -103.819446) (xy 69.174224 -103.759055) (xy 69.143279 -103.694796)
			(xy 69.119722 -103.627476) (xy 69.103852 -103.557941) (xy 69.095866 -103.487067) (xy 68.205075 -103.487067)
			(xy 68.201182 -103.521619) (xy 68.185312 -103.591154) (xy 68.161755 -103.658474) (xy 68.13081 -103.722733)
			(xy 68.092864 -103.783124) (xy 68.048395 -103.838886) (xy 67.997962 -103.889319) (xy 67.9422 -103.933788)
			(xy 67.881809 -103.971734) (xy 67.81755 -104.002679) (xy 67.75023 -104.026236) (xy 67.680695 -104.042106)
			(xy 67.609821 -104.050092) (xy 67.538499 -104.050092) (xy 67.467625 -104.042106) (xy 67.39809 -104.026236)
			(xy 67.33077 -104.002679) (xy 67.266511 -103.971734) (xy 67.20612 -103.933788) (xy 67.150358 -103.889319)
			(xy 67.099925 -103.838886) (xy 67.055456 -103.783124) (xy 67.01751 -103.722733) (xy 66.986565 -103.658474)
			(xy 66.963008 -103.591154) (xy 66.947138 -103.521619) (xy 66.939152 -103.450745) (xy 66.058267 -103.450745)
			(xy 66.05031 -103.521365) (xy 66.03444 -103.5909) (xy 66.010883 -103.65822) (xy 65.979938 -103.722479)
			(xy 65.941992 -103.78287) (xy 65.897523 -103.838632) (xy 65.84709 -103.889065) (xy 65.791328 -103.933534)
			(xy 65.730937 -103.97148) (xy 65.666678 -104.002425) (xy 65.599358 -104.025982) (xy 65.529823 -104.041852)
			(xy 65.458949 -104.049838) (xy 65.387627 -104.049838) (xy 65.316753 -104.041852) (xy 65.247218 -104.025982)
			(xy 65.179898 -104.002425) (xy 65.115639 -103.97148) (xy 65.055248 -103.933534) (xy 64.999486 -103.889065)
			(xy 64.949053 -103.838632) (xy 64.904584 -103.78287) (xy 64.866638 -103.722479) (xy 64.835693 -103.65822)
			(xy 64.812136 -103.5909) (xy 64.796266 -103.521365) (xy 64.78828 -103.450491) (xy 63.80521 -103.450491)
			(xy 63.808364 -103.478483) (xy 63.808364 -103.549805) (xy 63.800378 -103.620679) (xy 63.784508 -103.690214)
			(xy 63.760951 -103.757534) (xy 63.730006 -103.821793) (xy 63.69206 -103.882184) (xy 63.647591 -103.937946)
			(xy 63.597158 -103.988379) (xy 63.541396 -104.032848) (xy 63.481005 -104.070794) (xy 63.416746 -104.101739)
			(xy 63.349426 -104.125296) (xy 63.279891 -104.141166) (xy 63.209017 -104.149152) (xy 63.137695 -104.149152)
			(xy 63.066821 -104.141166) (xy 62.997286 -104.125296) (xy 62.929966 -104.101739) (xy 62.865707 -104.070794)
			(xy 62.805316 -104.032848) (xy 62.749554 -103.988379) (xy 62.699121 -103.937946) (xy 62.654652 -103.882184)
			(xy 62.616706 -103.821793) (xy 62.585761 -103.757534) (xy 62.562204 -103.690214) (xy 62.546334 -103.620679)
			(xy 62.538348 -103.549805) (xy 61.526399 -103.549805) (xy 61.522506 -103.584357) (xy 61.506636 -103.653892)
			(xy 61.483079 -103.721212) (xy 61.452134 -103.785471) (xy 61.414188 -103.845862) (xy 61.369719 -103.901624)
			(xy 61.319286 -103.952057) (xy 61.263524 -103.996526) (xy 61.203133 -104.034472) (xy 61.138874 -104.065417)
			(xy 61.071554 -104.088974) (xy 61.002019 -104.104844) (xy 60.931145 -104.11283) (xy 60.859823 -104.11283)
			(xy 60.788949 -104.104844) (xy 60.719414 -104.088974) (xy 60.652094 -104.065417) (xy 60.587835 -104.034472)
			(xy 60.527444 -103.996526) (xy 60.471682 -103.952057) (xy 60.421249 -103.901624) (xy 60.37678 -103.845862)
			(xy 60.338834 -103.785471) (xy 60.307889 -103.721212) (xy 60.284332 -103.653892) (xy 60.268462 -103.584357)
			(xy 60.260476 -103.513483) (xy 43.120564 -103.513483) (xy 43.120564 -105.181396) (xy 82.396566 -105.181396)
			(xy 82.396566 -105.12146) (xy 82.404389 -105.062038) (xy 82.419902 -105.004145) (xy 82.442838 -104.948772)
			(xy 82.472805 -104.896866) (xy 82.509292 -104.849316) (xy 82.551672 -104.806936) (xy 82.599222 -104.770449)
			(xy 82.651128 -104.740482) (xy 82.706501 -104.717546) (xy 82.764394 -104.702033) (xy 82.823816 -104.69421)
			(xy 82.853784 -104.69372) (xy 82.883752 -104.69421) (xy 82.943174 -104.702033) (xy 83.001067 -104.717546)
			(xy 83.05644 -104.740482) (xy 83.108346 -104.770449) (xy 83.155896 -104.806936) (xy 83.198276 -104.849316)
			(xy 83.234763 -104.896866) (xy 83.26473 -104.948772) (xy 83.287666 -105.004145) (xy 83.303179 -105.062038)
			(xy 83.311002 -105.12146) (xy 83.311002 -105.181396) (xy 83.303179 -105.240818) (xy 83.287666 -105.298711)
			(xy 83.26473 -105.354084) (xy 83.234763 -105.40599) (xy 83.198276 -105.45354) (xy 83.155896 -105.49592)
			(xy 83.108346 -105.532407) (xy 83.05644 -105.562374) (xy 83.001067 -105.58531) (xy 82.943174 -105.600823)
			(xy 82.883752 -105.608646) (xy 82.823816 -105.608646) (xy 82.764394 -105.600823) (xy 82.706501 -105.58531)
			(xy 82.651128 -105.562374) (xy 82.599222 -105.532407) (xy 82.551672 -105.49592) (xy 82.509292 -105.45354)
			(xy 82.472805 -105.40599) (xy 82.442838 -105.354084) (xy 82.419902 -105.298711) (xy 82.404389 -105.240818)
			(xy 82.396566 -105.181396) (xy 43.120564 -105.181396) (xy 43.120564 -106.181753) (xy 60.260476 -106.181753)
			(xy 60.260476 -106.110431) (xy 60.268462 -106.039557) (xy 60.284332 -105.970022) (xy 60.307889 -105.902702)
			(xy 60.338834 -105.838443) (xy 60.37678 -105.778052) (xy 60.421249 -105.72229) (xy 60.471682 -105.671857)
			(xy 60.527444 -105.627388) (xy 60.587835 -105.589442) (xy 60.652094 -105.558497) (xy 60.719414 -105.53494)
			(xy 60.788949 -105.51907) (xy 60.859823 -105.511084) (xy 60.895484 -105.510584) (xy 60.931145 -105.511084)
			(xy 61.002019 -105.51907) (xy 61.071554 -105.53494) (xy 61.138874 -105.558497) (xy 61.203133 -105.589442)
			(xy 61.263524 -105.627388) (xy 61.319286 -105.671857) (xy 61.369719 -105.72229) (xy 61.414188 -105.778052)
			(xy 61.452134 -105.838443) (xy 61.483079 -105.902702) (xy 61.506636 -105.970022) (xy 61.522506 -106.039557)
			(xy 61.530492 -106.110431) (xy 61.530492 -106.181753) (xy 61.526399 -106.218075) (xy 62.538348 -106.218075)
			(xy 62.538348 -106.146753) (xy 62.546334 -106.075879) (xy 62.562204 -106.006344) (xy 62.585761 -105.939024)
			(xy 62.616706 -105.874765) (xy 62.654652 -105.814374) (xy 62.699121 -105.758612) (xy 62.749554 -105.708179)
			(xy 62.805316 -105.66371) (xy 62.865707 -105.625764) (xy 62.929966 -105.594819) (xy 62.997286 -105.571262)
			(xy 63.066821 -105.555392) (xy 63.137695 -105.547406) (xy 63.173356 -105.546906) (xy 63.209017 -105.547406)
			(xy 63.279891 -105.555392) (xy 63.349426 -105.571262) (xy 63.416746 -105.594819) (xy 63.481005 -105.625764)
			(xy 63.541396 -105.66371) (xy 63.597158 -105.708179) (xy 63.647591 -105.758612) (xy 63.69206 -105.814374)
			(xy 63.730006 -105.874765) (xy 63.760951 -105.939024) (xy 63.784508 -106.006344) (xy 63.800378 -106.075879)
			(xy 63.80521 -106.118761) (xy 64.78828 -106.118761) (xy 64.78828 -106.047439) (xy 64.796266 -105.976565)
			(xy 64.812136 -105.90703) (xy 64.835693 -105.83971) (xy 64.866638 -105.775451) (xy 64.904584 -105.71506)
			(xy 64.949053 -105.659298) (xy 64.999486 -105.608865) (xy 65.055248 -105.564396) (xy 65.115639 -105.52645)
			(xy 65.179898 -105.495505) (xy 65.247218 -105.471948) (xy 65.316753 -105.456078) (xy 65.387627 -105.448092)
			(xy 65.423288 -105.447592) (xy 65.458949 -105.448092) (xy 65.529823 -105.456078) (xy 65.599358 -105.471948)
			(xy 65.666678 -105.495505) (xy 65.730937 -105.52645) (xy 65.791328 -105.564396) (xy 65.84709 -105.608865)
			(xy 65.897523 -105.659298) (xy 65.941992 -105.71506) (xy 65.979938 -105.775451) (xy 66.010883 -105.83971)
			(xy 66.03444 -105.90703) (xy 66.05031 -105.976565) (xy 66.058296 -106.047439) (xy 66.058296 -106.118761)
			(xy 66.058267 -106.119015) (xy 66.939152 -106.119015) (xy 66.939152 -106.047693) (xy 66.947138 -105.976819)
			(xy 66.963008 -105.907284) (xy 66.986565 -105.839964) (xy 67.01751 -105.775705) (xy 67.055456 -105.715314)
			(xy 67.099925 -105.659552) (xy 67.150358 -105.609119) (xy 67.20612 -105.56465) (xy 67.266511 -105.526704)
			(xy 67.33077 -105.495759) (xy 67.39809 -105.472202) (xy 67.467625 -105.456332) (xy 67.538499 -105.448346)
			(xy 67.57416 -105.447846) (xy 67.609821 -105.448346) (xy 67.680695 -105.456332) (xy 67.75023 -105.472202)
			(xy 67.81755 -105.495759) (xy 67.881809 -105.526704) (xy 67.9422 -105.56465) (xy 67.997962 -105.609119)
			(xy 68.048395 -105.659552) (xy 68.092864 -105.715314) (xy 68.13081 -105.775705) (xy 68.161755 -105.839964)
			(xy 68.185312 -105.907284) (xy 68.201182 -105.976819) (xy 68.209168 -106.047693) (xy 68.209168 -106.119015)
			(xy 68.205075 -106.155337) (xy 69.095866 -106.155337) (xy 69.095866 -106.084015) (xy 69.103852 -106.013141)
			(xy 69.119722 -105.943606) (xy 69.143279 -105.876286) (xy 69.174224 -105.812027) (xy 69.21217 -105.751636)
			(xy 69.256639 -105.695874) (xy 69.307072 -105.645441) (xy 69.362834 -105.600972) (xy 69.423225 -105.563026)
			(xy 69.487484 -105.532081) (xy 69.554804 -105.508524) (xy 69.624339 -105.492654) (xy 69.695213 -105.484668)
			(xy 69.730874 -105.484168) (xy 69.766535 -105.484668) (xy 69.837409 -105.492654) (xy 69.906944 -105.508524)
			(xy 69.974264 -105.532081) (xy 70.038523 -105.563026) (xy 70.098914 -105.600972) (xy 70.154676 -105.645441)
			(xy 70.205109 -105.695874) (xy 70.249578 -105.751636) (xy 70.287524 -105.812027) (xy 70.318469 -105.876286)
			(xy 70.342026 -105.943606) (xy 70.357896 -106.013141) (xy 70.365882 -106.084015) (xy 70.365882 -106.155337)
			(xy 70.357896 -106.226211) (xy 70.345284 -106.28147) (xy 81.664284 -106.28147) (xy 81.664284 -106.221534)
			(xy 81.672107 -106.162112) (xy 81.68762 -106.104219) (xy 81.710556 -106.048846) (xy 81.740523 -105.99694)
			(xy 81.77701 -105.94939) (xy 81.81939 -105.90701) (xy 81.86694 -105.870523) (xy 81.918846 -105.840556)
			(xy 81.974219 -105.81762) (xy 82.032112 -105.802107) (xy 82.091534 -105.794284) (xy 82.121502 -105.793794)
			(xy 82.15147 -105.794284) (xy 82.210892 -105.802107) (xy 82.268785 -105.81762) (xy 82.324158 -105.840556)
			(xy 82.376064 -105.870523) (xy 82.423614 -105.90701) (xy 82.465994 -105.94939) (xy 82.502481 -105.99694)
			(xy 82.532448 -106.048846) (xy 82.555384 -106.104219) (xy 82.570897 -106.162112) (xy 82.57872 -106.221534)
			(xy 82.57872 -106.28147) (xy 82.570897 -106.340892) (xy 82.555384 -106.398785) (xy 82.532448 -106.454158)
			(xy 82.502481 -106.506064) (xy 82.465994 -106.553614) (xy 82.423614 -106.595994) (xy 82.376064 -106.632481)
			(xy 82.324158 -106.662448) (xy 82.268785 -106.685384) (xy 82.210892 -106.700897) (xy 82.15147 -106.70872)
			(xy 82.091534 -106.70872) (xy 82.032112 -106.700897) (xy 81.974219 -106.685384) (xy 81.918846 -106.662448)
			(xy 81.86694 -106.632481) (xy 81.81939 -106.595994) (xy 81.77701 -106.553614) (xy 81.740523 -106.506064)
			(xy 81.710556 -106.454158) (xy 81.68762 -106.398785) (xy 81.672107 -106.340892) (xy 81.664284 -106.28147)
			(xy 70.345284 -106.28147) (xy 70.342026 -106.295746) (xy 70.318469 -106.363066) (xy 70.287524 -106.427325)
			(xy 70.249578 -106.487716) (xy 70.205109 -106.543478) (xy 70.154676 -106.593911) (xy 70.098914 -106.63838)
			(xy 70.038523 -106.676326) (xy 69.974264 -106.707271) (xy 69.906944 -106.730828) (xy 69.837409 -106.746698)
			(xy 69.766535 -106.754684) (xy 69.695213 -106.754684) (xy 69.624339 -106.746698) (xy 69.554804 -106.730828)
			(xy 69.487484 -106.707271) (xy 69.423225 -106.676326) (xy 69.362834 -106.63838) (xy 69.307072 -106.593911)
			(xy 69.256639 -106.543478) (xy 69.21217 -106.487716) (xy 69.174224 -106.427325) (xy 69.143279 -106.363066)
			(xy 69.119722 -106.295746) (xy 69.103852 -106.226211) (xy 69.095866 -106.155337) (xy 68.205075 -106.155337)
			(xy 68.201182 -106.189889) (xy 68.185312 -106.259424) (xy 68.161755 -106.326744) (xy 68.13081 -106.391003)
			(xy 68.092864 -106.451394) (xy 68.048395 -106.507156) (xy 67.997962 -106.557589) (xy 67.9422 -106.602058)
			(xy 67.881809 -106.640004) (xy 67.81755 -106.670949) (xy 67.75023 -106.694506) (xy 67.680695 -106.710376)
			(xy 67.609821 -106.718362) (xy 67.538499 -106.718362) (xy 67.467625 -106.710376) (xy 67.39809 -106.694506)
			(xy 67.33077 -106.670949) (xy 67.266511 -106.640004) (xy 67.20612 -106.602058) (xy 67.150358 -106.557589)
			(xy 67.099925 -106.507156) (xy 67.055456 -106.451394) (xy 67.01751 -106.391003) (xy 66.986565 -106.326744)
			(xy 66.963008 -106.259424) (xy 66.947138 -106.189889) (xy 66.939152 -106.119015) (xy 66.058267 -106.119015)
			(xy 66.05031 -106.189635) (xy 66.03444 -106.25917) (xy 66.010883 -106.32649) (xy 65.979938 -106.390749)
			(xy 65.941992 -106.45114) (xy 65.897523 -106.506902) (xy 65.84709 -106.557335) (xy 65.791328 -106.601804)
			(xy 65.730937 -106.63975) (xy 65.666678 -106.670695) (xy 65.599358 -106.694252) (xy 65.529823 -106.710122)
			(xy 65.458949 -106.718108) (xy 65.387627 -106.718108) (xy 65.316753 -106.710122) (xy 65.247218 -106.694252)
			(xy 65.179898 -106.670695) (xy 65.115639 -106.63975) (xy 65.055248 -106.601804) (xy 64.999486 -106.557335)
			(xy 64.949053 -106.506902) (xy 64.904584 -106.45114) (xy 64.866638 -106.390749) (xy 64.835693 -106.32649)
			(xy 64.812136 -106.25917) (xy 64.796266 -106.189635) (xy 64.78828 -106.118761) (xy 63.80521 -106.118761)
			(xy 63.808364 -106.146753) (xy 63.808364 -106.218075) (xy 63.800378 -106.288949) (xy 63.784508 -106.358484)
			(xy 63.760951 -106.425804) (xy 63.730006 -106.490063) (xy 63.69206 -106.550454) (xy 63.647591 -106.606216)
			(xy 63.597158 -106.656649) (xy 63.541396 -106.701118) (xy 63.481005 -106.739064) (xy 63.416746 -106.770009)
			(xy 63.349426 -106.793566) (xy 63.279891 -106.809436) (xy 63.209017 -106.817422) (xy 63.137695 -106.817422)
			(xy 63.066821 -106.809436) (xy 62.997286 -106.793566) (xy 62.929966 -106.770009) (xy 62.865707 -106.739064)
			(xy 62.805316 -106.701118) (xy 62.749554 -106.656649) (xy 62.699121 -106.606216) (xy 62.654652 -106.550454)
			(xy 62.616706 -106.490063) (xy 62.585761 -106.425804) (xy 62.562204 -106.358484) (xy 62.546334 -106.288949)
			(xy 62.538348 -106.218075) (xy 61.526399 -106.218075) (xy 61.522506 -106.252627) (xy 61.506636 -106.322162)
			(xy 61.483079 -106.389482) (xy 61.452134 -106.453741) (xy 61.414188 -106.514132) (xy 61.369719 -106.569894)
			(xy 61.319286 -106.620327) (xy 61.263524 -106.664796) (xy 61.203133 -106.702742) (xy 61.138874 -106.733687)
			(xy 61.071554 -106.757244) (xy 61.002019 -106.773114) (xy 60.931145 -106.7811) (xy 60.859823 -106.7811)
			(xy 60.788949 -106.773114) (xy 60.719414 -106.757244) (xy 60.652094 -106.733687) (xy 60.587835 -106.702742)
			(xy 60.527444 -106.664796) (xy 60.471682 -106.620327) (xy 60.421249 -106.569894) (xy 60.37678 -106.514132)
			(xy 60.338834 -106.453741) (xy 60.307889 -106.389482) (xy 60.284332 -106.322162) (xy 60.268462 -106.252627)
			(xy 60.260476 -106.181753) (xy 43.120564 -106.181753) (xy 43.120564 -106.29392) (xy 50.87366 -106.29392)
			(xy 52.525168 -106.29392) (xy 52.525168 -107.529118) (xy 81.071702 -107.529118) (xy 81.071702 -107.469182)
			(xy 81.079525 -107.40976) (xy 81.095038 -107.351867) (xy 81.117974 -107.296494) (xy 81.147941 -107.244588)
			(xy 81.184428 -107.197038) (xy 81.226808 -107.154658) (xy 81.274358 -107.118171) (xy 81.326264 -107.088204)
			(xy 81.381637 -107.065268) (xy 81.43953 -107.049755) (xy 81.498952 -107.041932) (xy 81.52892 -107.041442)
			(xy 81.558888 -107.041932) (xy 81.61831 -107.049755) (xy 81.676203 -107.065268) (xy 81.731576 -107.088204)
			(xy 81.783482 -107.118171) (xy 81.831032 -107.154658) (xy 81.873412 -107.197038) (xy 81.909899 -107.244588)
			(xy 81.939866 -107.296494) (xy 81.962802 -107.351867) (xy 81.978315 -107.40976) (xy 81.986138 -107.469182)
			(xy 81.986138 -107.529118) (xy 81.978315 -107.58854) (xy 81.962802 -107.646433) (xy 81.939866 -107.701806)
			(xy 81.909899 -107.753712) (xy 81.873412 -107.801262) (xy 81.831032 -107.843642) (xy 81.783482 -107.880129)
			(xy 81.731576 -107.910096) (xy 81.676203 -107.933032) (xy 81.61831 -107.948545) (xy 81.558888 -107.956368)
			(xy 81.498952 -107.956368) (xy 81.43953 -107.948545) (xy 81.381637 -107.933032) (xy 81.326264 -107.910096)
			(xy 81.274358 -107.880129) (xy 81.226808 -107.843642) (xy 81.184428 -107.801262) (xy 81.147941 -107.753712)
			(xy 81.117974 -107.701806) (xy 81.095038 -107.646433) (xy 81.079525 -107.58854) (xy 81.071702 -107.529118)
			(xy 52.525168 -107.529118) (xy 52.525168 -107.945936) (xy 50.87366 -107.945936) (xy 50.87366 -106.29392)
			(xy 43.120564 -106.29392) (xy 43.120564 -108.960411) (xy 86.399122 -108.960411) (xy 86.401115 -108.760283)
			(xy 86.411112 -108.560394) (xy 86.429099 -108.361066) (xy 86.455047 -108.162617) (xy 86.488914 -107.965365)
			(xy 86.530646 -107.769626) (xy 86.580175 -107.575713) (xy 86.637424 -107.383938) (xy 86.702299 -107.194606)
			(xy 86.774698 -107.008022) (xy 86.854504 -106.824483) (xy 86.941589 -106.644285) (xy 87.035814 -106.467715)
			(xy 87.137028 -106.295056) (xy 87.245069 -106.126586) (xy 87.359764 -105.962572) (xy 87.48093 -105.803279)
			(xy 87.608371 -105.648962) (xy 87.741885 -105.499866) (xy 87.881257 -105.356232) (xy 88.026264 -105.21829)
			(xy 88.176675 -105.086259) (xy 88.332247 -104.960352) (xy 88.492732 -104.84077) (xy 88.657873 -104.727705)
			(xy 88.827405 -104.621337) (xy 89.001058 -104.521838) (xy 89.178552 -104.429366) (xy 89.359604 -104.34407)
			(xy 89.543924 -104.266086) (xy 89.731216 -104.195538) (xy 89.921181 -104.132541) (xy 90.113514 -104.077195)
			(xy 90.307908 -104.029588) (xy 90.504051 -103.989797) (xy 90.701628 -103.957885) (xy 90.900325 -103.933904)
			(xy 91.099821 -103.917891) (xy 91.299799 -103.909874) (xy 91.399868 -103.909368) (xy 91.499937 -103.909864)
			(xy 91.699915 -103.917861) (xy 91.899414 -103.933853) (xy 92.098112 -103.957814) (xy 92.295693 -103.989706)
			(xy 92.49184 -104.029477) (xy 92.686239 -104.077064) (xy 92.878578 -104.132391) (xy 93.068549 -104.195369)
			(xy 93.076641 -104.198416) (xy 96.220008 -104.198416) (xy 96.220008 -104.13848) (xy 96.227831 -104.079058)
			(xy 96.243344 -104.021165) (xy 96.26628 -103.965792) (xy 96.296247 -103.913886) (xy 96.332734 -103.866336)
			(xy 96.375114 -103.823956) (xy 96.422664 -103.787469) (xy 96.47457 -103.757502) (xy 96.529943 -103.734566)
			(xy 96.587836 -103.719053) (xy 96.647258 -103.71123) (xy 96.677226 -103.71074) (xy 96.707194 -103.71123)
			(xy 96.766616 -103.719053) (xy 96.824509 -103.734566) (xy 96.879882 -103.757502) (xy 96.931788 -103.787469)
			(xy 96.979338 -103.823956) (xy 97.021718 -103.866336) (xy 97.058205 -103.913886) (xy 97.088172 -103.965792)
			(xy 97.111108 -104.021165) (xy 97.126621 -104.079058) (xy 97.134444 -104.13848) (xy 97.134444 -104.198416)
			(xy 97.126621 -104.257838) (xy 97.111108 -104.315731) (xy 97.088172 -104.371104) (xy 97.058205 -104.42301)
			(xy 97.021718 -104.47056) (xy 96.979338 -104.51294) (xy 96.931788 -104.549427) (xy 96.879882 -104.579394)
			(xy 96.824509 -104.60233) (xy 96.766616 -104.617843) (xy 96.707194 -104.625666) (xy 96.647258 -104.625666)
			(xy 96.587836 -104.617843) (xy 96.529943 -104.60233) (xy 96.47457 -104.579394) (xy 96.422664 -104.549427)
			(xy 96.375114 -104.51294) (xy 96.332734 -104.47056) (xy 96.296247 -104.42301) (xy 96.26628 -104.371104)
			(xy 96.243344 -104.315731) (xy 96.227831 -104.257838) (xy 96.220008 -104.198416) (xy 93.076641 -104.198416)
			(xy 93.255848 -104.265897) (xy 93.440176 -104.343863) (xy 93.621237 -104.429141) (xy 93.79874 -104.521594)
			(xy 93.972403 -104.621076) (xy 94.141946 -104.727426) (xy 94.307099 -104.840475) (xy 94.467596 -104.96004)
			(xy 94.623181 -105.085932) (xy 94.773605 -105.217947) (xy 94.918626 -105.355875) (xy 95.058012 -105.499495)
			(xy 95.191541 -105.648576) (xy 95.318999 -105.802881) (xy 95.44018 -105.962162) (xy 95.554892 -106.126163)
			(xy 95.66295 -106.294623) (xy 95.764182 -106.467272) (xy 95.858425 -106.643832) (xy 95.945528 -106.824022)
			(xy 96.025353 -107.007552) (xy 96.09777 -107.194129) (xy 96.162665 -107.383454) (xy 96.219933 -107.575224)
			(xy 96.269483 -107.769131) (xy 96.311234 -107.964866) (xy 96.345121 -108.162115) (xy 96.371089 -108.360561)
			(xy 96.389096 -108.559888) (xy 96.399114 -108.759775) (xy 96.401127 -108.959903) (xy 96.395131 -109.159951)
			(xy 96.381135 -109.3596) (xy 96.359164 -109.558528) (xy 96.32925 -109.756418) (xy 96.291443 -109.952953)
			(xy 96.245804 -110.147818) (xy 96.192404 -110.340701) (xy 96.13133 -110.531293) (xy 96.062679 -110.719288)
			(xy 95.986561 -110.904387) (xy 95.903099 -111.086292) (xy 95.812426 -111.264711) (xy 95.714687 -111.439361)
			(xy 95.610038 -111.60996) (xy 95.498648 -111.776235) (xy 95.380694 -111.93792) (xy 95.256365 -112.094757)
			(xy 95.125862 -112.246494) (xy 94.989391 -112.392888) (xy 94.847173 -112.533704) (xy 94.699435 -112.668718)
			(xy 94.546413 -112.797713) (xy 94.388353 -112.920482) (xy 94.225507 -113.036829) (xy 94.058137 -113.146567)
			(xy 93.88651 -113.249521) (xy 93.710902 -113.345526) (xy 93.531592 -113.434428) (xy 93.34887 -113.516084)
			(xy 93.163027 -113.590365) (xy 92.97436 -113.657151) (xy 92.783173 -113.716334) (xy 92.589771 -113.767821)
			(xy 92.394464 -113.811529) (xy 92.197564 -113.847388) (xy 91.999387 -113.87534) (xy 91.800251 -113.89534)
			(xy 91.600474 -113.907358) (xy 91.400376 -113.911372) (xy 91.200278 -113.907378) (xy 91.000499 -113.895381)
			(xy 90.801361 -113.875401) (xy 90.603182 -113.847469) (xy 90.406278 -113.81163) (xy 90.210967 -113.767942)
			(xy 90.017559 -113.716475) (xy 89.826366 -113.657311) (xy 89.637693 -113.590544) (xy 89.451842 -113.516282)
			(xy 89.269111 -113.434644) (xy 89.089793 -113.345761) (xy 88.914175 -113.249774) (xy 88.742537 -113.146837)
			(xy 88.575156 -113.037116) (xy 88.412298 -112.920785) (xy 88.254226 -112.798032) (xy 88.101191 -112.669053)
			(xy 87.953439 -112.534055) (xy 87.811206 -112.393252) (xy 87.674721 -112.246872) (xy 87.544202 -112.095149)
			(xy 87.419858 -111.938325) (xy 87.301888 -111.776651) (xy 87.19048 -111.610387) (xy 87.085814 -111.439799)
			(xy 86.988057 -111.26516) (xy 86.897366 -111.086749) (xy 86.813885 -110.904853) (xy 86.737749 -110.719762)
			(xy 86.669079 -110.531773) (xy 86.607986 -110.341188) (xy 86.554566 -110.14831) (xy 86.508906 -109.95345)
			(xy 86.47108 -109.756919) (xy 86.441146 -109.559032) (xy 86.419154 -109.360106) (xy 86.405139 -109.160459)
			(xy 86.399122 -108.960411) (xy 43.120564 -108.960411) (xy 43.120564 -112.094264) (xy 40.139366 -115.075208)
			(xy 29.69514 -115.075208) (xy 28.804108 -115.96624) (xy 28.804108 -117.657876) (xy 67.03617 -117.657876)
			(xy 67.03617 -117.59794) (xy 67.043993 -117.538518) (xy 67.059506 -117.480625) (xy 67.082442 -117.425252)
			(xy 67.112409 -117.373346) (xy 67.148896 -117.325796) (xy 67.191276 -117.283416) (xy 67.238826 -117.246929)
			(xy 67.290732 -117.216962) (xy 67.346105 -117.194026) (xy 67.403998 -117.178513) (xy 67.46342 -117.17069)
			(xy 67.493388 -117.1702) (xy 67.523356 -117.17069) (xy 67.582778 -117.178513) (xy 67.640671 -117.194026)
			(xy 67.696044 -117.216962) (xy 67.74795 -117.246929) (xy 67.7955 -117.283416) (xy 67.83788 -117.325796)
			(xy 67.874367 -117.373346) (xy 67.904334 -117.425252) (xy 67.92727 -117.480625) (xy 67.942783 -117.538518)
			(xy 67.950606 -117.59794) (xy 67.950606 -117.657876) (xy 67.942783 -117.717298) (xy 67.92727 -117.775191)
			(xy 67.904334 -117.830564) (xy 67.874367 -117.88247) (xy 67.83788 -117.93002) (xy 67.7955 -117.9724)
			(xy 67.74795 -118.008887) (xy 67.696044 -118.038854) (xy 67.640671 -118.06179) (xy 67.582778 -118.077303)
			(xy 67.523356 -118.085126) (xy 67.46342 -118.085126) (xy 67.403998 -118.077303) (xy 67.346105 -118.06179)
			(xy 67.290732 -118.038854) (xy 67.238826 -118.008887) (xy 67.191276 -117.9724) (xy 67.148896 -117.93002)
			(xy 67.112409 -117.88247) (xy 67.082442 -117.830564) (xy 67.059506 -117.775191) (xy 67.043993 -117.717298)
			(xy 67.03617 -117.657876) (xy 28.804108 -117.657876) (xy 28.804108 -120.344688) (xy 67.03998 -120.344688)
			(xy 67.03998 -120.284752) (xy 67.047803 -120.22533) (xy 67.063316 -120.167437) (xy 67.086252 -120.112064)
			(xy 67.116219 -120.060158) (xy 67.152706 -120.012608) (xy 67.195086 -119.970228) (xy 67.242636 -119.933741)
			(xy 67.294542 -119.903774) (xy 67.349915 -119.880838) (xy 67.407808 -119.865325) (xy 67.46723 -119.857502)
			(xy 67.497198 -119.857012) (xy 67.527166 -119.857502) (xy 67.586588 -119.865325) (xy 67.644481 -119.880838)
			(xy 67.699854 -119.903774) (xy 67.75176 -119.933741) (xy 67.79931 -119.970228) (xy 67.84169 -120.012608)
			(xy 67.878177 -120.060158) (xy 67.908144 -120.112064) (xy 67.93108 -120.167437) (xy 67.946593 -120.22533)
			(xy 67.954416 -120.284752) (xy 67.954416 -120.344688) (xy 67.946593 -120.40411) (xy 67.93108 -120.462003)
			(xy 67.908144 -120.517376) (xy 67.878177 -120.569282) (xy 67.84169 -120.616832) (xy 67.79931 -120.659212)
			(xy 67.75176 -120.695699) (xy 67.699854 -120.725666) (xy 67.644481 -120.748602) (xy 67.586588 -120.764115)
			(xy 67.527166 -120.771938) (xy 67.46723 -120.771938) (xy 67.407808 -120.764115) (xy 67.349915 -120.748602)
			(xy 67.294542 -120.725666) (xy 67.242636 -120.695699) (xy 67.195086 -120.659212) (xy 67.152706 -120.616832)
			(xy 67.116219 -120.569282) (xy 67.086252 -120.517376) (xy 67.063316 -120.462003) (xy 67.047803 -120.40411)
			(xy 67.03998 -120.344688) (xy 28.804108 -120.344688) (xy 28.804108 -121.249947) (xy 72.999096 -121.249947)
			(xy 73.001098 -121.049819) (xy 73.011106 -120.849931) (xy 73.029103 -120.650604) (xy 73.055061 -120.452156)
			(xy 73.088938 -120.254906) (xy 73.13068 -120.059169) (xy 73.180219 -119.865259) (xy 73.237477 -119.673486)
			(xy 73.302362 -119.484157) (xy 73.37477 -119.297577) (xy 73.454586 -119.114042) (xy 73.54168 -118.933848)
			(xy 73.635914 -118.757283) (xy 73.737137 -118.58463) (xy 73.845187 -118.416165) (xy 73.95989 -118.252157)
			(xy 74.081064 -118.09287) (xy 74.208513 -117.938559) (xy 74.342034 -117.789471) (xy 74.481414 -117.645844)
			(xy 74.626428 -117.507908) (xy 74.776845 -117.375885) (xy 74.932423 -117.249986) (xy 75.092915 -117.130412)
			(xy 75.258061 -117.017356) (xy 75.427599 -116.910997) (xy 75.601257 -116.811506) (xy 75.778756 -116.719043)
			(xy 75.959812 -116.633756) (xy 76.144136 -116.555781) (xy 76.331432 -116.485244) (xy 76.5214 -116.422256)
			(xy 76.713736 -116.366919) (xy 76.908132 -116.319322) (xy 77.104277 -116.279541) (xy 77.301856 -116.247639)
			(xy 77.500553 -116.223668) (xy 77.700051 -116.207666) (xy 77.900029 -116.199659) (xy 78.000098 -116.199158)
			(xy 78.100167 -116.199659) (xy 78.300145 -116.207666) (xy 78.499643 -116.223668) (xy 78.69834 -116.247639)
			(xy 78.895919 -116.279541) (xy 79.092064 -116.319322) (xy 79.28646 -116.366919) (xy 79.478796 -116.422256)
			(xy 79.668764 -116.485244) (xy 79.85606 -116.555781) (xy 80.040384 -116.633756) (xy 80.22144 -116.719043)
			(xy 80.398939 -116.811506) (xy 80.572597 -116.910997) (xy 80.742135 -117.017356) (xy 80.907281 -117.130412)
			(xy 81.067773 -117.249986) (xy 81.223351 -117.375885) (xy 81.373768 -117.507908) (xy 81.518782 -117.645844)
			(xy 81.658162 -117.789471) (xy 81.791683 -117.938559) (xy 81.919132 -118.09287) (xy 82.040306 -118.252157)
			(xy 82.155009 -118.416165) (xy 82.263059 -118.58463) (xy 82.364282 -118.757283) (xy 82.458516 -118.933848)
			(xy 82.54561 -119.114042) (xy 82.625426 -119.297577) (xy 82.697834 -119.484157) (xy 82.762719 -119.673486)
			(xy 82.819977 -119.865259) (xy 82.869516 -120.059169) (xy 82.911258 -120.254906) (xy 82.945135 -120.452156)
			(xy 82.971093 -120.650604) (xy 82.98909 -120.849931) (xy 82.999098 -121.049819) (xy 83.0011 -121.249947)
			(xy 82.995094 -121.449995) (xy 82.981089 -121.649643) (xy 82.959107 -121.84857) (xy 82.929183 -122.046459)
			(xy 82.891366 -122.242992) (xy 82.845717 -122.437854) (xy 82.792307 -122.630734) (xy 82.731223 -122.821323)
			(xy 82.662563 -123.009315) (xy 82.586436 -123.19441) (xy 82.502965 -123.37631) (xy 82.412282 -123.554726)
			(xy 82.314534 -123.72937) (xy 82.209877 -123.899963) (xy 82.098478 -124.066233) (xy 81.980516 -124.227912)
			(xy 81.85618 -124.384743) (xy 81.725668 -124.536473) (xy 81.589191 -124.68286) (xy 81.446965 -124.823669)
			(xy 81.29922 -124.958676) (xy 81.146192 -125.087663) (xy 80.988125 -125.210424) (xy 80.825274 -125.326762)
			(xy 80.657898 -125.436492) (xy 80.486266 -125.539437) (xy 80.310652 -125.635433) (xy 80.131339 -125.724326)
			(xy 79.948612 -125.805973) (xy 79.762765 -125.880245) (xy 79.574095 -125.947021) (xy 79.382905 -126.006195)
			(xy 79.1895 -126.057672) (xy 78.994191 -126.10137) (xy 78.797289 -126.137218) (xy 78.599111 -126.16516)
			(xy 78.399974 -126.185151) (xy 78.200196 -126.197158) (xy 78.000098 -126.201163) (xy 77.8 -126.197158)
			(xy 77.600222 -126.185151) (xy 77.401085 -126.16516) (xy 77.202907 -126.137218) (xy 77.006005 -126.10137)
			(xy 76.810696 -126.057672) (xy 76.617291 -126.006195) (xy 76.426101 -125.947021) (xy 76.237431 -125.880245)
			(xy 76.051584 -125.805973) (xy 75.868857 -125.724326) (xy 75.689544 -125.635433) (xy 75.51393 -125.539437)
			(xy 75.342298 -125.436492) (xy 75.174922 -125.326762) (xy 75.012071 -125.210424) (xy 74.854004 -125.087663)
			(xy 74.700976 -124.958676) (xy 74.553231 -124.823669) (xy 74.411005 -124.68286) (xy 74.274528 -124.536473)
			(xy 74.144016 -124.384743) (xy 74.01968 -124.227912) (xy 73.901718 -124.066233) (xy 73.790319 -123.899963)
			(xy 73.685662 -123.72937) (xy 73.587914 -123.554726) (xy 73.497231 -123.37631) (xy 73.41376 -123.19441)
			(xy 73.337633 -123.009315) (xy 73.268973 -122.821323) (xy 73.207889 -122.630734) (xy 73.154479 -122.437854)
			(xy 73.10883 -122.242992) (xy 73.071013 -122.046459) (xy 73.041089 -121.84857) (xy 73.019107 -121.649643)
			(xy 73.005102 -121.449995) (xy 72.999096 -121.249947) (xy 28.804108 -121.249947) (xy 28.804108 -127.829564)
			(xy 51.074828 -127.829564) (xy 52.726336 -127.829564) (xy 52.726336 -129.481072) (xy 51.074828 -129.481072)
			(xy 51.074828 -127.829564) (xy 28.804108 -127.829564) (xy 28.804108 -131.250791) (xy 73.677518 -131.250791)
			(xy 73.677518 -131.179469) (xy 73.685504 -131.108595) (xy 73.701374 -131.03906) (xy 73.724931 -130.97174)
			(xy 73.755876 -130.907481) (xy 73.793822 -130.84709) (xy 73.838291 -130.791328) (xy 73.888724 -130.740895)
			(xy 73.944486 -130.696426) (xy 74.004877 -130.65848) (xy 74.069136 -130.627535) (xy 74.136456 -130.603978)
			(xy 74.205991 -130.588108) (xy 74.276865 -130.580122) (xy 74.312526 -130.579622) (xy 74.348187 -130.580122)
			(xy 74.419061 -130.588108) (xy 74.488596 -130.603978) (xy 74.555916 -130.627535) (xy 74.620175 -130.65848)
			(xy 74.680566 -130.696426) (xy 74.736328 -130.740895) (xy 74.786761 -130.791328) (xy 74.83123 -130.84709)
			(xy 74.869176 -130.907481) (xy 74.900121 -130.97174) (xy 74.923678 -131.03906) (xy 74.939548 -131.108595)
			(xy 74.947385 -131.178147) (xy 75.70139 -131.178147) (xy 75.70139 -131.106825) (xy 75.709376 -131.035951)
			(xy 75.725246 -130.966416) (xy 75.748803 -130.899096) (xy 75.779748 -130.834837) (xy 75.817694 -130.774446)
			(xy 75.862163 -130.718684) (xy 75.912596 -130.668251) (xy 75.968358 -130.623782) (xy 76.028749 -130.585836)
			(xy 76.093008 -130.554891) (xy 76.160328 -130.531334) (xy 76.229863 -130.515464) (xy 76.300737 -130.507478)
			(xy 76.336398 -130.506978) (xy 76.372059 -130.507478) (xy 76.442933 -130.515464) (xy 76.512468 -130.531334)
			(xy 76.579788 -130.554891) (xy 76.644047 -130.585836) (xy 76.704438 -130.623782) (xy 76.7602 -130.668251)
			(xy 76.810633 -130.718684) (xy 76.855102 -130.774446) (xy 76.893048 -130.834837) (xy 76.923993 -130.899096)
			(xy 76.94755 -130.966416) (xy 76.96342 -131.035951) (xy 76.971406 -131.106825) (xy 76.971406 -131.178147)
			(xy 76.968258 -131.206087) (xy 77.588356 -131.206087) (xy 77.588356 -131.134765) (xy 77.596342 -131.063891)
			(xy 77.612212 -130.994356) (xy 77.635769 -130.927036) (xy 77.666714 -130.862777) (xy 77.70466 -130.802386)
			(xy 77.749129 -130.746624) (xy 77.799562 -130.696191) (xy 77.855324 -130.651722) (xy 77.915715 -130.613776)
			(xy 77.979974 -130.582831) (xy 78.047294 -130.559274) (xy 78.116829 -130.543404) (xy 78.187703 -130.535418)
			(xy 78.223364 -130.534918) (xy 78.259025 -130.535418) (xy 78.329899 -130.543404) (xy 78.399434 -130.559274)
			(xy 78.466754 -130.582831) (xy 78.531013 -130.613776) (xy 78.591404 -130.651722) (xy 78.647166 -130.696191)
			(xy 78.697599 -130.746624) (xy 78.742068 -130.802386) (xy 78.780014 -130.862777) (xy 78.810959 -130.927036)
			(xy 78.834516 -130.994356) (xy 78.850386 -131.063891) (xy 78.858372 -131.134765) (xy 78.858372 -131.206087)
			(xy 78.850386 -131.276961) (xy 78.85004 -131.278477) (xy 79.829906 -131.278477) (xy 79.829906 -131.207155)
			(xy 79.837892 -131.136281) (xy 79.853762 -131.066746) (xy 79.877319 -130.999426) (xy 79.908264 -130.935167)
			(xy 79.94621 -130.874776) (xy 79.990679 -130.819014) (xy 80.041112 -130.768581) (xy 80.096874 -130.724112)
			(xy 80.157265 -130.686166) (xy 80.221524 -130.655221) (xy 80.288844 -130.631664) (xy 80.358379 -130.615794)
			(xy 80.429253 -130.607808) (xy 80.464914 -130.607308) (xy 80.500575 -130.607808) (xy 80.571449 -130.615794)
			(xy 80.640984 -130.631664) (xy 80.708304 -130.655221) (xy 80.772563 -130.686166) (xy 80.832954 -130.724112)
			(xy 80.888716 -130.768581) (xy 80.939149 -130.819014) (xy 80.983618 -130.874776) (xy 81.021564 -130.935167)
			(xy 81.052509 -130.999426) (xy 81.076066 -131.066746) (xy 81.091936 -131.136281) (xy 81.099922 -131.207155)
			(xy 81.099922 -131.260189) (xy 81.950298 -131.260189) (xy 81.950298 -131.188867) (xy 81.958284 -131.117993)
			(xy 81.974154 -131.048458) (xy 81.997711 -130.981138) (xy 82.028656 -130.916879) (xy 82.066602 -130.856488)
			(xy 82.111071 -130.800726) (xy 82.161504 -130.750293) (xy 82.217266 -130.705824) (xy 82.277657 -130.667878)
			(xy 82.341916 -130.636933) (xy 82.409236 -130.613376) (xy 82.478771 -130.597506) (xy 82.549645 -130.58952)
			(xy 82.585306 -130.58902) (xy 82.620967 -130.58952) (xy 82.691841 -130.597506) (xy 82.761376 -130.613376)
			(xy 82.828696 -130.636933) (xy 82.892955 -130.667878) (xy 82.953346 -130.705824) (xy 83.009108 -130.750293)
			(xy 83.059541 -130.800726) (xy 83.10401 -130.856488) (xy 83.141956 -130.916879) (xy 83.172901 -130.981138)
			(xy 83.196458 -131.048458) (xy 83.212328 -131.117993) (xy 83.220314 -131.188867) (xy 83.220314 -131.260189)
			(xy 83.212328 -131.331063) (xy 83.196458 -131.400598) (xy 83.172901 -131.467918) (xy 83.141956 -131.532177)
			(xy 83.10401 -131.592568) (xy 83.059541 -131.64833) (xy 83.009108 -131.698763) (xy 82.953346 -131.743232)
			(xy 82.892955 -131.781178) (xy 82.828696 -131.812123) (xy 82.761376 -131.83568) (xy 82.691841 -131.85155)
			(xy 82.620967 -131.859536) (xy 82.549645 -131.859536) (xy 82.478771 -131.85155) (xy 82.409236 -131.83568)
			(xy 82.341916 -131.812123) (xy 82.277657 -131.781178) (xy 82.217266 -131.743232) (xy 82.161504 -131.698763)
			(xy 82.111071 -131.64833) (xy 82.066602 -131.592568) (xy 82.028656 -131.532177) (xy 81.997711 -131.467918)
			(xy 81.974154 -131.400598) (xy 81.958284 -131.331063) (xy 81.950298 -131.260189) (xy 81.099922 -131.260189)
			(xy 81.099922 -131.278477) (xy 81.091936 -131.349351) (xy 81.076066 -131.418886) (xy 81.052509 -131.486206)
			(xy 81.021564 -131.550465) (xy 80.983618 -131.610856) (xy 80.939149 -131.666618) (xy 80.888716 -131.717051)
			(xy 80.832954 -131.76152) (xy 80.772563 -131.799466) (xy 80.708304 -131.830411) (xy 80.640984 -131.853968)
			(xy 80.571449 -131.869838) (xy 80.500575 -131.877824) (xy 80.429253 -131.877824) (xy 80.358379 -131.869838)
			(xy 80.288844 -131.853968) (xy 80.221524 -131.830411) (xy 80.157265 -131.799466) (xy 80.096874 -131.76152)
			(xy 80.041112 -131.717051) (xy 79.990679 -131.666618) (xy 79.94621 -131.610856) (xy 79.908264 -131.550465)
			(xy 79.877319 -131.486206) (xy 79.853762 -131.418886) (xy 79.837892 -131.349351) (xy 79.829906 -131.278477)
			(xy 78.85004 -131.278477) (xy 78.834516 -131.346496) (xy 78.810959 -131.413816) (xy 78.780014 -131.478075)
			(xy 78.742068 -131.538466) (xy 78.697599 -131.594228) (xy 78.647166 -131.644661) (xy 78.591404 -131.68913)
			(xy 78.531013 -131.727076) (xy 78.466754 -131.758021) (xy 78.399434 -131.781578) (xy 78.329899 -131.797448)
			(xy 78.259025 -131.805434) (xy 78.187703 -131.805434) (xy 78.116829 -131.797448) (xy 78.047294 -131.781578)
			(xy 77.979974 -131.758021) (xy 77.915715 -131.727076) (xy 77.855324 -131.68913) (xy 77.799562 -131.644661)
			(xy 77.749129 -131.594228) (xy 77.70466 -131.538466) (xy 77.666714 -131.478075) (xy 77.635769 -131.413816)
			(xy 77.612212 -131.346496) (xy 77.596342 -131.276961) (xy 77.588356 -131.206087) (xy 76.968258 -131.206087)
			(xy 76.96342 -131.249021) (xy 76.94755 -131.318556) (xy 76.923993 -131.385876) (xy 76.893048 -131.450135)
			(xy 76.855102 -131.510526) (xy 76.810633 -131.566288) (xy 76.7602 -131.616721) (xy 76.704438 -131.66119)
			(xy 76.644047 -131.699136) (xy 76.579788 -131.730081) (xy 76.512468 -131.753638) (xy 76.442933 -131.769508)
			(xy 76.372059 -131.777494) (xy 76.300737 -131.777494) (xy 76.229863 -131.769508) (xy 76.160328 -131.753638)
			(xy 76.093008 -131.730081) (xy 76.028749 -131.699136) (xy 75.968358 -131.66119) (xy 75.912596 -131.616721)
			(xy 75.862163 -131.566288) (xy 75.817694 -131.510526) (xy 75.779748 -131.450135) (xy 75.748803 -131.385876)
			(xy 75.725246 -131.318556) (xy 75.709376 -131.249021) (xy 75.70139 -131.178147) (xy 74.947385 -131.178147)
			(xy 74.947534 -131.179469) (xy 74.947534 -131.250791) (xy 74.939548 -131.321665) (xy 74.923678 -131.3912)
			(xy 74.900121 -131.45852) (xy 74.869176 -131.522779) (xy 74.83123 -131.58317) (xy 74.786761 -131.638932)
			(xy 74.736328 -131.689365) (xy 74.680566 -131.733834) (xy 74.620175 -131.77178) (xy 74.555916 -131.802725)
			(xy 74.488596 -131.826282) (xy 74.419061 -131.842152) (xy 74.348187 -131.850138) (xy 74.276865 -131.850138)
			(xy 74.205991 -131.842152) (xy 74.136456 -131.826282) (xy 74.069136 -131.802725) (xy 74.004877 -131.77178)
			(xy 73.944486 -131.733834) (xy 73.888724 -131.689365) (xy 73.838291 -131.638932) (xy 73.793822 -131.58317)
			(xy 73.755876 -131.522779) (xy 73.724931 -131.45852) (xy 73.701374 -131.3912) (xy 73.685504 -131.321665)
			(xy 73.677518 -131.250791) (xy 28.804108 -131.250791) (xy 28.804108 -133.213703) (xy 73.677518 -133.213703)
			(xy 73.677518 -133.142381) (xy 73.685504 -133.071507) (xy 73.701374 -133.001972) (xy 73.724931 -132.934652)
			(xy 73.755876 -132.870393) (xy 73.793822 -132.810002) (xy 73.838291 -132.75424) (xy 73.888724 -132.703807)
			(xy 73.944486 -132.659338) (xy 74.004877 -132.621392) (xy 74.069136 -132.590447) (xy 74.136456 -132.56689)
			(xy 74.205991 -132.55102) (xy 74.276865 -132.543034) (xy 74.312526 -132.542534) (xy 74.348187 -132.543034)
			(xy 74.419061 -132.55102) (xy 74.488596 -132.56689) (xy 74.555916 -132.590447) (xy 74.620175 -132.621392)
			(xy 74.680566 -132.659338) (xy 74.736328 -132.703807) (xy 74.786761 -132.75424) (xy 74.83123 -132.810002)
			(xy 74.869176 -132.870393) (xy 74.900121 -132.934652) (xy 74.923678 -133.001972) (xy 74.939548 -133.071507)
			(xy 74.947385 -133.141059) (xy 75.70139 -133.141059) (xy 75.70139 -133.069737) (xy 75.709376 -132.998863)
			(xy 75.725246 -132.929328) (xy 75.748803 -132.862008) (xy 75.779748 -132.797749) (xy 75.817694 -132.737358)
			(xy 75.862163 -132.681596) (xy 75.912596 -132.631163) (xy 75.968358 -132.586694) (xy 76.028749 -132.548748)
			(xy 76.093008 -132.517803) (xy 76.160328 -132.494246) (xy 76.229863 -132.478376) (xy 76.300737 -132.47039)
			(xy 76.336398 -132.46989) (xy 76.372059 -132.47039) (xy 76.442933 -132.478376) (xy 76.512468 -132.494246)
			(xy 76.579788 -132.517803) (xy 76.644047 -132.548748) (xy 76.704438 -132.586694) (xy 76.7602 -132.631163)
			(xy 76.810633 -132.681596) (xy 76.855102 -132.737358) (xy 76.893048 -132.797749) (xy 76.923993 -132.862008)
			(xy 76.94755 -132.929328) (xy 76.96342 -132.998863) (xy 76.971406 -133.069737) (xy 76.971406 -133.141059)
			(xy 76.968258 -133.168999) (xy 77.588356 -133.168999) (xy 77.588356 -133.097677) (xy 77.596342 -133.026803)
			(xy 77.612212 -132.957268) (xy 77.635769 -132.889948) (xy 77.666714 -132.825689) (xy 77.70466 -132.765298)
			(xy 77.749129 -132.709536) (xy 77.799562 -132.659103) (xy 77.855324 -132.614634) (xy 77.915715 -132.576688)
			(xy 77.979974 -132.545743) (xy 78.047294 -132.522186) (xy 78.116829 -132.506316) (xy 78.187703 -132.49833)
			(xy 78.223364 -132.49783) (xy 78.259025 -132.49833) (xy 78.329899 -132.506316) (xy 78.399434 -132.522186)
			(xy 78.466754 -132.545743) (xy 78.531013 -132.576688) (xy 78.591404 -132.614634) (xy 78.647166 -132.659103)
			(xy 78.697599 -132.709536) (xy 78.742068 -132.765298) (xy 78.780014 -132.825689) (xy 78.810959 -132.889948)
			(xy 78.834516 -132.957268) (xy 78.850386 -133.026803) (xy 78.858372 -133.097677) (xy 78.858372 -133.168999)
			(xy 78.850386 -133.239873) (xy 78.85004 -133.241389) (xy 79.829906 -133.241389) (xy 79.829906 -133.170067)
			(xy 79.837892 -133.099193) (xy 79.853762 -133.029658) (xy 79.877319 -132.962338) (xy 79.908264 -132.898079)
			(xy 79.94621 -132.837688) (xy 79.990679 -132.781926) (xy 80.041112 -132.731493) (xy 80.096874 -132.687024)
			(xy 80.157265 -132.649078) (xy 80.221524 -132.618133) (xy 80.288844 -132.594576) (xy 80.358379 -132.578706)
			(xy 80.429253 -132.57072) (xy 80.464914 -132.57022) (xy 80.500575 -132.57072) (xy 80.571449 -132.578706)
			(xy 80.640984 -132.594576) (xy 80.708304 -132.618133) (xy 80.772563 -132.649078) (xy 80.832954 -132.687024)
			(xy 80.888716 -132.731493) (xy 80.939149 -132.781926) (xy 80.983618 -132.837688) (xy 81.021564 -132.898079)
			(xy 81.052509 -132.962338) (xy 81.076066 -133.029658) (xy 81.091936 -133.099193) (xy 81.099922 -133.170067)
			(xy 81.099922 -133.223101) (xy 81.950298 -133.223101) (xy 81.950298 -133.151779) (xy 81.958284 -133.080905)
			(xy 81.974154 -133.01137) (xy 81.997711 -132.94405) (xy 82.028656 -132.879791) (xy 82.066602 -132.8194)
			(xy 82.111071 -132.763638) (xy 82.161504 -132.713205) (xy 82.217266 -132.668736) (xy 82.277657 -132.63079)
			(xy 82.341916 -132.599845) (xy 82.409236 -132.576288) (xy 82.478771 -132.560418) (xy 82.549645 -132.552432)
			(xy 82.585306 -132.551932) (xy 82.620967 -132.552432) (xy 82.691841 -132.560418) (xy 82.761376 -132.576288)
			(xy 82.828696 -132.599845) (xy 82.892955 -132.63079) (xy 82.953346 -132.668736) (xy 83.009108 -132.713205)
			(xy 83.059541 -132.763638) (xy 83.10401 -132.8194) (xy 83.141956 -132.879791) (xy 83.172901 -132.94405)
			(xy 83.196458 -133.01137) (xy 83.212328 -133.080905) (xy 83.220314 -133.151779) (xy 83.220314 -133.223101)
			(xy 83.212328 -133.293975) (xy 83.196458 -133.36351) (xy 83.172901 -133.43083) (xy 83.141956 -133.495089)
			(xy 83.10401 -133.55548) (xy 83.059541 -133.611242) (xy 83.009108 -133.661675) (xy 82.953346 -133.706144)
			(xy 82.892955 -133.74409) (xy 82.828696 -133.775035) (xy 82.761376 -133.798592) (xy 82.691841 -133.814462)
			(xy 82.620967 -133.822448) (xy 82.549645 -133.822448) (xy 82.478771 -133.814462) (xy 82.409236 -133.798592)
			(xy 82.341916 -133.775035) (xy 82.277657 -133.74409) (xy 82.217266 -133.706144) (xy 82.161504 -133.661675)
			(xy 82.111071 -133.611242) (xy 82.066602 -133.55548) (xy 82.028656 -133.495089) (xy 81.997711 -133.43083)
			(xy 81.974154 -133.36351) (xy 81.958284 -133.293975) (xy 81.950298 -133.223101) (xy 81.099922 -133.223101)
			(xy 81.099922 -133.241389) (xy 81.091936 -133.312263) (xy 81.076066 -133.381798) (xy 81.052509 -133.449118)
			(xy 81.021564 -133.513377) (xy 80.983618 -133.573768) (xy 80.939149 -133.62953) (xy 80.888716 -133.679963)
			(xy 80.832954 -133.724432) (xy 80.772563 -133.762378) (xy 80.708304 -133.793323) (xy 80.640984 -133.81688)
			(xy 80.571449 -133.83275) (xy 80.500575 -133.840736) (xy 80.429253 -133.840736) (xy 80.358379 -133.83275)
			(xy 80.288844 -133.81688) (xy 80.221524 -133.793323) (xy 80.157265 -133.762378) (xy 80.096874 -133.724432)
			(xy 80.041112 -133.679963) (xy 79.990679 -133.62953) (xy 79.94621 -133.573768) (xy 79.908264 -133.513377)
			(xy 79.877319 -133.449118) (xy 79.853762 -133.381798) (xy 79.837892 -133.312263) (xy 79.829906 -133.241389)
			(xy 78.85004 -133.241389) (xy 78.834516 -133.309408) (xy 78.810959 -133.376728) (xy 78.780014 -133.440987)
			(xy 78.742068 -133.501378) (xy 78.697599 -133.55714) (xy 78.647166 -133.607573) (xy 78.591404 -133.652042)
			(xy 78.531013 -133.689988) (xy 78.466754 -133.720933) (xy 78.399434 -133.74449) (xy 78.329899 -133.76036)
			(xy 78.259025 -133.768346) (xy 78.187703 -133.768346) (xy 78.116829 -133.76036) (xy 78.047294 -133.74449)
			(xy 77.979974 -133.720933) (xy 77.915715 -133.689988) (xy 77.855324 -133.652042) (xy 77.799562 -133.607573)
			(xy 77.749129 -133.55714) (xy 77.70466 -133.501378) (xy 77.666714 -133.440987) (xy 77.635769 -133.376728)
			(xy 77.612212 -133.309408) (xy 77.596342 -133.239873) (xy 77.588356 -133.168999) (xy 76.968258 -133.168999)
			(xy 76.96342 -133.211933) (xy 76.94755 -133.281468) (xy 76.923993 -133.348788) (xy 76.893048 -133.413047)
			(xy 76.855102 -133.473438) (xy 76.810633 -133.5292) (xy 76.7602 -133.579633) (xy 76.704438 -133.624102)
			(xy 76.644047 -133.662048) (xy 76.579788 -133.692993) (xy 76.512468 -133.71655) (xy 76.442933 -133.73242)
			(xy 76.372059 -133.740406) (xy 76.300737 -133.740406) (xy 76.229863 -133.73242) (xy 76.160328 -133.71655)
			(xy 76.093008 -133.692993) (xy 76.028749 -133.662048) (xy 75.968358 -133.624102) (xy 75.912596 -133.579633)
			(xy 75.862163 -133.5292) (xy 75.817694 -133.473438) (xy 75.779748 -133.413047) (xy 75.748803 -133.348788)
			(xy 75.725246 -133.281468) (xy 75.709376 -133.211933) (xy 75.70139 -133.141059) (xy 74.947385 -133.141059)
			(xy 74.947534 -133.142381) (xy 74.947534 -133.213703) (xy 74.939548 -133.284577) (xy 74.923678 -133.354112)
			(xy 74.900121 -133.421432) (xy 74.869176 -133.485691) (xy 74.83123 -133.546082) (xy 74.786761 -133.601844)
			(xy 74.736328 -133.652277) (xy 74.680566 -133.696746) (xy 74.620175 -133.734692) (xy 74.555916 -133.765637)
			(xy 74.488596 -133.789194) (xy 74.419061 -133.805064) (xy 74.348187 -133.81305) (xy 74.276865 -133.81305)
			(xy 74.205991 -133.805064) (xy 74.136456 -133.789194) (xy 74.069136 -133.765637) (xy 74.004877 -133.734692)
			(xy 73.944486 -133.696746) (xy 73.888724 -133.652277) (xy 73.838291 -133.601844) (xy 73.793822 -133.546082)
			(xy 73.755876 -133.485691) (xy 73.724931 -133.421432) (xy 73.701374 -133.354112) (xy 73.685504 -133.284577)
			(xy 73.677518 -133.213703) (xy 28.804108 -133.213703) (xy 28.804108 -135.357209) (xy 73.677518 -135.357209)
			(xy 73.677518 -135.285887) (xy 73.685504 -135.215013) (xy 73.701374 -135.145478) (xy 73.724931 -135.078158)
			(xy 73.755876 -135.013899) (xy 73.793822 -134.953508) (xy 73.838291 -134.897746) (xy 73.888724 -134.847313)
			(xy 73.944486 -134.802844) (xy 74.004877 -134.764898) (xy 74.069136 -134.733953) (xy 74.136456 -134.710396)
			(xy 74.205991 -134.694526) (xy 74.276865 -134.68654) (xy 74.312526 -134.68604) (xy 74.348187 -134.68654)
			(xy 74.419061 -134.694526) (xy 74.488596 -134.710396) (xy 74.555916 -134.733953) (xy 74.620175 -134.764898)
			(xy 74.680566 -134.802844) (xy 74.736328 -134.847313) (xy 74.786761 -134.897746) (xy 74.83123 -134.953508)
			(xy 74.869176 -135.013899) (xy 74.900121 -135.078158) (xy 74.923678 -135.145478) (xy 74.939548 -135.215013)
			(xy 74.947385 -135.284565) (xy 75.70139 -135.284565) (xy 75.70139 -135.213243) (xy 75.709376 -135.142369)
			(xy 75.725246 -135.072834) (xy 75.748803 -135.005514) (xy 75.779748 -134.941255) (xy 75.817694 -134.880864)
			(xy 75.862163 -134.825102) (xy 75.912596 -134.774669) (xy 75.968358 -134.7302) (xy 76.028749 -134.692254)
			(xy 76.093008 -134.661309) (xy 76.160328 -134.637752) (xy 76.229863 -134.621882) (xy 76.300737 -134.613896)
			(xy 76.336398 -134.613396) (xy 76.372059 -134.613896) (xy 76.442933 -134.621882) (xy 76.512468 -134.637752)
			(xy 76.579788 -134.661309) (xy 76.644047 -134.692254) (xy 76.704438 -134.7302) (xy 76.7602 -134.774669)
			(xy 76.810633 -134.825102) (xy 76.855102 -134.880864) (xy 76.893048 -134.941255) (xy 76.923993 -135.005514)
			(xy 76.94755 -135.072834) (xy 76.96342 -135.142369) (xy 76.971406 -135.213243) (xy 76.971406 -135.284565)
			(xy 76.968258 -135.312505) (xy 77.588356 -135.312505) (xy 77.588356 -135.241183) (xy 77.596342 -135.170309)
			(xy 77.612212 -135.100774) (xy 77.635769 -135.033454) (xy 77.666714 -134.969195) (xy 77.70466 -134.908804)
			(xy 77.749129 -134.853042) (xy 77.799562 -134.802609) (xy 77.855324 -134.75814) (xy 77.915715 -134.720194)
			(xy 77.979974 -134.689249) (xy 78.047294 -134.665692) (xy 78.116829 -134.649822) (xy 78.187703 -134.641836)
			(xy 78.223364 -134.641336) (xy 78.259025 -134.641836) (xy 78.329899 -134.649822) (xy 78.399434 -134.665692)
			(xy 78.466754 -134.689249) (xy 78.531013 -134.720194) (xy 78.591404 -134.75814) (xy 78.647166 -134.802609)
			(xy 78.697599 -134.853042) (xy 78.742068 -134.908804) (xy 78.780014 -134.969195) (xy 78.810959 -135.033454)
			(xy 78.834516 -135.100774) (xy 78.850386 -135.170309) (xy 78.858372 -135.241183) (xy 78.858372 -135.312505)
			(xy 78.850386 -135.383379) (xy 78.85004 -135.384895) (xy 79.829906 -135.384895) (xy 79.829906 -135.313573)
			(xy 79.837892 -135.242699) (xy 79.853762 -135.173164) (xy 79.877319 -135.105844) (xy 79.908264 -135.041585)
			(xy 79.94621 -134.981194) (xy 79.990679 -134.925432) (xy 80.041112 -134.874999) (xy 80.096874 -134.83053)
			(xy 80.157265 -134.792584) (xy 80.221524 -134.761639) (xy 80.288844 -134.738082) (xy 80.358379 -134.722212)
			(xy 80.429253 -134.714226) (xy 80.464914 -134.713726) (xy 80.500575 -134.714226) (xy 80.571449 -134.722212)
			(xy 80.640984 -134.738082) (xy 80.708304 -134.761639) (xy 80.772563 -134.792584) (xy 80.832954 -134.83053)
			(xy 80.888716 -134.874999) (xy 80.939149 -134.925432) (xy 80.983618 -134.981194) (xy 81.021564 -135.041585)
			(xy 81.052509 -135.105844) (xy 81.076066 -135.173164) (xy 81.091936 -135.242699) (xy 81.099922 -135.313573)
			(xy 81.099922 -135.366607) (xy 81.950298 -135.366607) (xy 81.950298 -135.295285) (xy 81.958284 -135.224411)
			(xy 81.974154 -135.154876) (xy 81.997711 -135.087556) (xy 82.028656 -135.023297) (xy 82.066602 -134.962906)
			(xy 82.111071 -134.907144) (xy 82.161504 -134.856711) (xy 82.217266 -134.812242) (xy 82.277657 -134.774296)
			(xy 82.341916 -134.743351) (xy 82.409236 -134.719794) (xy 82.478771 -134.703924) (xy 82.549645 -134.695938)
			(xy 82.585306 -134.695438) (xy 82.620967 -134.695938) (xy 82.691841 -134.703924) (xy 82.761376 -134.719794)
			(xy 82.828696 -134.743351) (xy 82.892955 -134.774296) (xy 82.953346 -134.812242) (xy 83.009108 -134.856711)
			(xy 83.059541 -134.907144) (xy 83.10401 -134.962906) (xy 83.141956 -135.023297) (xy 83.172901 -135.087556)
			(xy 83.196458 -135.154876) (xy 83.212328 -135.224411) (xy 83.220314 -135.295285) (xy 83.220314 -135.366607)
			(xy 83.212328 -135.437481) (xy 83.196458 -135.507016) (xy 83.172901 -135.574336) (xy 83.141956 -135.638595)
			(xy 83.10401 -135.698986) (xy 83.059541 -135.754748) (xy 83.009108 -135.805181) (xy 82.953346 -135.84965)
			(xy 82.892955 -135.887596) (xy 82.828696 -135.918541) (xy 82.761376 -135.942098) (xy 82.691841 -135.957968)
			(xy 82.620967 -135.965954) (xy 82.549645 -135.965954) (xy 82.478771 -135.957968) (xy 82.409236 -135.942098)
			(xy 82.341916 -135.918541) (xy 82.277657 -135.887596) (xy 82.217266 -135.84965) (xy 82.161504 -135.805181)
			(xy 82.111071 -135.754748) (xy 82.066602 -135.698986) (xy 82.028656 -135.638595) (xy 81.997711 -135.574336)
			(xy 81.974154 -135.507016) (xy 81.958284 -135.437481) (xy 81.950298 -135.366607) (xy 81.099922 -135.366607)
			(xy 81.099922 -135.384895) (xy 81.091936 -135.455769) (xy 81.076066 -135.525304) (xy 81.052509 -135.592624)
			(xy 81.021564 -135.656883) (xy 80.983618 -135.717274) (xy 80.939149 -135.773036) (xy 80.888716 -135.823469)
			(xy 80.832954 -135.867938) (xy 80.772563 -135.905884) (xy 80.708304 -135.936829) (xy 80.640984 -135.960386)
			(xy 80.571449 -135.976256) (xy 80.500575 -135.984242) (xy 80.429253 -135.984242) (xy 80.358379 -135.976256)
			(xy 80.288844 -135.960386) (xy 80.221524 -135.936829) (xy 80.157265 -135.905884) (xy 80.096874 -135.867938)
			(xy 80.041112 -135.823469) (xy 79.990679 -135.773036) (xy 79.94621 -135.717274) (xy 79.908264 -135.656883)
			(xy 79.877319 -135.592624) (xy 79.853762 -135.525304) (xy 79.837892 -135.455769) (xy 79.829906 -135.384895)
			(xy 78.85004 -135.384895) (xy 78.834516 -135.452914) (xy 78.810959 -135.520234) (xy 78.780014 -135.584493)
			(xy 78.742068 -135.644884) (xy 78.697599 -135.700646) (xy 78.647166 -135.751079) (xy 78.591404 -135.795548)
			(xy 78.531013 -135.833494) (xy 78.466754 -135.864439) (xy 78.399434 -135.887996) (xy 78.329899 -135.903866)
			(xy 78.259025 -135.911852) (xy 78.187703 -135.911852) (xy 78.116829 -135.903866) (xy 78.047294 -135.887996)
			(xy 77.979974 -135.864439) (xy 77.915715 -135.833494) (xy 77.855324 -135.795548) (xy 77.799562 -135.751079)
			(xy 77.749129 -135.700646) (xy 77.70466 -135.644884) (xy 77.666714 -135.584493) (xy 77.635769 -135.520234)
			(xy 77.612212 -135.452914) (xy 77.596342 -135.383379) (xy 77.588356 -135.312505) (xy 76.968258 -135.312505)
			(xy 76.96342 -135.355439) (xy 76.94755 -135.424974) (xy 76.923993 -135.492294) (xy 76.893048 -135.556553)
			(xy 76.855102 -135.616944) (xy 76.810633 -135.672706) (xy 76.7602 -135.723139) (xy 76.704438 -135.767608)
			(xy 76.644047 -135.805554) (xy 76.579788 -135.836499) (xy 76.512468 -135.860056) (xy 76.442933 -135.875926)
			(xy 76.372059 -135.883912) (xy 76.300737 -135.883912) (xy 76.229863 -135.875926) (xy 76.160328 -135.860056)
			(xy 76.093008 -135.836499) (xy 76.028749 -135.805554) (xy 75.968358 -135.767608) (xy 75.912596 -135.723139)
			(xy 75.862163 -135.672706) (xy 75.817694 -135.616944) (xy 75.779748 -135.556553) (xy 75.748803 -135.492294)
			(xy 75.725246 -135.424974) (xy 75.709376 -135.355439) (xy 75.70139 -135.284565) (xy 74.947385 -135.284565)
			(xy 74.947534 -135.285887) (xy 74.947534 -135.357209) (xy 74.939548 -135.428083) (xy 74.923678 -135.497618)
			(xy 74.900121 -135.564938) (xy 74.869176 -135.629197) (xy 74.83123 -135.689588) (xy 74.786761 -135.74535)
			(xy 74.736328 -135.795783) (xy 74.680566 -135.840252) (xy 74.620175 -135.878198) (xy 74.555916 -135.909143)
			(xy 74.488596 -135.9327) (xy 74.419061 -135.94857) (xy 74.348187 -135.956556) (xy 74.276865 -135.956556)
			(xy 74.205991 -135.94857) (xy 74.136456 -135.9327) (xy 74.069136 -135.909143) (xy 74.004877 -135.878198)
			(xy 73.944486 -135.840252) (xy 73.888724 -135.795783) (xy 73.838291 -135.74535) (xy 73.793822 -135.689588)
			(xy 73.755876 -135.629197) (xy 73.724931 -135.564938) (xy 73.701374 -135.497618) (xy 73.685504 -135.428083)
			(xy 73.677518 -135.357209) (xy 28.804108 -135.357209) (xy 28.804108 -140.231047) (xy 39.818821 -140.231047)
			(xy 39.82483 -140.115126) (xy 39.838821 -139.999897) (xy 39.860729 -139.885907) (xy 39.890449 -139.7737)
			(xy 39.927839 -139.663811) (xy 39.972722 -139.556764) (xy 40.024883 -139.453068) (xy 40.084074 -139.353218)
			(xy 40.150013 -139.257689) (xy 40.222385 -139.166938) (xy 40.300846 -139.081395) (xy 40.385021 -139.001469)
			(xy 40.47451 -138.927542) (xy 40.568886 -138.859964) (xy 40.6677 -138.799058) (xy 40.77048 -138.745115)
			(xy 40.876737 -138.698391) (xy 40.985964 -138.65911) (xy 41.097641 -138.627458) (xy 41.211236 -138.603585)
			(xy 41.326207 -138.587607) (xy 41.442006 -138.579599) (xy 41.500044 -138.579098) (xy 41.558082 -138.579599)
			(xy 41.673881 -138.587607) (xy 41.788852 -138.603585) (xy 41.902447 -138.627458) (xy 42.014124 -138.65911)
			(xy 42.123351 -138.698391) (xy 42.229608 -138.745115) (xy 42.332388 -138.799058) (xy 42.431202 -138.859964)
			(xy 42.474686 -138.891101) (xy 63.648083 -138.891101) (xy 63.654132 -138.815531) (xy 63.668179 -138.741033)
			(xy 63.690065 -138.66845) (xy 63.719542 -138.598604) (xy 63.756277 -138.532287) (xy 63.799852 -138.470251)
			(xy 63.849774 -138.413198) (xy 63.905478 -138.361774) (xy 63.966333 -138.316563) (xy 64.031648 -138.278076)
			(xy 64.100684 -138.24675) (xy 64.172659 -138.22294) (xy 64.246757 -138.206915) (xy 64.322138 -138.198856)
			(xy 64.360044 -138.198352) (xy 64.39795 -138.198856) (xy 64.473331 -138.206915) (xy 64.547429 -138.22294)
			(xy 64.619404 -138.24675) (xy 64.68844 -138.278076) (xy 64.753755 -138.316563) (xy 64.81461 -138.361774)
			(xy 64.870314 -138.413198) (xy 64.920236 -138.470251) (xy 64.963811 -138.532287) (xy 65.000546 -138.598604)
			(xy 65.030023 -138.66845) (xy 65.051909 -138.741033) (xy 65.065956 -138.815531) (xy 65.072005 -138.891101)
			(xy 66.188083 -138.891101) (xy 66.194132 -138.815531) (xy 66.208179 -138.741033) (xy 66.230065 -138.66845)
			(xy 66.259542 -138.598604) (xy 66.296277 -138.532287) (xy 66.339852 -138.470251) (xy 66.389774 -138.413198)
			(xy 66.445478 -138.361774) (xy 66.506333 -138.316563) (xy 66.571648 -138.278076) (xy 66.640684 -138.24675)
			(xy 66.712659 -138.22294) (xy 66.786757 -138.206915) (xy 66.862138 -138.198856) (xy 66.900044 -138.198352)
			(xy 66.93795 -138.198856) (xy 67.013331 -138.206915) (xy 67.087429 -138.22294) (xy 67.159404 -138.24675)
			(xy 67.22844 -138.278076) (xy 67.293755 -138.316563) (xy 67.35461 -138.361774) (xy 67.410314 -138.413198)
			(xy 67.460236 -138.470251) (xy 67.503811 -138.532287) (xy 67.540546 -138.598604) (xy 67.570023 -138.66845)
			(xy 67.591909 -138.741033) (xy 67.605956 -138.815531) (xy 67.612005 -138.891101) (xy 68.728083 -138.891101)
			(xy 68.734132 -138.815531) (xy 68.748179 -138.741033) (xy 68.770065 -138.66845) (xy 68.799542 -138.598604)
			(xy 68.836277 -138.532287) (xy 68.879852 -138.470251) (xy 68.929774 -138.413198) (xy 68.985478 -138.361774)
			(xy 69.046333 -138.316563) (xy 69.111648 -138.278076) (xy 69.180684 -138.24675) (xy 69.252659 -138.22294)
			(xy 69.326757 -138.206915) (xy 69.402138 -138.198856) (xy 69.440044 -138.198352) (xy 69.47795 -138.198856)
			(xy 69.553331 -138.206915) (xy 69.627429 -138.22294) (xy 69.699404 -138.24675) (xy 69.76844 -138.278076)
			(xy 69.833755 -138.316563) (xy 69.89461 -138.361774) (xy 69.950314 -138.413198) (xy 70.000236 -138.470251)
			(xy 70.043811 -138.532287) (xy 70.080546 -138.598604) (xy 70.110023 -138.66845) (xy 70.131909 -138.741033)
			(xy 70.145956 -138.815531) (xy 70.152005 -138.891101) (xy 71.268083 -138.891101) (xy 71.274132 -138.815531)
			(xy 71.288179 -138.741033) (xy 71.310065 -138.66845) (xy 71.339542 -138.598604) (xy 71.376277 -138.532287)
			(xy 71.419852 -138.470251) (xy 71.469774 -138.413198) (xy 71.525478 -138.361774) (xy 71.586333 -138.316563)
			(xy 71.651648 -138.278076) (xy 71.720684 -138.24675) (xy 71.792659 -138.22294) (xy 71.866757 -138.206915)
			(xy 71.942138 -138.198856) (xy 71.980044 -138.198352) (xy 72.01795 -138.198856) (xy 72.093331 -138.206915)
			(xy 72.167429 -138.22294) (xy 72.239404 -138.24675) (xy 72.30844 -138.278076) (xy 72.373755 -138.316563)
			(xy 72.43461 -138.361774) (xy 72.490314 -138.413198) (xy 72.540236 -138.470251) (xy 72.583811 -138.532287)
			(xy 72.620546 -138.598604) (xy 72.650023 -138.66845) (xy 72.671909 -138.741033) (xy 72.685956 -138.815531)
			(xy 72.692005 -138.891101) (xy 73.808083 -138.891101) (xy 73.814132 -138.815531) (xy 73.828179 -138.741033)
			(xy 73.850065 -138.66845) (xy 73.879542 -138.598604) (xy 73.916277 -138.532287) (xy 73.959852 -138.470251)
			(xy 74.009774 -138.413198) (xy 74.065478 -138.361774) (xy 74.126333 -138.316563) (xy 74.191648 -138.278076)
			(xy 74.260684 -138.24675) (xy 74.332659 -138.22294) (xy 74.406757 -138.206915) (xy 74.482138 -138.198856)
			(xy 74.520044 -138.198352) (xy 74.55795 -138.198856) (xy 74.633331 -138.206915) (xy 74.707429 -138.22294)
			(xy 74.779404 -138.24675) (xy 74.84844 -138.278076) (xy 74.913755 -138.316563) (xy 74.97461 -138.361774)
			(xy 75.030314 -138.413198) (xy 75.080236 -138.470251) (xy 75.123811 -138.532287) (xy 75.160546 -138.598604)
			(xy 75.190023 -138.66845) (xy 75.211909 -138.741033) (xy 75.225956 -138.815531) (xy 75.232005 -138.891101)
			(xy 76.348083 -138.891101) (xy 76.354132 -138.815531) (xy 76.368179 -138.741033) (xy 76.390065 -138.66845)
			(xy 76.419542 -138.598604) (xy 76.456277 -138.532287) (xy 76.499852 -138.470251) (xy 76.549774 -138.413198)
			(xy 76.605478 -138.361774) (xy 76.666333 -138.316563) (xy 76.731648 -138.278076) (xy 76.800684 -138.24675)
			(xy 76.872659 -138.22294) (xy 76.946757 -138.206915) (xy 77.022138 -138.198856) (xy 77.060044 -138.198352)
			(xy 77.09795 -138.198856) (xy 77.173331 -138.206915) (xy 77.247429 -138.22294) (xy 77.319404 -138.24675)
			(xy 77.38844 -138.278076) (xy 77.453755 -138.316563) (xy 77.51461 -138.361774) (xy 77.570314 -138.413198)
			(xy 77.620236 -138.470251) (xy 77.663811 -138.532287) (xy 77.700546 -138.598604) (xy 77.730023 -138.66845)
			(xy 77.751909 -138.741033) (xy 77.765956 -138.815531) (xy 77.772005 -138.891101) (xy 78.888083 -138.891101)
			(xy 78.894132 -138.815531) (xy 78.908179 -138.741033) (xy 78.930065 -138.66845) (xy 78.959542 -138.598604)
			(xy 78.996277 -138.532287) (xy 79.039852 -138.470251) (xy 79.089774 -138.413198) (xy 79.145478 -138.361774)
			(xy 79.206333 -138.316563) (xy 79.271648 -138.278076) (xy 79.340684 -138.24675) (xy 79.412659 -138.22294)
			(xy 79.486757 -138.206915) (xy 79.562138 -138.198856) (xy 79.600044 -138.198352) (xy 79.63795 -138.198856)
			(xy 79.713331 -138.206915) (xy 79.787429 -138.22294) (xy 79.859404 -138.24675) (xy 79.92844 -138.278076)
			(xy 79.993755 -138.316563) (xy 80.05461 -138.361774) (xy 80.110314 -138.413198) (xy 80.160236 -138.470251)
			(xy 80.203811 -138.532287) (xy 80.240546 -138.598604) (xy 80.270023 -138.66845) (xy 80.291909 -138.741033)
			(xy 80.305956 -138.815531) (xy 80.312005 -138.891101) (xy 81.428083 -138.891101) (xy 81.434132 -138.815531)
			(xy 81.448179 -138.741033) (xy 81.470065 -138.66845) (xy 81.499542 -138.598604) (xy 81.536277 -138.532287)
			(xy 81.579852 -138.470251) (xy 81.629774 -138.413198) (xy 81.685478 -138.361774) (xy 81.746333 -138.316563)
			(xy 81.811648 -138.278076) (xy 81.880684 -138.24675) (xy 81.952659 -138.22294) (xy 82.026757 -138.206915)
			(xy 82.102138 -138.198856) (xy 82.140044 -138.198352) (xy 82.17795 -138.198856) (xy 82.253331 -138.206915)
			(xy 82.327429 -138.22294) (xy 82.399404 -138.24675) (xy 82.46844 -138.278076) (xy 82.533755 -138.316563)
			(xy 82.560067 -138.336111) (xy 86.198203 -138.336111) (xy 86.204252 -138.260541) (xy 86.218299 -138.186043)
			(xy 86.240185 -138.11346) (xy 86.269662 -138.043614) (xy 86.306397 -137.977297) (xy 86.349972 -137.915261)
			(xy 86.399894 -137.858208) (xy 86.455598 -137.806784) (xy 86.516453 -137.761573) (xy 86.581768 -137.723086)
			(xy 86.650804 -137.69176) (xy 86.722779 -137.66795) (xy 86.796877 -137.651925) (xy 86.872258 -137.643866)
			(xy 86.910164 -137.643362) (xy 86.94807 -137.643866) (xy 87.023451 -137.651925) (xy 87.097549 -137.66795)
			(xy 87.169524 -137.69176) (xy 87.23856 -137.723086) (xy 87.303875 -137.761573) (xy 87.36473 -137.806784)
			(xy 87.420434 -137.858208) (xy 87.470356 -137.915261) (xy 87.513931 -137.977297) (xy 87.550666 -138.043614)
			(xy 87.580143 -138.11346) (xy 87.602029 -138.186043) (xy 87.616076 -138.260541) (xy 87.622125 -138.336111)
			(xy 88.738203 -138.336111) (xy 88.744252 -138.260541) (xy 88.758299 -138.186043) (xy 88.780185 -138.11346)
			(xy 88.809662 -138.043614) (xy 88.846397 -137.977297) (xy 88.889972 -137.915261) (xy 88.939894 -137.858208)
			(xy 88.995598 -137.806784) (xy 89.056453 -137.761573) (xy 89.121768 -137.723086) (xy 89.190804 -137.69176)
			(xy 89.262779 -137.66795) (xy 89.336877 -137.651925) (xy 89.412258 -137.643866) (xy 89.450164 -137.643362)
			(xy 89.48807 -137.643866) (xy 89.563451 -137.651925) (xy 89.637549 -137.66795) (xy 89.709524 -137.69176)
			(xy 89.77856 -137.723086) (xy 89.843875 -137.761573) (xy 89.90473 -137.806784) (xy 89.960434 -137.858208)
			(xy 90.010356 -137.915261) (xy 90.053931 -137.977297) (xy 90.090666 -138.043614) (xy 90.120143 -138.11346)
			(xy 90.142029 -138.186043) (xy 90.156076 -138.260541) (xy 90.162125 -138.336111) (xy 91.278203 -138.336111)
			(xy 91.284252 -138.260541) (xy 91.298299 -138.186043) (xy 91.320185 -138.11346) (xy 91.349662 -138.043614)
			(xy 91.386397 -137.977297) (xy 91.429972 -137.915261) (xy 91.479894 -137.858208) (xy 91.535598 -137.806784)
			(xy 91.596453 -137.761573) (xy 91.661768 -137.723086) (xy 91.730804 -137.69176) (xy 91.802779 -137.66795)
			(xy 91.876877 -137.651925) (xy 91.952258 -137.643866) (xy 91.990164 -137.643362) (xy 92.02807 -137.643866)
			(xy 92.103451 -137.651925) (xy 92.177549 -137.66795) (xy 92.249524 -137.69176) (xy 92.31856 -137.723086)
			(xy 92.383875 -137.761573) (xy 92.44473 -137.806784) (xy 92.500434 -137.858208) (xy 92.550356 -137.915261)
			(xy 92.593931 -137.977297) (xy 92.630666 -138.043614) (xy 92.660143 -138.11346) (xy 92.682029 -138.186043)
			(xy 92.696076 -138.260541) (xy 92.702125 -138.336111) (xy 92.700106 -138.411895) (xy 92.690044 -138.487035)
			(xy 92.672052 -138.56068) (xy 92.646334 -138.631996) (xy 92.613182 -138.700173) (xy 92.57297 -138.764441)
			(xy 92.526155 -138.82407) (xy 92.473267 -138.878386) (xy 92.414905 -138.926772) (xy 92.35173 -138.96868)
			(xy 92.284459 -139.003636) (xy 92.213854 -139.031243) (xy 92.140713 -139.051189) (xy 92.065868 -139.063248)
			(xy 91.990164 -139.067283) (xy 91.91446 -139.063248) (xy 91.839615 -139.051189) (xy 91.766474 -139.031243)
			(xy 91.695869 -139.003636) (xy 91.628598 -138.96868) (xy 91.565423 -138.926772) (xy 91.507061 -138.878386)
			(xy 91.454173 -138.82407) (xy 91.407358 -138.764441) (xy 91.367146 -138.700173) (xy 91.333994 -138.631996)
			(xy 91.308276 -138.56068) (xy 91.290284 -138.487035) (xy 91.280222 -138.411895) (xy 91.278203 -138.336111)
			(xy 90.162125 -138.336111) (xy 90.160106 -138.411895) (xy 90.150044 -138.487035) (xy 90.132052 -138.56068)
			(xy 90.106334 -138.631996) (xy 90.073182 -138.700173) (xy 90.03297 -138.764441) (xy 89.986155 -138.82407)
			(xy 89.933267 -138.878386) (xy 89.874905 -138.926772) (xy 89.81173 -138.96868) (xy 89.744459 -139.003636)
			(xy 89.673854 -139.031243) (xy 89.600713 -139.051189) (xy 89.525868 -139.063248) (xy 89.450164 -139.067283)
			(xy 89.37446 -139.063248) (xy 89.299615 -139.051189) (xy 89.226474 -139.031243) (xy 89.155869 -139.003636)
			(xy 89.088598 -138.96868) (xy 89.025423 -138.926772) (xy 88.967061 -138.878386) (xy 88.914173 -138.82407)
			(xy 88.867358 -138.764441) (xy 88.827146 -138.700173) (xy 88.793994 -138.631996) (xy 88.768276 -138.56068)
			(xy 88.750284 -138.487035) (xy 88.740222 -138.411895) (xy 88.738203 -138.336111) (xy 87.622125 -138.336111)
			(xy 87.620106 -138.411895) (xy 87.610044 -138.487035) (xy 87.592052 -138.56068) (xy 87.566334 -138.631996)
			(xy 87.533182 -138.700173) (xy 87.49297 -138.764441) (xy 87.446155 -138.82407) (xy 87.393267 -138.878386)
			(xy 87.334905 -138.926772) (xy 87.27173 -138.96868) (xy 87.204459 -139.003636) (xy 87.133854 -139.031243)
			(xy 87.060713 -139.051189) (xy 86.985868 -139.063248) (xy 86.910164 -139.067283) (xy 86.83446 -139.063248)
			(xy 86.759615 -139.051189) (xy 86.686474 -139.031243) (xy 86.615869 -139.003636) (xy 86.548598 -138.96868)
			(xy 86.485423 -138.926772) (xy 86.427061 -138.878386) (xy 86.374173 -138.82407) (xy 86.327358 -138.764441)
			(xy 86.287146 -138.700173) (xy 86.253994 -138.631996) (xy 86.228276 -138.56068) (xy 86.210284 -138.487035)
			(xy 86.200222 -138.411895) (xy 86.198203 -138.336111) (xy 82.560067 -138.336111) (xy 82.59461 -138.361774)
			(xy 82.650314 -138.413198) (xy 82.700236 -138.470251) (xy 82.743811 -138.532287) (xy 82.780546 -138.598604)
			(xy 82.810023 -138.66845) (xy 82.831909 -138.741033) (xy 82.845956 -138.815531) (xy 82.852005 -138.891101)
			(xy 82.849986 -138.966885) (xy 82.839924 -139.042025) (xy 82.821932 -139.11567) (xy 82.796214 -139.186986)
			(xy 82.763062 -139.255163) (xy 82.72285 -139.319431) (xy 82.676035 -139.37906) (xy 82.623147 -139.433376)
			(xy 82.564785 -139.481762) (xy 82.50161 -139.52367) (xy 82.434339 -139.558626) (xy 82.363734 -139.586233)
			(xy 82.290842 -139.606111) (xy 84.928203 -139.606111) (xy 84.934252 -139.530541) (xy 84.948299 -139.456043)
			(xy 84.970185 -139.38346) (xy 84.999662 -139.313614) (xy 85.036397 -139.247297) (xy 85.079972 -139.185261)
			(xy 85.129894 -139.128208) (xy 85.185598 -139.076784) (xy 85.246453 -139.031573) (xy 85.311768 -138.993086)
			(xy 85.380804 -138.96176) (xy 85.452779 -138.93795) (xy 85.526877 -138.921925) (xy 85.602258 -138.913866)
			(xy 85.640164 -138.913362) (xy 85.67807 -138.913866) (xy 85.753451 -138.921925) (xy 85.827549 -138.93795)
			(xy 85.899524 -138.96176) (xy 85.96856 -138.993086) (xy 86.033875 -139.031573) (xy 86.09473 -139.076784)
			(xy 86.150434 -139.128208) (xy 86.200356 -139.185261) (xy 86.243931 -139.247297) (xy 86.280666 -139.313614)
			(xy 86.310143 -139.38346) (xy 86.332029 -139.456043) (xy 86.346076 -139.530541) (xy 86.352125 -139.606111)
			(xy 87.468203 -139.606111) (xy 87.474252 -139.530541) (xy 87.488299 -139.456043) (xy 87.510185 -139.38346)
			(xy 87.539662 -139.313614) (xy 87.576397 -139.247297) (xy 87.619972 -139.185261) (xy 87.669894 -139.128208)
			(xy 87.725598 -139.076784) (xy 87.786453 -139.031573) (xy 87.851768 -138.993086) (xy 87.920804 -138.96176)
			(xy 87.992779 -138.93795) (xy 88.066877 -138.921925) (xy 88.142258 -138.913866) (xy 88.180164 -138.913362)
			(xy 88.21807 -138.913866) (xy 88.293451 -138.921925) (xy 88.367549 -138.93795) (xy 88.439524 -138.96176)
			(xy 88.50856 -138.993086) (xy 88.573875 -139.031573) (xy 88.63473 -139.076784) (xy 88.690434 -139.128208)
			(xy 88.740356 -139.185261) (xy 88.783931 -139.247297) (xy 88.820666 -139.313614) (xy 88.850143 -139.38346)
			(xy 88.872029 -139.456043) (xy 88.886076 -139.530541) (xy 88.892125 -139.606111) (xy 90.008203 -139.606111)
			(xy 90.014252 -139.530541) (xy 90.028299 -139.456043) (xy 90.050185 -139.38346) (xy 90.079662 -139.313614)
			(xy 90.116397 -139.247297) (xy 90.159972 -139.185261) (xy 90.209894 -139.128208) (xy 90.265598 -139.076784)
			(xy 90.326453 -139.031573) (xy 90.391768 -138.993086) (xy 90.460804 -138.96176) (xy 90.532779 -138.93795)
			(xy 90.606877 -138.921925) (xy 90.682258 -138.913866) (xy 90.720164 -138.913362) (xy 90.75807 -138.913866)
			(xy 90.833451 -138.921925) (xy 90.907549 -138.93795) (xy 90.979524 -138.96176) (xy 91.04856 -138.993086)
			(xy 91.113875 -139.031573) (xy 91.17473 -139.076784) (xy 91.230434 -139.128208) (xy 91.280356 -139.185261)
			(xy 91.323931 -139.247297) (xy 91.360666 -139.313614) (xy 91.390143 -139.38346) (xy 91.412029 -139.456043)
			(xy 91.426076 -139.530541) (xy 91.432125 -139.606111) (xy 91.430106 -139.681895) (xy 91.420044 -139.757035)
			(xy 91.402052 -139.83068) (xy 91.376334 -139.901996) (xy 91.343182 -139.970173) (xy 91.30297 -140.034441)
			(xy 91.256155 -140.09407) (xy 91.203267 -140.148386) (xy 91.144905 -140.196772) (xy 91.08173 -140.23868)
			(xy 91.014459 -140.273636) (xy 90.943854 -140.301243) (xy 90.870713 -140.321189) (xy 90.795868 -140.333248)
			(xy 90.720164 -140.337283) (xy 90.64446 -140.333248) (xy 90.569615 -140.321189) (xy 90.496474 -140.301243)
			(xy 90.425869 -140.273636) (xy 90.358598 -140.23868) (xy 90.295423 -140.196772) (xy 90.237061 -140.148386)
			(xy 90.184173 -140.09407) (xy 90.137358 -140.034441) (xy 90.097146 -139.970173) (xy 90.063994 -139.901996)
			(xy 90.038276 -139.83068) (xy 90.020284 -139.757035) (xy 90.010222 -139.681895) (xy 90.008203 -139.606111)
			(xy 88.892125 -139.606111) (xy 88.890106 -139.681895) (xy 88.880044 -139.757035) (xy 88.862052 -139.83068)
			(xy 88.836334 -139.901996) (xy 88.803182 -139.970173) (xy 88.76297 -140.034441) (xy 88.716155 -140.09407)
			(xy 88.663267 -140.148386) (xy 88.604905 -140.196772) (xy 88.54173 -140.23868) (xy 88.474459 -140.273636)
			(xy 88.403854 -140.301243) (xy 88.330713 -140.321189) (xy 88.255868 -140.333248) (xy 88.180164 -140.337283)
			(xy 88.10446 -140.333248) (xy 88.029615 -140.321189) (xy 87.956474 -140.301243) (xy 87.885869 -140.273636)
			(xy 87.818598 -140.23868) (xy 87.755423 -140.196772) (xy 87.697061 -140.148386) (xy 87.644173 -140.09407)
			(xy 87.597358 -140.034441) (xy 87.557146 -139.970173) (xy 87.523994 -139.901996) (xy 87.498276 -139.83068)
			(xy 87.480284 -139.757035) (xy 87.470222 -139.681895) (xy 87.468203 -139.606111) (xy 86.352125 -139.606111)
			(xy 86.350106 -139.681895) (xy 86.340044 -139.757035) (xy 86.322052 -139.83068) (xy 86.296334 -139.901996)
			(xy 86.263182 -139.970173) (xy 86.22297 -140.034441) (xy 86.176155 -140.09407) (xy 86.123267 -140.148386)
			(xy 86.064905 -140.196772) (xy 86.00173 -140.23868) (xy 85.934459 -140.273636) (xy 85.863854 -140.301243)
			(xy 85.790713 -140.321189) (xy 85.715868 -140.333248) (xy 85.640164 -140.337283) (xy 85.56446 -140.333248)
			(xy 85.489615 -140.321189) (xy 85.416474 -140.301243) (xy 85.345869 -140.273636) (xy 85.278598 -140.23868)
			(xy 85.215423 -140.196772) (xy 85.157061 -140.148386) (xy 85.104173 -140.09407) (xy 85.057358 -140.034441)
			(xy 85.017146 -139.970173) (xy 84.983994 -139.901996) (xy 84.958276 -139.83068) (xy 84.940284 -139.757035)
			(xy 84.930222 -139.681895) (xy 84.928203 -139.606111) (xy 82.290842 -139.606111) (xy 82.290593 -139.606179)
			(xy 82.215748 -139.618238) (xy 82.140044 -139.622273) (xy 82.06434 -139.618238) (xy 81.989495 -139.606179)
			(xy 81.916354 -139.586233) (xy 81.845749 -139.558626) (xy 81.778478 -139.52367) (xy 81.715303 -139.481762)
			(xy 81.656941 -139.433376) (xy 81.604053 -139.37906) (xy 81.557238 -139.319431) (xy 81.517026 -139.255163)
			(xy 81.483874 -139.186986) (xy 81.458156 -139.11567) (xy 81.440164 -139.042025) (xy 81.430102 -138.966885)
			(xy 81.428083 -138.891101) (xy 80.312005 -138.891101) (xy 80.309986 -138.966885) (xy 80.299924 -139.042025)
			(xy 80.281932 -139.11567) (xy 80.256214 -139.186986) (xy 80.223062 -139.255163) (xy 80.18285 -139.319431)
			(xy 80.136035 -139.37906) (xy 80.083147 -139.433376) (xy 80.024785 -139.481762) (xy 79.96161 -139.52367)
			(xy 79.894339 -139.558626) (xy 79.823734 -139.586233) (xy 79.750593 -139.606179) (xy 79.675748 -139.618238)
			(xy 79.600044 -139.622273) (xy 79.52434 -139.618238) (xy 79.449495 -139.606179) (xy 79.376354 -139.586233)
			(xy 79.305749 -139.558626) (xy 79.238478 -139.52367) (xy 79.175303 -139.481762) (xy 79.116941 -139.433376)
			(xy 79.064053 -139.37906) (xy 79.017238 -139.319431) (xy 78.977026 -139.255163) (xy 78.943874 -139.186986)
			(xy 78.918156 -139.11567) (xy 78.900164 -139.042025) (xy 78.890102 -138.966885) (xy 78.888083 -138.891101)
			(xy 77.772005 -138.891101) (xy 77.769986 -138.966885) (xy 77.759924 -139.042025) (xy 77.741932 -139.11567)
			(xy 77.716214 -139.186986) (xy 77.683062 -139.255163) (xy 77.64285 -139.319431) (xy 77.596035 -139.37906)
			(xy 77.543147 -139.433376) (xy 77.484785 -139.481762) (xy 77.42161 -139.52367) (xy 77.354339 -139.558626)
			(xy 77.283734 -139.586233) (xy 77.210593 -139.606179) (xy 77.135748 -139.618238) (xy 77.060044 -139.622273)
			(xy 76.98434 -139.618238) (xy 76.909495 -139.606179) (xy 76.836354 -139.586233) (xy 76.765749 -139.558626)
			(xy 76.698478 -139.52367) (xy 76.635303 -139.481762) (xy 76.576941 -139.433376) (xy 76.524053 -139.37906)
			(xy 76.477238 -139.319431) (xy 76.437026 -139.255163) (xy 76.403874 -139.186986) (xy 76.378156 -139.11567)
			(xy 76.360164 -139.042025) (xy 76.350102 -138.966885) (xy 76.348083 -138.891101) (xy 75.232005 -138.891101)
			(xy 75.229986 -138.966885) (xy 75.219924 -139.042025) (xy 75.201932 -139.11567) (xy 75.176214 -139.186986)
			(xy 75.143062 -139.255163) (xy 75.10285 -139.319431) (xy 75.056035 -139.37906) (xy 75.003147 -139.433376)
			(xy 74.944785 -139.481762) (xy 74.88161 -139.52367) (xy 74.814339 -139.558626) (xy 74.743734 -139.586233)
			(xy 74.670593 -139.606179) (xy 74.595748 -139.618238) (xy 74.520044 -139.622273) (xy 74.44434 -139.618238)
			(xy 74.369495 -139.606179) (xy 74.296354 -139.586233) (xy 74.225749 -139.558626) (xy 74.158478 -139.52367)
			(xy 74.095303 -139.481762) (xy 74.036941 -139.433376) (xy 73.984053 -139.37906) (xy 73.937238 -139.319431)
			(xy 73.897026 -139.255163) (xy 73.863874 -139.186986) (xy 73.838156 -139.11567) (xy 73.820164 -139.042025)
			(xy 73.810102 -138.966885) (xy 73.808083 -138.891101) (xy 72.692005 -138.891101) (xy 72.689986 -138.966885)
			(xy 72.679924 -139.042025) (xy 72.661932 -139.11567) (xy 72.636214 -139.186986) (xy 72.603062 -139.255163)
			(xy 72.56285 -139.319431) (xy 72.516035 -139.37906) (xy 72.463147 -139.433376) (xy 72.404785 -139.481762)
			(xy 72.34161 -139.52367) (xy 72.274339 -139.558626) (xy 72.203734 -139.586233) (xy 72.130593 -139.606179)
			(xy 72.055748 -139.618238) (xy 71.980044 -139.622273) (xy 71.90434 -139.618238) (xy 71.829495 -139.606179)
			(xy 71.756354 -139.586233) (xy 71.685749 -139.558626) (xy 71.618478 -139.52367) (xy 71.555303 -139.481762)
			(xy 71.496941 -139.433376) (xy 71.444053 -139.37906) (xy 71.397238 -139.319431) (xy 71.357026 -139.255163)
			(xy 71.323874 -139.186986) (xy 71.298156 -139.11567) (xy 71.280164 -139.042025) (xy 71.270102 -138.966885)
			(xy 71.268083 -138.891101) (xy 70.152005 -138.891101) (xy 70.149986 -138.966885) (xy 70.139924 -139.042025)
			(xy 70.121932 -139.11567) (xy 70.096214 -139.186986) (xy 70.063062 -139.255163) (xy 70.02285 -139.319431)
			(xy 69.976035 -139.37906) (xy 69.923147 -139.433376) (xy 69.864785 -139.481762) (xy 69.80161 -139.52367)
			(xy 69.734339 -139.558626) (xy 69.663734 -139.586233) (xy 69.590593 -139.606179) (xy 69.515748 -139.618238)
			(xy 69.440044 -139.622273) (xy 69.36434 -139.618238) (xy 69.289495 -139.606179) (xy 69.216354 -139.586233)
			(xy 69.145749 -139.558626) (xy 69.078478 -139.52367) (xy 69.015303 -139.481762) (xy 68.956941 -139.433376)
			(xy 68.904053 -139.37906) (xy 68.857238 -139.319431) (xy 68.817026 -139.255163) (xy 68.783874 -139.186986)
			(xy 68.758156 -139.11567) (xy 68.740164 -139.042025) (xy 68.730102 -138.966885) (xy 68.728083 -138.891101)
			(xy 67.612005 -138.891101) (xy 67.609986 -138.966885) (xy 67.599924 -139.042025) (xy 67.581932 -139.11567)
			(xy 67.556214 -139.186986) (xy 67.523062 -139.255163) (xy 67.48285 -139.319431) (xy 67.436035 -139.37906)
			(xy 67.383147 -139.433376) (xy 67.324785 -139.481762) (xy 67.26161 -139.52367) (xy 67.194339 -139.558626)
			(xy 67.123734 -139.586233) (xy 67.050593 -139.606179) (xy 66.975748 -139.618238) (xy 66.900044 -139.622273)
			(xy 66.82434 -139.618238) (xy 66.749495 -139.606179) (xy 66.676354 -139.586233) (xy 66.605749 -139.558626)
			(xy 66.538478 -139.52367) (xy 66.475303 -139.481762) (xy 66.416941 -139.433376) (xy 66.364053 -139.37906)
			(xy 66.317238 -139.319431) (xy 66.277026 -139.255163) (xy 66.243874 -139.186986) (xy 66.218156 -139.11567)
			(xy 66.200164 -139.042025) (xy 66.190102 -138.966885) (xy 66.188083 -138.891101) (xy 65.072005 -138.891101)
			(xy 65.069986 -138.966885) (xy 65.059924 -139.042025) (xy 65.041932 -139.11567) (xy 65.016214 -139.186986)
			(xy 64.983062 -139.255163) (xy 64.94285 -139.319431) (xy 64.896035 -139.37906) (xy 64.843147 -139.433376)
			(xy 64.784785 -139.481762) (xy 64.72161 -139.52367) (xy 64.654339 -139.558626) (xy 64.583734 -139.586233)
			(xy 64.510593 -139.606179) (xy 64.435748 -139.618238) (xy 64.360044 -139.622273) (xy 64.28434 -139.618238)
			(xy 64.209495 -139.606179) (xy 64.136354 -139.586233) (xy 64.065749 -139.558626) (xy 63.998478 -139.52367)
			(xy 63.935303 -139.481762) (xy 63.876941 -139.433376) (xy 63.824053 -139.37906) (xy 63.777238 -139.319431)
			(xy 63.737026 -139.255163) (xy 63.703874 -139.186986) (xy 63.678156 -139.11567) (xy 63.660164 -139.042025)
			(xy 63.650102 -138.966885) (xy 63.648083 -138.891101) (xy 42.474686 -138.891101) (xy 42.525578 -138.927542)
			(xy 42.615067 -139.001469) (xy 42.699242 -139.081395) (xy 42.777703 -139.166938) (xy 42.850075 -139.257689)
			(xy 42.916014 -139.353218) (xy 42.975205 -139.453068) (xy 43.027366 -139.556764) (xy 43.072249 -139.663811)
			(xy 43.109639 -139.7737) (xy 43.139359 -139.885907) (xy 43.161267 -139.999897) (xy 43.175258 -140.115126)
			(xy 43.181267 -140.231047) (xy 43.179263 -140.347105) (xy 43.169257 -140.462749) (xy 43.151297 -140.577427)
			(xy 43.125467 -140.690593) (xy 43.091892 -140.801707) (xy 43.063674 -140.876111) (xy 86.198203 -140.876111)
			(xy 86.204252 -140.800541) (xy 86.218299 -140.726043) (xy 86.240185 -140.65346) (xy 86.269662 -140.583614)
			(xy 86.306397 -140.517297) (xy 86.349972 -140.455261) (xy 86.399894 -140.398208) (xy 86.455598 -140.346784)
			(xy 86.516453 -140.301573) (xy 86.581768 -140.263086) (xy 86.650804 -140.23176) (xy 86.722779 -140.20795)
			(xy 86.796877 -140.191925) (xy 86.872258 -140.183866) (xy 86.910164 -140.183362) (xy 86.94807 -140.183866)
			(xy 87.023451 -140.191925) (xy 87.097549 -140.20795) (xy 87.169524 -140.23176) (xy 87.23856 -140.263086)
			(xy 87.303875 -140.301573) (xy 87.36473 -140.346784) (xy 87.420434 -140.398208) (xy 87.470356 -140.455261)
			(xy 87.513931 -140.517297) (xy 87.550666 -140.583614) (xy 87.580143 -140.65346) (xy 87.602029 -140.726043)
			(xy 87.616076 -140.800541) (xy 87.622125 -140.876111) (xy 88.738203 -140.876111) (xy 88.744252 -140.800541)
			(xy 88.758299 -140.726043) (xy 88.780185 -140.65346) (xy 88.809662 -140.583614) (xy 88.846397 -140.517297)
			(xy 88.889972 -140.455261) (xy 88.939894 -140.398208) (xy 88.995598 -140.346784) (xy 89.056453 -140.301573)
			(xy 89.121768 -140.263086) (xy 89.190804 -140.23176) (xy 89.262779 -140.20795) (xy 89.336877 -140.191925)
			(xy 89.412258 -140.183866) (xy 89.450164 -140.183362) (xy 89.48807 -140.183866) (xy 89.563451 -140.191925)
			(xy 89.637549 -140.20795) (xy 89.709524 -140.23176) (xy 89.77856 -140.263086) (xy 89.843875 -140.301573)
			(xy 89.90473 -140.346784) (xy 89.960434 -140.398208) (xy 90.010356 -140.455261) (xy 90.053931 -140.517297)
			(xy 90.090666 -140.583614) (xy 90.120143 -140.65346) (xy 90.142029 -140.726043) (xy 90.156076 -140.800541)
			(xy 90.162125 -140.876111) (xy 91.278203 -140.876111) (xy 91.284252 -140.800541) (xy 91.298299 -140.726043)
			(xy 91.320185 -140.65346) (xy 91.349662 -140.583614) (xy 91.386397 -140.517297) (xy 91.429972 -140.455261)
			(xy 91.479894 -140.398208) (xy 91.535598 -140.346784) (xy 91.596453 -140.301573) (xy 91.661768 -140.263086)
			(xy 91.730804 -140.23176) (xy 91.802779 -140.20795) (xy 91.876877 -140.191925) (xy 91.952258 -140.183866)
			(xy 91.990164 -140.183362) (xy 92.02807 -140.183866) (xy 92.103451 -140.191925) (xy 92.177549 -140.20795)
			(xy 92.249524 -140.23176) (xy 92.31856 -140.263086) (xy 92.383875 -140.301573) (xy 92.44473 -140.346784)
			(xy 92.500434 -140.398208) (xy 92.550356 -140.455261) (xy 92.593931 -140.517297) (xy 92.630666 -140.583614)
			(xy 92.660143 -140.65346) (xy 92.682029 -140.726043) (xy 92.696076 -140.800541) (xy 92.702125 -140.876111)
			(xy 92.700106 -140.951895) (xy 92.690044 -141.027035) (xy 92.672052 -141.10068) (xy 92.646334 -141.171996)
			(xy 92.613182 -141.240173) (xy 92.57297 -141.304441) (xy 92.526155 -141.36407) (xy 92.473267 -141.418386)
			(xy 92.414905 -141.466772) (xy 92.35173 -141.50868) (xy 92.284459 -141.543636) (xy 92.213854 -141.571243)
			(xy 92.178109 -141.580991) (xy 93.155011 -141.580991) (xy 93.161033 -141.464808) (xy 93.175056 -141.349317)
			(xy 93.197014 -141.235069) (xy 93.226801 -141.122608) (xy 93.264276 -141.01247) (xy 93.309261 -140.90518)
			(xy 93.36154 -140.801249) (xy 93.420865 -140.701173) (xy 93.486953 -140.605427) (xy 93.559489 -140.51447)
			(xy 93.638128 -140.428734) (xy 93.722494 -140.348627) (xy 93.812186 -140.274531) (xy 93.906776 -140.206801)
			(xy 94.005814 -140.145757) (xy 94.108827 -140.091692) (xy 94.215324 -140.044862) (xy 94.324799 -140.005491)
			(xy 94.436729 -139.973767) (xy 94.550581 -139.949841) (xy 94.665813 -139.933827) (xy 94.781875 -139.9258)
			(xy 94.840044 -139.925298) (xy 94.898213 -139.9258) (xy 95.014275 -139.933827) (xy 95.129507 -139.949841)
			(xy 95.243359 -139.973767) (xy 95.355289 -140.005491) (xy 95.464764 -140.044862) (xy 95.571261 -140.091692)
			(xy 95.674274 -140.145757) (xy 95.773312 -140.206801) (xy 95.867902 -140.274531) (xy 95.957594 -140.348627)
			(xy 96.04196 -140.428734) (xy 96.120599 -140.51447) (xy 96.193135 -140.605427) (xy 96.259223 -140.701173)
			(xy 96.318548 -140.801249) (xy 96.370827 -140.90518) (xy 96.415812 -141.01247) (xy 96.453287 -141.122608)
			(xy 96.483074 -141.235069) (xy 96.505032 -141.349317) (xy 96.519055 -141.464808) (xy 96.525077 -141.580991)
			(xy 96.523069 -141.697313) (xy 96.51304 -141.813219) (xy 96.495039 -141.928156) (xy 96.469151 -142.041579)
			(xy 96.4355 -142.152944) (xy 96.394246 -142.261723) (xy 96.345585 -142.367397) (xy 96.289749 -142.469461)
			(xy 96.227006 -142.56743) (xy 96.157652 -142.660837) (xy 96.08202 -142.749237) (xy 96.000469 -142.832208)
			(xy 95.913388 -142.909355) (xy 95.821192 -142.98031) (xy 95.72432 -143.044736) (xy 95.623235 -143.102325)
			(xy 95.518417 -143.152802) (xy 95.410366 -143.195928) (xy 95.299598 -143.231497) (xy 95.186639 -143.259339)
			(xy 95.072029 -143.279321) (xy 94.956314 -143.291348) (xy 94.840044 -143.295364) (xy 94.723774 -143.291348)
			(xy 94.608059 -143.279321) (xy 94.493449 -143.259339) (xy 94.38049 -143.231497) (xy 94.269722 -143.195928)
			(xy 94.161671 -143.152802) (xy 94.056853 -143.102325) (xy 93.955768 -143.044736) (xy 93.858896 -142.98031)
			(xy 93.7667 -142.909355) (xy 93.679619 -142.832208) (xy 93.598068 -142.749237) (xy 93.522436 -142.660837)
			(xy 93.453082 -142.56743) (xy 93.390339 -142.469461) (xy 93.334503 -142.367397) (xy 93.285842 -142.261723)
			(xy 93.244588 -142.152944) (xy 93.210937 -142.041579) (xy 93.185049 -141.928156) (xy 93.167048 -141.813219)
			(xy 93.157019 -141.697313) (xy 93.155011 -141.580991) (xy 92.178109 -141.580991) (xy 92.140713 -141.591189)
			(xy 92.065868 -141.603248) (xy 91.990164 -141.607283) (xy 91.91446 -141.603248) (xy 91.839615 -141.591189)
			(xy 91.766474 -141.571243) (xy 91.695869 -141.543636) (xy 91.628598 -141.50868) (xy 91.565423 -141.466772)
			(xy 91.507061 -141.418386) (xy 91.454173 -141.36407) (xy 91.407358 -141.304441) (xy 91.367146 -141.240173)
			(xy 91.333994 -141.171996) (xy 91.308276 -141.10068) (xy 91.290284 -141.027035) (xy 91.280222 -140.951895)
			(xy 91.278203 -140.876111) (xy 90.162125 -140.876111) (xy 90.160106 -140.951895) (xy 90.150044 -141.027035)
			(xy 90.132052 -141.10068) (xy 90.106334 -141.171996) (xy 90.073182 -141.240173) (xy 90.03297 -141.304441)
			(xy 89.986155 -141.36407) (xy 89.933267 -141.418386) (xy 89.874905 -141.466772) (xy 89.81173 -141.50868)
			(xy 89.744459 -141.543636) (xy 89.673854 -141.571243) (xy 89.600713 -141.591189) (xy 89.525868 -141.603248)
			(xy 89.450164 -141.607283) (xy 89.37446 -141.603248) (xy 89.299615 -141.591189) (xy 89.226474 -141.571243)
			(xy 89.155869 -141.543636) (xy 89.088598 -141.50868) (xy 89.025423 -141.466772) (xy 88.967061 -141.418386)
			(xy 88.914173 -141.36407) (xy 88.867358 -141.304441) (xy 88.827146 -141.240173) (xy 88.793994 -141.171996)
			(xy 88.768276 -141.10068) (xy 88.750284 -141.027035) (xy 88.740222 -140.951895) (xy 88.738203 -140.876111)
			(xy 87.622125 -140.876111) (xy 87.620106 -140.951895) (xy 87.610044 -141.027035) (xy 87.592052 -141.10068)
			(xy 87.566334 -141.171996) (xy 87.533182 -141.240173) (xy 87.49297 -141.304441) (xy 87.446155 -141.36407)
			(xy 87.393267 -141.418386) (xy 87.334905 -141.466772) (xy 87.27173 -141.50868) (xy 87.204459 -141.543636)
			(xy 87.133854 -141.571243) (xy 87.060713 -141.591189) (xy 86.985868 -141.603248) (xy 86.910164 -141.607283)
			(xy 86.83446 -141.603248) (xy 86.759615 -141.591189) (xy 86.686474 -141.571243) (xy 86.615869 -141.543636)
			(xy 86.548598 -141.50868) (xy 86.485423 -141.466772) (xy 86.427061 -141.418386) (xy 86.374173 -141.36407)
			(xy 86.327358 -141.304441) (xy 86.287146 -141.240173) (xy 86.253994 -141.171996) (xy 86.228276 -141.10068)
			(xy 86.210284 -141.027035) (xy 86.200222 -140.951895) (xy 86.198203 -140.876111) (xy 43.063674 -140.876111)
			(xy 43.050731 -140.91024) (xy 43.00218 -141.015674) (xy 42.946471 -141.117508) (xy 42.883869 -141.215256)
			(xy 42.814673 -141.308451) (xy 42.739211 -141.396651) (xy 42.657844 -141.479434) (xy 42.57096 -141.556407)
			(xy 42.525855 -141.591121) (xy 63.648083 -141.591121) (xy 63.654132 -141.515551) (xy 63.668179 -141.441053)
			(xy 63.690065 -141.36847) (xy 63.719542 -141.298624) (xy 63.756277 -141.232307) (xy 63.799852 -141.170271)
			(xy 63.849774 -141.113218) (xy 63.905478 -141.061794) (xy 63.966333 -141.016583) (xy 64.031648 -140.978096)
			(xy 64.100684 -140.94677) (xy 64.172659 -140.92296) (xy 64.246757 -140.906935) (xy 64.322138 -140.898876)
			(xy 64.360044 -140.898372) (xy 64.39795 -140.898876) (xy 64.473331 -140.906935) (xy 64.547429 -140.92296)
			(xy 64.619404 -140.94677) (xy 64.68844 -140.978096) (xy 64.753755 -141.016583) (xy 64.81461 -141.061794)
			(xy 64.870314 -141.113218) (xy 64.920236 -141.170271) (xy 64.963811 -141.232307) (xy 65.000546 -141.298624)
			(xy 65.030023 -141.36847) (xy 65.051909 -141.441053) (xy 65.065956 -141.515551) (xy 65.072005 -141.591121)
			(xy 66.188083 -141.591121) (xy 66.194132 -141.515551) (xy 66.208179 -141.441053) (xy 66.230065 -141.36847)
			(xy 66.259542 -141.298624) (xy 66.296277 -141.232307) (xy 66.339852 -141.170271) (xy 66.389774 -141.113218)
			(xy 66.445478 -141.061794) (xy 66.506333 -141.016583) (xy 66.571648 -140.978096) (xy 66.640684 -140.94677)
			(xy 66.712659 -140.92296) (xy 66.786757 -140.906935) (xy 66.862138 -140.898876) (xy 66.900044 -140.898372)
			(xy 66.93795 -140.898876) (xy 67.013331 -140.906935) (xy 67.087429 -140.92296) (xy 67.159404 -140.94677)
			(xy 67.22844 -140.978096) (xy 67.293755 -141.016583) (xy 67.35461 -141.061794) (xy 67.410314 -141.113218)
			(xy 67.460236 -141.170271) (xy 67.503811 -141.232307) (xy 67.540546 -141.298624) (xy 67.570023 -141.36847)
			(xy 67.591909 -141.441053) (xy 67.605956 -141.515551) (xy 67.612005 -141.591121) (xy 68.728083 -141.591121)
			(xy 68.734132 -141.515551) (xy 68.748179 -141.441053) (xy 68.770065 -141.36847) (xy 68.799542 -141.298624)
			(xy 68.836277 -141.232307) (xy 68.879852 -141.170271) (xy 68.929774 -141.113218) (xy 68.985478 -141.061794)
			(xy 69.046333 -141.016583) (xy 69.111648 -140.978096) (xy 69.180684 -140.94677) (xy 69.252659 -140.92296)
			(xy 69.326757 -140.906935) (xy 69.402138 -140.898876) (xy 69.440044 -140.898372) (xy 69.47795 -140.898876)
			(xy 69.553331 -140.906935) (xy 69.627429 -140.92296) (xy 69.699404 -140.94677) (xy 69.76844 -140.978096)
			(xy 69.833755 -141.016583) (xy 69.89461 -141.061794) (xy 69.950314 -141.113218) (xy 70.000236 -141.170271)
			(xy 70.043811 -141.232307) (xy 70.080546 -141.298624) (xy 70.110023 -141.36847) (xy 70.131909 -141.441053)
			(xy 70.145956 -141.515551) (xy 70.152005 -141.591121) (xy 71.268083 -141.591121) (xy 71.274132 -141.515551)
			(xy 71.288179 -141.441053) (xy 71.310065 -141.36847) (xy 71.339542 -141.298624) (xy 71.376277 -141.232307)
			(xy 71.419852 -141.170271) (xy 71.469774 -141.113218) (xy 71.525478 -141.061794) (xy 71.586333 -141.016583)
			(xy 71.651648 -140.978096) (xy 71.720684 -140.94677) (xy 71.792659 -140.92296) (xy 71.866757 -140.906935)
			(xy 71.942138 -140.898876) (xy 71.980044 -140.898372) (xy 72.01795 -140.898876) (xy 72.093331 -140.906935)
			(xy 72.167429 -140.92296) (xy 72.239404 -140.94677) (xy 72.30844 -140.978096) (xy 72.373755 -141.016583)
			(xy 72.43461 -141.061794) (xy 72.490314 -141.113218) (xy 72.540236 -141.170271) (xy 72.583811 -141.232307)
			(xy 72.620546 -141.298624) (xy 72.650023 -141.36847) (xy 72.671909 -141.441053) (xy 72.685956 -141.515551)
			(xy 72.692005 -141.591121) (xy 73.808083 -141.591121) (xy 73.814132 -141.515551) (xy 73.828179 -141.441053)
			(xy 73.850065 -141.36847) (xy 73.879542 -141.298624) (xy 73.916277 -141.232307) (xy 73.959852 -141.170271)
			(xy 74.009774 -141.113218) (xy 74.065478 -141.061794) (xy 74.126333 -141.016583) (xy 74.191648 -140.978096)
			(xy 74.260684 -140.94677) (xy 74.332659 -140.92296) (xy 74.406757 -140.906935) (xy 74.482138 -140.898876)
			(xy 74.520044 -140.898372) (xy 74.55795 -140.898876) (xy 74.633331 -140.906935) (xy 74.707429 -140.92296)
			(xy 74.779404 -140.94677) (xy 74.84844 -140.978096) (xy 74.913755 -141.016583) (xy 74.97461 -141.061794)
			(xy 75.030314 -141.113218) (xy 75.080236 -141.170271) (xy 75.123811 -141.232307) (xy 75.160546 -141.298624)
			(xy 75.190023 -141.36847) (xy 75.211909 -141.441053) (xy 75.225956 -141.515551) (xy 75.232005 -141.591121)
			(xy 76.348083 -141.591121) (xy 76.354132 -141.515551) (xy 76.368179 -141.441053) (xy 76.390065 -141.36847)
			(xy 76.419542 -141.298624) (xy 76.456277 -141.232307) (xy 76.499852 -141.170271) (xy 76.549774 -141.113218)
			(xy 76.605478 -141.061794) (xy 76.666333 -141.016583) (xy 76.731648 -140.978096) (xy 76.800684 -140.94677)
			(xy 76.872659 -140.92296) (xy 76.946757 -140.906935) (xy 77.022138 -140.898876) (xy 77.060044 -140.898372)
			(xy 77.09795 -140.898876) (xy 77.173331 -140.906935) (xy 77.247429 -140.92296) (xy 77.319404 -140.94677)
			(xy 77.38844 -140.978096) (xy 77.453755 -141.016583) (xy 77.51461 -141.061794) (xy 77.570314 -141.113218)
			(xy 77.620236 -141.170271) (xy 77.663811 -141.232307) (xy 77.700546 -141.298624) (xy 77.730023 -141.36847)
			(xy 77.751909 -141.441053) (xy 77.765956 -141.515551) (xy 77.772005 -141.591121) (xy 78.888083 -141.591121)
			(xy 78.894132 -141.515551) (xy 78.908179 -141.441053) (xy 78.930065 -141.36847) (xy 78.959542 -141.298624)
			(xy 78.996277 -141.232307) (xy 79.039852 -141.170271) (xy 79.089774 -141.113218) (xy 79.145478 -141.061794)
			(xy 79.206333 -141.016583) (xy 79.271648 -140.978096) (xy 79.340684 -140.94677) (xy 79.412659 -140.92296)
			(xy 79.486757 -140.906935) (xy 79.562138 -140.898876) (xy 79.600044 -140.898372) (xy 79.63795 -140.898876)
			(xy 79.713331 -140.906935) (xy 79.787429 -140.92296) (xy 79.859404 -140.94677) (xy 79.92844 -140.978096)
			(xy 79.993755 -141.016583) (xy 80.05461 -141.061794) (xy 80.110314 -141.113218) (xy 80.160236 -141.170271)
			(xy 80.203811 -141.232307) (xy 80.240546 -141.298624) (xy 80.270023 -141.36847) (xy 80.291909 -141.441053)
			(xy 80.305956 -141.515551) (xy 80.312005 -141.591121) (xy 81.428083 -141.591121) (xy 81.434132 -141.515551)
			(xy 81.448179 -141.441053) (xy 81.470065 -141.36847) (xy 81.499542 -141.298624) (xy 81.536277 -141.232307)
			(xy 81.579852 -141.170271) (xy 81.629774 -141.113218) (xy 81.685478 -141.061794) (xy 81.746333 -141.016583)
			(xy 81.811648 -140.978096) (xy 81.880684 -140.94677) (xy 81.952659 -140.92296) (xy 82.026757 -140.906935)
			(xy 82.102138 -140.898876) (xy 82.140044 -140.898372) (xy 82.17795 -140.898876) (xy 82.253331 -140.906935)
			(xy 82.327429 -140.92296) (xy 82.399404 -140.94677) (xy 82.46844 -140.978096) (xy 82.533755 -141.016583)
			(xy 82.59461 -141.061794) (xy 82.650314 -141.113218) (xy 82.700236 -141.170271) (xy 82.743811 -141.232307)
			(xy 82.780546 -141.298624) (xy 82.810023 -141.36847) (xy 82.831909 -141.441053) (xy 82.845956 -141.515551)
			(xy 82.852005 -141.591121) (xy 82.849986 -141.666905) (xy 82.839924 -141.742045) (xy 82.821932 -141.81569)
			(xy 82.796214 -141.887006) (xy 82.763062 -141.955183) (xy 82.72285 -142.019451) (xy 82.676035 -142.07908)
			(xy 82.623147 -142.133396) (xy 82.60781 -142.146111) (xy 84.928203 -142.146111) (xy 84.934252 -142.070541)
			(xy 84.948299 -141.996043) (xy 84.970185 -141.92346) (xy 84.999662 -141.853614) (xy 85.036397 -141.787297)
			(xy 85.079972 -141.725261) (xy 85.129894 -141.668208) (xy 85.185598 -141.616784) (xy 85.246453 -141.571573)
			(xy 85.311768 -141.533086) (xy 85.380804 -141.50176) (xy 85.452779 -141.47795) (xy 85.526877 -141.461925)
			(xy 85.602258 -141.453866) (xy 85.640164 -141.453362) (xy 85.67807 -141.453866) (xy 85.753451 -141.461925)
			(xy 85.827549 -141.47795) (xy 85.899524 -141.50176) (xy 85.96856 -141.533086) (xy 86.033875 -141.571573)
			(xy 86.09473 -141.616784) (xy 86.150434 -141.668208) (xy 86.200356 -141.725261) (xy 86.243931 -141.787297)
			(xy 86.280666 -141.853614) (xy 86.310143 -141.92346) (xy 86.332029 -141.996043) (xy 86.346076 -142.070541)
			(xy 86.352125 -142.146111) (xy 87.468203 -142.146111) (xy 87.474252 -142.070541) (xy 87.488299 -141.996043)
			(xy 87.510185 -141.92346) (xy 87.539662 -141.853614) (xy 87.576397 -141.787297) (xy 87.619972 -141.725261)
			(xy 87.669894 -141.668208) (xy 87.725598 -141.616784) (xy 87.786453 -141.571573) (xy 87.851768 -141.533086)
			(xy 87.920804 -141.50176) (xy 87.992779 -141.47795) (xy 88.066877 -141.461925) (xy 88.142258 -141.453866)
			(xy 88.180164 -141.453362) (xy 88.21807 -141.453866) (xy 88.293451 -141.461925) (xy 88.367549 -141.47795)
			(xy 88.439524 -141.50176) (xy 88.50856 -141.533086) (xy 88.573875 -141.571573) (xy 88.63473 -141.616784)
			(xy 88.690434 -141.668208) (xy 88.740356 -141.725261) (xy 88.783931 -141.787297) (xy 88.820666 -141.853614)
			(xy 88.850143 -141.92346) (xy 88.872029 -141.996043) (xy 88.886076 -142.070541) (xy 88.892125 -142.146111)
			(xy 90.008203 -142.146111) (xy 90.014252 -142.070541) (xy 90.028299 -141.996043) (xy 90.050185 -141.92346)
			(xy 90.079662 -141.853614) (xy 90.116397 -141.787297) (xy 90.159972 -141.725261) (xy 90.209894 -141.668208)
			(xy 90.265598 -141.616784) (xy 90.326453 -141.571573) (xy 90.391768 -141.533086) (xy 90.460804 -141.50176)
			(xy 90.532779 -141.47795) (xy 90.606877 -141.461925) (xy 90.682258 -141.453866) (xy 90.720164 -141.453362)
			(xy 90.75807 -141.453866) (xy 90.833451 -141.461925) (xy 90.907549 -141.47795) (xy 90.979524 -141.50176)
			(xy 91.04856 -141.533086) (xy 91.113875 -141.571573) (xy 91.17473 -141.616784) (xy 91.230434 -141.668208)
			(xy 91.280356 -141.725261) (xy 91.323931 -141.787297) (xy 91.360666 -141.853614) (xy 91.390143 -141.92346)
			(xy 91.412029 -141.996043) (xy 91.426076 -142.070541) (xy 91.432125 -142.146111) (xy 91.430106 -142.221895)
			(xy 91.420044 -142.297035) (xy 91.402052 -142.37068) (xy 91.376334 -142.441996) (xy 91.343182 -142.510173)
			(xy 91.30297 -142.574441) (xy 91.256155 -142.63407) (xy 91.203267 -142.688386) (xy 91.144905 -142.736772)
			(xy 91.08173 -142.77868) (xy 91.014459 -142.813636) (xy 90.943854 -142.841243) (xy 90.870713 -142.861189)
			(xy 90.795868 -142.873248) (xy 90.720164 -142.877283) (xy 90.64446 -142.873248) (xy 90.569615 -142.861189)
			(xy 90.496474 -142.841243) (xy 90.425869 -142.813636) (xy 90.358598 -142.77868) (xy 90.295423 -142.736772)
			(xy 90.237061 -142.688386) (xy 90.184173 -142.63407) (xy 90.137358 -142.574441) (xy 90.097146 -142.510173)
			(xy 90.063994 -142.441996) (xy 90.038276 -142.37068) (xy 90.020284 -142.297035) (xy 90.010222 -142.221895)
			(xy 90.008203 -142.146111) (xy 88.892125 -142.146111) (xy 88.890106 -142.221895) (xy 88.880044 -142.297035)
			(xy 88.862052 -142.37068) (xy 88.836334 -142.441996) (xy 88.803182 -142.510173) (xy 88.76297 -142.574441)
			(xy 88.716155 -142.63407) (xy 88.663267 -142.688386) (xy 88.604905 -142.736772) (xy 88.54173 -142.77868)
			(xy 88.474459 -142.813636) (xy 88.403854 -142.841243) (xy 88.330713 -142.861189) (xy 88.255868 -142.873248)
			(xy 88.180164 -142.877283) (xy 88.10446 -142.873248) (xy 88.029615 -142.861189) (xy 87.956474 -142.841243)
			(xy 87.885869 -142.813636) (xy 87.818598 -142.77868) (xy 87.755423 -142.736772) (xy 87.697061 -142.688386)
			(xy 87.644173 -142.63407) (xy 87.597358 -142.574441) (xy 87.557146 -142.510173) (xy 87.523994 -142.441996)
			(xy 87.498276 -142.37068) (xy 87.480284 -142.297035) (xy 87.470222 -142.221895) (xy 87.468203 -142.146111)
			(xy 86.352125 -142.146111) (xy 86.350106 -142.221895) (xy 86.340044 -142.297035) (xy 86.322052 -142.37068)
			(xy 86.296334 -142.441996) (xy 86.263182 -142.510173) (xy 86.22297 -142.574441) (xy 86.176155 -142.63407)
			(xy 86.123267 -142.688386) (xy 86.064905 -142.736772) (xy 86.00173 -142.77868) (xy 85.934459 -142.813636)
			(xy 85.863854 -142.841243) (xy 85.790713 -142.861189) (xy 85.715868 -142.873248) (xy 85.640164 -142.877283)
			(xy 85.56446 -142.873248) (xy 85.489615 -142.861189) (xy 85.416474 -142.841243) (xy 85.345869 -142.813636)
			(xy 85.278598 -142.77868) (xy 85.215423 -142.736772) (xy 85.157061 -142.688386) (xy 85.104173 -142.63407)
			(xy 85.057358 -142.574441) (xy 85.017146 -142.510173) (xy 84.983994 -142.441996) (xy 84.958276 -142.37068)
			(xy 84.940284 -142.297035) (xy 84.930222 -142.221895) (xy 84.928203 -142.146111) (xy 82.60781 -142.146111)
			(xy 82.564785 -142.181782) (xy 82.50161 -142.22369) (xy 82.434339 -142.258646) (xy 82.363734 -142.286253)
			(xy 82.290593 -142.306199) (xy 82.215748 -142.318258) (xy 82.140044 -142.322293) (xy 82.06434 -142.318258)
			(xy 81.989495 -142.306199) (xy 81.916354 -142.286253) (xy 81.845749 -142.258646) (xy 81.778478 -142.22369)
			(xy 81.715303 -142.181782) (xy 81.656941 -142.133396) (xy 81.604053 -142.07908) (xy 81.557238 -142.019451)
			(xy 81.517026 -141.955183) (xy 81.483874 -141.887006) (xy 81.458156 -141.81569) (xy 81.440164 -141.742045)
			(xy 81.430102 -141.666905) (xy 81.428083 -141.591121) (xy 80.312005 -141.591121) (xy 80.309986 -141.666905)
			(xy 80.299924 -141.742045) (xy 80.281932 -141.81569) (xy 80.256214 -141.887006) (xy 80.223062 -141.955183)
			(xy 80.18285 -142.019451) (xy 80.136035 -142.07908) (xy 80.083147 -142.133396) (xy 80.024785 -142.181782)
			(xy 79.96161 -142.22369) (xy 79.894339 -142.258646) (xy 79.823734 -142.286253) (xy 79.750593 -142.306199)
			(xy 79.675748 -142.318258) (xy 79.600044 -142.322293) (xy 79.52434 -142.318258) (xy 79.449495 -142.306199)
			(xy 79.376354 -142.286253) (xy 79.305749 -142.258646) (xy 79.238478 -142.22369) (xy 79.175303 -142.181782)
			(xy 79.116941 -142.133396) (xy 79.064053 -142.07908) (xy 79.017238 -142.019451) (xy 78.977026 -141.955183)
			(xy 78.943874 -141.887006) (xy 78.918156 -141.81569) (xy 78.900164 -141.742045) (xy 78.890102 -141.666905)
			(xy 78.888083 -141.591121) (xy 77.772005 -141.591121) (xy 77.769986 -141.666905) (xy 77.759924 -141.742045)
			(xy 77.741932 -141.81569) (xy 77.716214 -141.887006) (xy 77.683062 -141.955183) (xy 77.64285 -142.019451)
			(xy 77.596035 -142.07908) (xy 77.543147 -142.133396) (xy 77.484785 -142.181782) (xy 77.42161 -142.22369)
			(xy 77.354339 -142.258646) (xy 77.283734 -142.286253) (xy 77.210593 -142.306199) (xy 77.135748 -142.318258)
			(xy 77.060044 -142.322293) (xy 76.98434 -142.318258) (xy 76.909495 -142.306199) (xy 76.836354 -142.286253)
			(xy 76.765749 -142.258646) (xy 76.698478 -142.22369) (xy 76.635303 -142.181782) (xy 76.576941 -142.133396)
			(xy 76.524053 -142.07908) (xy 76.477238 -142.019451) (xy 76.437026 -141.955183) (xy 76.403874 -141.887006)
			(xy 76.378156 -141.81569) (xy 76.360164 -141.742045) (xy 76.350102 -141.666905) (xy 76.348083 -141.591121)
			(xy 75.232005 -141.591121) (xy 75.229986 -141.666905) (xy 75.219924 -141.742045) (xy 75.201932 -141.81569)
			(xy 75.176214 -141.887006) (xy 75.143062 -141.955183) (xy 75.10285 -142.019451) (xy 75.056035 -142.07908)
			(xy 75.003147 -142.133396) (xy 74.944785 -142.181782) (xy 74.88161 -142.22369) (xy 74.814339 -142.258646)
			(xy 74.743734 -142.286253) (xy 74.670593 -142.306199) (xy 74.595748 -142.318258) (xy 74.520044 -142.322293)
			(xy 74.44434 -142.318258) (xy 74.369495 -142.306199) (xy 74.296354 -142.286253) (xy 74.225749 -142.258646)
			(xy 74.158478 -142.22369) (xy 74.095303 -142.181782) (xy 74.036941 -142.133396) (xy 73.984053 -142.07908)
			(xy 73.937238 -142.019451) (xy 73.897026 -141.955183) (xy 73.863874 -141.887006) (xy 73.838156 -141.81569)
			(xy 73.820164 -141.742045) (xy 73.810102 -141.666905) (xy 73.808083 -141.591121) (xy 72.692005 -141.591121)
			(xy 72.689986 -141.666905) (xy 72.679924 -141.742045) (xy 72.661932 -141.81569) (xy 72.636214 -141.887006)
			(xy 72.603062 -141.955183) (xy 72.56285 -142.019451) (xy 72.516035 -142.07908) (xy 72.463147 -142.133396)
			(xy 72.404785 -142.181782) (xy 72.34161 -142.22369) (xy 72.274339 -142.258646) (xy 72.203734 -142.286253)
			(xy 72.130593 -142.306199) (xy 72.055748 -142.318258) (xy 71.980044 -142.322293) (xy 71.90434 -142.318258)
			(xy 71.829495 -142.306199) (xy 71.756354 -142.286253) (xy 71.685749 -142.258646) (xy 71.618478 -142.22369)
			(xy 71.555303 -142.181782) (xy 71.496941 -142.133396) (xy 71.444053 -142.07908) (xy 71.397238 -142.019451)
			(xy 71.357026 -141.955183) (xy 71.323874 -141.887006) (xy 71.298156 -141.81569) (xy 71.280164 -141.742045)
			(xy 71.270102 -141.666905) (xy 71.268083 -141.591121) (xy 70.152005 -141.591121) (xy 70.149986 -141.666905)
			(xy 70.139924 -141.742045) (xy 70.121932 -141.81569) (xy 70.096214 -141.887006) (xy 70.063062 -141.955183)
			(xy 70.02285 -142.019451) (xy 69.976035 -142.07908) (xy 69.923147 -142.133396) (xy 69.864785 -142.181782)
			(xy 69.80161 -142.22369) (xy 69.734339 -142.258646) (xy 69.663734 -142.286253) (xy 69.590593 -142.306199)
			(xy 69.515748 -142.318258) (xy 69.440044 -142.322293) (xy 69.36434 -142.318258) (xy 69.289495 -142.306199)
			(xy 69.216354 -142.286253) (xy 69.145749 -142.258646) (xy 69.078478 -142.22369) (xy 69.015303 -142.181782)
			(xy 68.956941 -142.133396) (xy 68.904053 -142.07908) (xy 68.857238 -142.019451) (xy 68.817026 -141.955183)
			(xy 68.783874 -141.887006) (xy 68.758156 -141.81569) (xy 68.740164 -141.742045) (xy 68.730102 -141.666905)
			(xy 68.728083 -141.591121) (xy 67.612005 -141.591121) (xy 67.609986 -141.666905) (xy 67.599924 -141.742045)
			(xy 67.581932 -141.81569) (xy 67.556214 -141.887006) (xy 67.523062 -141.955183) (xy 67.48285 -142.019451)
			(xy 67.436035 -142.07908) (xy 67.383147 -142.133396) (xy 67.324785 -142.181782) (xy 67.26161 -142.22369)
			(xy 67.194339 -142.258646) (xy 67.123734 -142.286253) (xy 67.050593 -142.306199) (xy 66.975748 -142.318258)
			(xy 66.900044 -142.322293) (xy 66.82434 -142.318258) (xy 66.749495 -142.306199) (xy 66.676354 -142.286253)
			(xy 66.605749 -142.258646) (xy 66.538478 -142.22369) (xy 66.475303 -142.181782) (xy 66.416941 -142.133396)
			(xy 66.364053 -142.07908) (xy 66.317238 -142.019451) (xy 66.277026 -141.955183) (xy 66.243874 -141.887006)
			(xy 66.218156 -141.81569) (xy 66.200164 -141.742045) (xy 66.190102 -141.666905) (xy 66.188083 -141.591121)
			(xy 65.072005 -141.591121) (xy 65.069986 -141.666905) (xy 65.059924 -141.742045) (xy 65.041932 -141.81569)
			(xy 65.016214 -141.887006) (xy 64.983062 -141.955183) (xy 64.94285 -142.019451) (xy 64.896035 -142.07908)
			(xy 64.843147 -142.133396) (xy 64.784785 -142.181782) (xy 64.72161 -142.22369) (xy 64.654339 -142.258646)
			(xy 64.583734 -142.286253) (xy 64.510593 -142.306199) (xy 64.435748 -142.318258) (xy 64.360044 -142.322293)
			(xy 64.28434 -142.318258) (xy 64.209495 -142.306199) (xy 64.136354 -142.286253) (xy 64.065749 -142.258646)
			(xy 63.998478 -142.22369) (xy 63.935303 -142.181782) (xy 63.876941 -142.133396) (xy 63.824053 -142.07908)
			(xy 63.777238 -142.019451) (xy 63.737026 -141.955183) (xy 63.703874 -141.887006) (xy 63.678156 -141.81569)
			(xy 63.660164 -141.742045) (xy 63.650102 -141.666905) (xy 63.648083 -141.591121) (xy 42.525855 -141.591121)
			(xy 42.478973 -141.627202) (xy 42.38232 -141.691482) (xy 42.281463 -141.74894) (xy 42.176883 -141.799304)
			(xy 42.069076 -141.842332) (xy 41.958559 -141.87782) (xy 41.845856 -141.905599) (xy 41.731505 -141.925536)
			(xy 41.616051 -141.937537) (xy 41.500044 -141.941543) (xy 41.384037 -141.937537) (xy 41.268583 -141.925536)
			(xy 41.154232 -141.905599) (xy 41.041529 -141.87782) (xy 40.931012 -141.842332) (xy 40.823205 -141.799304)
			(xy 40.718625 -141.74894) (xy 40.617768 -141.691482) (xy 40.521115 -141.627202) (xy 40.429128 -141.556407)
			(xy 40.342244 -141.479434) (xy 40.260877 -141.396651) (xy 40.185415 -141.308451) (xy 40.116219 -141.215256)
			(xy 40.053617 -141.117508) (xy 39.997908 -141.015674) (xy 39.949357 -140.91024) (xy 39.908196 -140.801707)
			(xy 39.874621 -140.690593) (xy 39.848791 -140.577427) (xy 39.830831 -140.462749) (xy 39.820825 -140.347105)
			(xy 39.818821 -140.231047) (xy 28.804108 -140.231047) (xy 28.804108 -143.833358) (xy 29.519874 -143.833358)
			(xy 29.519874 -143.746458) (xy 29.527892 -143.659929) (xy 29.54386 -143.574509) (xy 29.567641 -143.490927)
			(xy 29.599033 -143.409895) (xy 29.637767 -143.332106) (xy 29.683514 -143.258222) (xy 29.735883 -143.188875)
			(xy 29.794427 -143.124655) (xy 29.858647 -143.066111) (xy 29.927994 -143.013742) (xy 30.001878 -142.967995)
			(xy 30.079667 -142.929261) (xy 30.160699 -142.897869) (xy 30.244281 -142.874088) (xy 30.329701 -142.85812)
			(xy 30.41623 -142.850102) (xy 30.45968 -142.8496) (xy 30.50313 -142.850102) (xy 30.589659 -142.85812)
			(xy 30.675079 -142.874088) (xy 30.758661 -142.897869) (xy 30.839693 -142.929261) (xy 30.917482 -142.967995)
			(xy 30.991366 -143.013742) (xy 31.060713 -143.066111) (xy 31.124933 -143.124655) (xy 31.183477 -143.188875)
			(xy 31.235846 -143.258222) (xy 31.281593 -143.332106) (xy 31.320327 -143.409895) (xy 31.351719 -143.490927)
			(xy 31.3755 -143.574509) (xy 31.391468 -143.659929) (xy 31.399486 -143.746458) (xy 31.399486 -143.833358)
			(xy 34.599874 -143.833358) (xy 34.599874 -143.746458) (xy 34.607892 -143.659929) (xy 34.62386 -143.574509)
			(xy 34.647641 -143.490927) (xy 34.679033 -143.409895) (xy 34.717767 -143.332106) (xy 34.763514 -143.258222)
			(xy 34.815883 -143.188875) (xy 34.874427 -143.124655) (xy 34.938647 -143.066111) (xy 35.007994 -143.013742)
			(xy 35.081878 -142.967995) (xy 35.159667 -142.929261) (xy 35.240699 -142.897869) (xy 35.324281 -142.874088)
			(xy 35.409701 -142.85812) (xy 35.49623 -142.850102) (xy 35.53968 -142.8496) (xy 35.58313 -142.850102)
			(xy 35.669659 -142.85812) (xy 35.755079 -142.874088) (xy 35.838661 -142.897869) (xy 35.919693 -142.929261)
			(xy 35.997482 -142.967995) (xy 36.071366 -143.013742) (xy 36.140713 -143.066111) (xy 36.204933 -143.124655)
			(xy 36.263477 -143.188875) (xy 36.315846 -143.258222) (xy 36.361593 -143.332106) (xy 36.400327 -143.409895)
			(xy 36.431719 -143.490927) (xy 36.4555 -143.574509) (xy 36.471468 -143.659929) (xy 36.479486 -143.746458)
			(xy 36.479486 -143.833358) (xy 36.471468 -143.919887) (xy 36.4555 -144.005307) (xy 36.431719 -144.088889)
			(xy 36.400327 -144.169921) (xy 36.361593 -144.24771) (xy 36.315846 -144.321594) (xy 36.263477 -144.390941)
			(xy 36.204933 -144.455161) (xy 36.140713 -144.513705) (xy 36.071366 -144.566074) (xy 35.997482 -144.611821)
			(xy 35.919693 -144.650555) (xy 35.838661 -144.681947) (xy 35.755079 -144.705728) (xy 35.669659 -144.721696)
			(xy 35.58313 -144.729714) (xy 35.49623 -144.729714) (xy 35.409701 -144.721696) (xy 35.324281 -144.705728)
			(xy 35.240699 -144.681947) (xy 35.159667 -144.650555) (xy 35.081878 -144.611821) (xy 35.007994 -144.566074)
			(xy 34.938647 -144.513705) (xy 34.874427 -144.455161) (xy 34.815883 -144.390941) (xy 34.763514 -144.321594)
			(xy 34.717767 -144.24771) (xy 34.679033 -144.169921) (xy 34.647641 -144.088889) (xy 34.62386 -144.005307)
			(xy 34.607892 -143.919887) (xy 34.599874 -143.833358) (xy 31.399486 -143.833358) (xy 31.391468 -143.919887)
			(xy 31.3755 -144.005307) (xy 31.351719 -144.088889) (xy 31.320327 -144.169921) (xy 31.281593 -144.24771)
			(xy 31.235846 -144.321594) (xy 31.183477 -144.390941) (xy 31.124933 -144.455161) (xy 31.060713 -144.513705)
			(xy 30.991366 -144.566074) (xy 30.917482 -144.611821) (xy 30.839693 -144.650555) (xy 30.758661 -144.681947)
			(xy 30.675079 -144.705728) (xy 30.589659 -144.721696) (xy 30.50313 -144.729714) (xy 30.41623 -144.729714)
			(xy 30.329701 -144.721696) (xy 30.244281 -144.705728) (xy 30.160699 -144.681947) (xy 30.079667 -144.650555)
			(xy 30.001878 -144.611821) (xy 29.927994 -144.566074) (xy 29.858647 -144.513705) (xy 29.794427 -144.455161)
			(xy 29.735883 -144.390941) (xy 29.683514 -144.321594) (xy 29.637767 -144.24771) (xy 29.599033 -144.169921)
			(xy 29.567641 -144.088889) (xy 29.54386 -144.005307) (xy 29.527892 -143.919887) (xy 29.519874 -143.833358)
			(xy 28.804108 -143.833358) (xy 28.804108 -146.373358) (xy 29.519874 -146.373358) (xy 29.519874 -146.286458)
			(xy 29.527892 -146.199929) (xy 29.54386 -146.114509) (xy 29.567641 -146.030927) (xy 29.599033 -145.949895)
			(xy 29.637767 -145.872106) (xy 29.683514 -145.798222) (xy 29.735883 -145.728875) (xy 29.794427 -145.664655)
			(xy 29.858647 -145.606111) (xy 29.927994 -145.553742) (xy 30.001878 -145.507995) (xy 30.079667 -145.469261)
			(xy 30.160699 -145.437869) (xy 30.244281 -145.414088) (xy 30.329701 -145.39812) (xy 30.41623 -145.390102)
			(xy 30.45968 -145.3896) (xy 30.50313 -145.390102) (xy 30.589659 -145.39812) (xy 30.675079 -145.414088)
			(xy 30.758661 -145.437869) (xy 30.839693 -145.469261) (xy 30.917482 -145.507995) (xy 30.991366 -145.553742)
			(xy 31.060713 -145.606111) (xy 31.124933 -145.664655) (xy 31.183477 -145.728875) (xy 31.235846 -145.798222)
			(xy 31.281593 -145.872106) (xy 31.320327 -145.949895) (xy 31.351719 -146.030927) (xy 31.3755 -146.114509)
			(xy 31.391468 -146.199929) (xy 31.399486 -146.286458) (xy 31.399486 -146.373358) (xy 34.599874 -146.373358)
			(xy 34.599874 -146.286458) (xy 34.607892 -146.199929) (xy 34.62386 -146.114509) (xy 34.647641 -146.030927)
			(xy 34.679033 -145.949895) (xy 34.717767 -145.872106) (xy 34.763514 -145.798222) (xy 34.815883 -145.728875)
			(xy 34.874427 -145.664655) (xy 34.938647 -145.606111) (xy 35.007994 -145.553742) (xy 35.081878 -145.507995)
			(xy 35.159667 -145.469261) (xy 35.240699 -145.437869) (xy 35.324281 -145.414088) (xy 35.409701 -145.39812)
			(xy 35.49623 -145.390102) (xy 35.53968 -145.3896) (xy 35.58313 -145.390102) (xy 35.669659 -145.39812)
			(xy 35.755079 -145.414088) (xy 35.838661 -145.437869) (xy 35.919693 -145.469261) (xy 35.953243 -145.485967)
			(xy 67.225156 -145.485967) (xy 67.225156 -145.414645) (xy 67.233142 -145.343771) (xy 67.249012 -145.274236)
			(xy 67.272569 -145.206916) (xy 67.303514 -145.142657) (xy 67.34146 -145.082266) (xy 67.385929 -145.026504)
			(xy 67.436362 -144.976071) (xy 67.492124 -144.931602) (xy 67.552515 -144.893656) (xy 67.616774 -144.862711)
			(xy 67.684094 -144.839154) (xy 67.753629 -144.823284) (xy 67.824503 -144.815298) (xy 67.860164 -144.814798)
			(xy 67.895825 -144.815298) (xy 67.966699 -144.823284) (xy 68.036234 -144.839154) (xy 68.103554 -144.862711)
			(xy 68.167813 -144.893656) (xy 68.228204 -144.931602) (xy 68.283966 -144.976071) (xy 68.334399 -145.026504)
			(xy 68.378868 -145.082266) (xy 68.416814 -145.142657) (xy 68.447759 -145.206916) (xy 68.471316 -145.274236)
			(xy 68.487186 -145.343771) (xy 68.495172 -145.414645) (xy 68.495172 -145.485967) (xy 70.216768 -145.485967)
			(xy 70.216768 -145.414645) (xy 70.224754 -145.343771) (xy 70.240624 -145.274236) (xy 70.264181 -145.206916)
			(xy 70.295126 -145.142657) (xy 70.333072 -145.082266) (xy 70.377541 -145.026504) (xy 70.427974 -144.976071)
			(xy 70.483736 -144.931602) (xy 70.544127 -144.893656) (xy 70.608386 -144.862711) (xy 70.675706 -144.839154)
			(xy 70.745241 -144.823284) (xy 70.816115 -144.815298) (xy 70.851776 -144.814798) (xy 70.887437 -144.815298)
			(xy 70.958311 -144.823284) (xy 71.027846 -144.839154) (xy 71.095166 -144.862711) (xy 71.159425 -144.893656)
			(xy 71.219816 -144.931602) (xy 71.275578 -144.976071) (xy 71.326011 -145.026504) (xy 71.37048 -145.082266)
			(xy 71.408426 -145.142657) (xy 71.439371 -145.206916) (xy 71.462928 -145.274236) (xy 71.478798 -145.343771)
			(xy 71.486784 -145.414645) (xy 71.486784 -145.485967) (xy 71.478798 -145.556841) (xy 71.462928 -145.626376)
			(xy 71.439371 -145.693696) (xy 71.408426 -145.757955) (xy 71.37048 -145.818346) (xy 71.326011 -145.874108)
			(xy 71.275578 -145.924541) (xy 71.219816 -145.96901) (xy 71.159425 -146.006956) (xy 71.095166 -146.037901)
			(xy 71.027846 -146.061458) (xy 70.958311 -146.077328) (xy 70.887437 -146.085314) (xy 70.816115 -146.085314)
			(xy 70.745241 -146.077328) (xy 70.675706 -146.061458) (xy 70.608386 -146.037901) (xy 70.544127 -146.006956)
			(xy 70.483736 -145.96901) (xy 70.427974 -145.924541) (xy 70.377541 -145.874108) (xy 70.333072 -145.818346)
			(xy 70.295126 -145.757955) (xy 70.264181 -145.693696) (xy 70.240624 -145.626376) (xy 70.224754 -145.556841)
			(xy 70.216768 -145.485967) (xy 68.495172 -145.485967) (xy 68.487186 -145.556841) (xy 68.471316 -145.626376)
			(xy 68.447759 -145.693696) (xy 68.416814 -145.757955) (xy 68.378868 -145.818346) (xy 68.334399 -145.874108)
			(xy 68.283966 -145.924541) (xy 68.228204 -145.96901) (xy 68.167813 -146.006956) (xy 68.103554 -146.037901)
			(xy 68.036234 -146.061458) (xy 67.966699 -146.077328) (xy 67.895825 -146.085314) (xy 67.824503 -146.085314)
			(xy 67.753629 -146.077328) (xy 67.684094 -146.061458) (xy 67.616774 -146.037901) (xy 67.552515 -146.006956)
			(xy 67.492124 -145.96901) (xy 67.436362 -145.924541) (xy 67.385929 -145.874108) (xy 67.34146 -145.818346)
			(xy 67.303514 -145.757955) (xy 67.272569 -145.693696) (xy 67.249012 -145.626376) (xy 67.233142 -145.556841)
			(xy 67.225156 -145.485967) (xy 35.953243 -145.485967) (xy 35.997482 -145.507995) (xy 36.071366 -145.553742)
			(xy 36.140713 -145.606111) (xy 36.204933 -145.664655) (xy 36.263477 -145.728875) (xy 36.315846 -145.798222)
			(xy 36.361593 -145.872106) (xy 36.400327 -145.949895) (xy 36.431719 -146.030927) (xy 36.4555 -146.114509)
			(xy 36.471468 -146.199929) (xy 36.479486 -146.286458) (xy 36.479486 -146.373358) (xy 36.47158 -146.458682)
			(xy 80.919302 -146.458682) (xy 80.919302 -146.398746) (xy 80.927125 -146.339324) (xy 80.942638 -146.281431)
			(xy 80.965574 -146.226058) (xy 80.995541 -146.174152) (xy 81.032028 -146.126602) (xy 81.074408 -146.084222)
			(xy 81.121958 -146.047735) (xy 81.173864 -146.017768) (xy 81.229237 -145.994832) (xy 81.28713 -145.979319)
			(xy 81.346552 -145.971496) (xy 81.37652 -145.971006) (xy 81.406488 -145.971496) (xy 81.46591 -145.979319)
			(xy 81.523803 -145.994832) (xy 81.579176 -146.017768) (xy 81.631082 -146.047735) (xy 81.678632 -146.084222)
			(xy 81.721012 -146.126602) (xy 81.757499 -146.174152) (xy 81.787466 -146.226058) (xy 81.810402 -146.281431)
			(xy 81.825915 -146.339324) (xy 81.833738 -146.398746) (xy 81.833738 -146.458682) (xy 81.825915 -146.518104)
			(xy 81.810402 -146.575997) (xy 81.787466 -146.63137) (xy 81.757499 -146.683276) (xy 81.721012 -146.730826)
			(xy 81.678632 -146.773206) (xy 81.631082 -146.809693) (xy 81.584857 -146.83638) (xy 85.0435 -146.83638)
			(xy 85.0435 -146.776444) (xy 85.051323 -146.717022) (xy 85.066836 -146.659129) (xy 85.089772 -146.603756)
			(xy 85.119739 -146.55185) (xy 85.156226 -146.5043) (xy 85.198606 -146.46192) (xy 85.246156 -146.425433)
			(xy 85.298062 -146.395466) (xy 85.353435 -146.37253) (xy 85.411328 -146.357017) (xy 85.47075 -146.349194)
			(xy 85.500718 -146.348704) (xy 85.530686 -146.349194) (xy 85.590108 -146.357017) (xy 85.648001 -146.37253)
			(xy 85.703374 -146.395466) (xy 85.75528 -146.425433) (xy 85.80283 -146.46192) (xy 85.84521 -146.5043)
			(xy 85.881697 -146.55185) (xy 85.911664 -146.603756) (xy 85.9346 -146.659129) (xy 85.950113 -146.717022)
			(xy 85.957936 -146.776444) (xy 85.957936 -146.83638) (xy 85.950113 -146.895802) (xy 85.9346 -146.953695)
			(xy 85.911664 -147.009068) (xy 85.881697 -147.060974) (xy 85.84521 -147.108524) (xy 85.80283 -147.150904)
			(xy 85.75528 -147.187391) (xy 85.703374 -147.217358) (xy 85.648001 -147.240294) (xy 85.590108 -147.255807)
			(xy 85.530686 -147.26363) (xy 85.47075 -147.26363) (xy 85.411328 -147.255807) (xy 85.353435 -147.240294)
			(xy 85.298062 -147.217358) (xy 85.246156 -147.187391) (xy 85.198606 -147.150904) (xy 85.156226 -147.108524)
			(xy 85.119739 -147.060974) (xy 85.089772 -147.009068) (xy 85.066836 -146.953695) (xy 85.051323 -146.895802)
			(xy 85.0435 -146.83638) (xy 81.584857 -146.83638) (xy 81.579176 -146.83966) (xy 81.523803 -146.862596)
			(xy 81.46591 -146.878109) (xy 81.406488 -146.885932) (xy 81.346552 -146.885932) (xy 81.28713 -146.878109)
			(xy 81.229237 -146.862596) (xy 81.173864 -146.83966) (xy 81.121958 -146.809693) (xy 81.074408 -146.773206)
			(xy 81.032028 -146.730826) (xy 80.995541 -146.683276) (xy 80.965574 -146.63137) (xy 80.942638 -146.575997)
			(xy 80.927125 -146.518104) (xy 80.919302 -146.458682) (xy 36.47158 -146.458682) (xy 36.471468 -146.459887)
			(xy 36.4555 -146.545307) (xy 36.431719 -146.628889) (xy 36.400327 -146.709921) (xy 36.361593 -146.78771)
			(xy 36.315846 -146.861594) (xy 36.263477 -146.930941) (xy 36.204933 -146.995161) (xy 36.140713 -147.053705)
			(xy 36.071366 -147.106074) (xy 35.997482 -147.151821) (xy 35.919693 -147.190555) (xy 35.838661 -147.221947)
			(xy 35.755079 -147.245728) (xy 35.669659 -147.261696) (xy 35.58313 -147.269714) (xy 35.49623 -147.269714)
			(xy 35.409701 -147.261696) (xy 35.324281 -147.245728) (xy 35.240699 -147.221947) (xy 35.159667 -147.190555)
			(xy 35.081878 -147.151821) (xy 35.007994 -147.106074) (xy 34.938647 -147.053705) (xy 34.874427 -146.995161)
			(xy 34.815883 -146.930941) (xy 34.763514 -146.861594) (xy 34.717767 -146.78771) (xy 34.679033 -146.709921)
			(xy 34.647641 -146.628889) (xy 34.62386 -146.545307) (xy 34.607892 -146.459887) (xy 34.599874 -146.373358)
			(xy 31.399486 -146.373358) (xy 31.391468 -146.459887) (xy 31.3755 -146.545307) (xy 31.351719 -146.628889)
			(xy 31.320327 -146.709921) (xy 31.281593 -146.78771) (xy 31.235846 -146.861594) (xy 31.183477 -146.930941)
			(xy 31.124933 -146.995161) (xy 31.060713 -147.053705) (xy 30.991366 -147.106074) (xy 30.917482 -147.151821)
			(xy 30.839693 -147.190555) (xy 30.758661 -147.221947) (xy 30.675079 -147.245728) (xy 30.589659 -147.261696)
			(xy 30.50313 -147.269714) (xy 30.41623 -147.269714) (xy 30.329701 -147.261696) (xy 30.244281 -147.245728)
			(xy 30.160699 -147.221947) (xy 30.079667 -147.190555) (xy 30.001878 -147.151821) (xy 29.927994 -147.106074)
			(xy 29.858647 -147.053705) (xy 29.794427 -146.995161) (xy 29.735883 -146.930941) (xy 29.683514 -146.861594)
			(xy 29.637767 -146.78771) (xy 29.599033 -146.709921) (xy 29.567641 -146.628889) (xy 29.54386 -146.545307)
			(xy 29.527892 -146.459887) (xy 29.519874 -146.373358) (xy 28.804108 -146.373358) (xy 28.804108 -147.721421)
			(xy 67.225156 -147.721421) (xy 67.225156 -147.650099) (xy 67.233142 -147.579225) (xy 67.249012 -147.50969)
			(xy 67.272569 -147.44237) (xy 67.303514 -147.378111) (xy 67.34146 -147.31772) (xy 67.385929 -147.261958)
			(xy 67.436362 -147.211525) (xy 67.492124 -147.167056) (xy 67.552515 -147.12911) (xy 67.616774 -147.098165)
			(xy 67.684094 -147.074608) (xy 67.753629 -147.058738) (xy 67.824503 -147.050752) (xy 67.860164 -147.050252)
			(xy 67.895825 -147.050752) (xy 67.966699 -147.058738) (xy 68.036234 -147.074608) (xy 68.103554 -147.098165)
			(xy 68.167813 -147.12911) (xy 68.228204 -147.167056) (xy 68.283966 -147.211525) (xy 68.334399 -147.261958)
			(xy 68.378868 -147.31772) (xy 68.416814 -147.378111) (xy 68.447759 -147.44237) (xy 68.471316 -147.50969)
			(xy 68.487186 -147.579225) (xy 68.495172 -147.650099) (xy 68.495172 -147.721421) (xy 70.216768 -147.721421)
			(xy 70.216768 -147.650099) (xy 70.224754 -147.579225) (xy 70.240624 -147.50969) (xy 70.264181 -147.44237)
			(xy 70.295126 -147.378111) (xy 70.333072 -147.31772) (xy 70.377541 -147.261958) (xy 70.427974 -147.211525)
			(xy 70.483736 -147.167056) (xy 70.544127 -147.12911) (xy 70.608386 -147.098165) (xy 70.675706 -147.074608)
			(xy 70.745241 -147.058738) (xy 70.816115 -147.050752) (xy 70.851776 -147.050252) (xy 70.887437 -147.050752)
			(xy 70.958311 -147.058738) (xy 71.027846 -147.074608) (xy 71.095166 -147.098165) (xy 71.159425 -147.12911)
			(xy 71.219816 -147.167056) (xy 71.275578 -147.211525) (xy 71.326011 -147.261958) (xy 71.37048 -147.31772)
			(xy 71.408426 -147.378111) (xy 71.410285 -147.381972) (xy 86.639382 -147.381972) (xy 86.639382 -147.322036)
			(xy 86.647205 -147.262614) (xy 86.662718 -147.204721) (xy 86.685654 -147.149348) (xy 86.715621 -147.097442)
			(xy 86.752108 -147.049892) (xy 86.794488 -147.007512) (xy 86.842038 -146.971025) (xy 86.893944 -146.941058)
			(xy 86.949317 -146.918122) (xy 87.00721 -146.902609) (xy 87.066632 -146.894786) (xy 87.0966 -146.894296)
			(xy 87.126568 -146.894786) (xy 87.18599 -146.902609) (xy 87.243883 -146.918122) (xy 87.299256 -146.941058)
			(xy 87.351162 -146.971025) (xy 87.398712 -147.007512) (xy 87.441092 -147.049892) (xy 87.477579 -147.097442)
			(xy 87.507546 -147.149348) (xy 87.530482 -147.204721) (xy 87.545995 -147.262614) (xy 87.553818 -147.322036)
			(xy 87.553818 -147.381972) (xy 87.545995 -147.441394) (xy 87.530482 -147.499287) (xy 87.507546 -147.55466)
			(xy 87.477579 -147.606566) (xy 87.441092 -147.654116) (xy 87.398712 -147.696496) (xy 87.351162 -147.732983)
			(xy 87.299256 -147.76295) (xy 87.243883 -147.785886) (xy 87.18599 -147.801399) (xy 87.126568 -147.809222)
			(xy 87.066632 -147.809222) (xy 87.00721 -147.801399) (xy 86.949317 -147.785886) (xy 86.893944 -147.76295)
			(xy 86.842038 -147.732983) (xy 86.794488 -147.696496) (xy 86.752108 -147.654116) (xy 86.715621 -147.606566)
			(xy 86.685654 -147.55466) (xy 86.662718 -147.499287) (xy 86.647205 -147.441394) (xy 86.639382 -147.381972)
			(xy 71.410285 -147.381972) (xy 71.439371 -147.44237) (xy 71.462928 -147.50969) (xy 71.478798 -147.579225)
			(xy 71.486784 -147.650099) (xy 71.486784 -147.721421) (xy 71.478798 -147.792295) (xy 71.462928 -147.86183)
			(xy 71.454414 -147.886162) (xy 80.646252 -147.886162) (xy 80.646252 -147.826226) (xy 80.654075 -147.766804)
			(xy 80.669588 -147.708911) (xy 80.692524 -147.653538) (xy 80.722491 -147.601632) (xy 80.758978 -147.554082)
			(xy 80.801358 -147.511702) (xy 80.848908 -147.475215) (xy 80.900814 -147.445248) (xy 80.956187 -147.422312)
			(xy 81.01408 -147.406799) (xy 81.073502 -147.398976) (xy 81.10347 -147.398486) (xy 81.133438 -147.398976)
			(xy 81.19286 -147.406799) (xy 81.250753 -147.422312) (xy 81.306126 -147.445248) (xy 81.358032 -147.475215)
			(xy 81.405582 -147.511702) (xy 81.447962 -147.554082) (xy 81.484449 -147.601632) (xy 81.514416 -147.653538)
			(xy 81.537352 -147.708911) (xy 81.552865 -147.766804) (xy 81.560688 -147.826226) (xy 81.560688 -147.886162)
			(xy 81.552865 -147.945584) (xy 81.537352 -148.003477) (xy 81.514416 -148.05885) (xy 81.484449 -148.110756)
			(xy 81.447962 -148.158306) (xy 81.405582 -148.200686) (xy 81.358032 -148.237173) (xy 81.306126 -148.26714)
			(xy 81.250753 -148.290076) (xy 81.19286 -148.305589) (xy 81.133438 -148.313412) (xy 81.073502 -148.313412)
			(xy 81.01408 -148.305589) (xy 80.956187 -148.290076) (xy 80.900814 -148.26714) (xy 80.848908 -148.237173)
			(xy 80.801358 -148.200686) (xy 80.758978 -148.158306) (xy 80.722491 -148.110756) (xy 80.692524 -148.05885)
			(xy 80.669588 -148.003477) (xy 80.654075 -147.945584) (xy 80.646252 -147.886162) (xy 71.454414 -147.886162)
			(xy 71.439371 -147.92915) (xy 71.408426 -147.993409) (xy 71.37048 -148.0538) (xy 71.326011 -148.109562)
			(xy 71.275578 -148.159995) (xy 71.219816 -148.204464) (xy 71.159425 -148.24241) (xy 71.095166 -148.273355)
			(xy 71.027846 -148.296912) (xy 70.958311 -148.312782) (xy 70.887437 -148.320768) (xy 70.816115 -148.320768)
			(xy 70.745241 -148.312782) (xy 70.675706 -148.296912) (xy 70.608386 -148.273355) (xy 70.544127 -148.24241)
			(xy 70.483736 -148.204464) (xy 70.427974 -148.159995) (xy 70.377541 -148.109562) (xy 70.333072 -148.0538)
			(xy 70.295126 -147.993409) (xy 70.264181 -147.92915) (xy 70.240624 -147.86183) (xy 70.224754 -147.792295)
			(xy 70.216768 -147.721421) (xy 68.495172 -147.721421) (xy 68.487186 -147.792295) (xy 68.471316 -147.86183)
			(xy 68.447759 -147.92915) (xy 68.416814 -147.993409) (xy 68.378868 -148.0538) (xy 68.334399 -148.109562)
			(xy 68.283966 -148.159995) (xy 68.228204 -148.204464) (xy 68.167813 -148.24241) (xy 68.103554 -148.273355)
			(xy 68.036234 -148.296912) (xy 67.966699 -148.312782) (xy 67.895825 -148.320768) (xy 67.824503 -148.320768)
			(xy 67.753629 -148.312782) (xy 67.684094 -148.296912) (xy 67.616774 -148.273355) (xy 67.552515 -148.24241)
			(xy 67.492124 -148.204464) (xy 67.436362 -148.159995) (xy 67.385929 -148.109562) (xy 67.34146 -148.0538)
			(xy 67.303514 -147.993409) (xy 67.272569 -147.92915) (xy 67.249012 -147.86183) (xy 67.233142 -147.792295)
			(xy 67.225156 -147.721421) (xy 28.804108 -147.721421) (xy 28.804108 -148.913358) (xy 29.519874 -148.913358)
			(xy 29.519874 -148.826458) (xy 29.527892 -148.739929) (xy 29.54386 -148.654509) (xy 29.567641 -148.570927)
			(xy 29.599033 -148.489895) (xy 29.637767 -148.412106) (xy 29.683514 -148.338222) (xy 29.735883 -148.268875)
			(xy 29.794427 -148.204655) (xy 29.858647 -148.146111) (xy 29.927994 -148.093742) (xy 30.001878 -148.047995)
			(xy 30.079667 -148.009261) (xy 30.160699 -147.977869) (xy 30.244281 -147.954088) (xy 30.329701 -147.93812)
			(xy 30.41623 -147.930102) (xy 30.45968 -147.9296) (xy 30.50313 -147.930102) (xy 30.589659 -147.93812)
			(xy 30.675079 -147.954088) (xy 30.758661 -147.977869) (xy 30.839693 -148.009261) (xy 30.917482 -148.047995)
			(xy 30.991366 -148.093742) (xy 31.060713 -148.146111) (xy 31.124933 -148.204655) (xy 31.183477 -148.268875)
			(xy 31.235846 -148.338222) (xy 31.281593 -148.412106) (xy 31.320327 -148.489895) (xy 31.351719 -148.570927)
			(xy 31.3755 -148.654509) (xy 31.391468 -148.739929) (xy 31.399486 -148.826458) (xy 31.399486 -148.913358)
			(xy 34.599874 -148.913358) (xy 34.599874 -148.826458) (xy 34.607892 -148.739929) (xy 34.62386 -148.654509)
			(xy 34.647641 -148.570927) (xy 34.679033 -148.489895) (xy 34.717767 -148.412106) (xy 34.763514 -148.338222)
			(xy 34.815883 -148.268875) (xy 34.874427 -148.204655) (xy 34.938647 -148.146111) (xy 35.007994 -148.093742)
			(xy 35.081878 -148.047995) (xy 35.159667 -148.009261) (xy 35.240699 -147.977869) (xy 35.324281 -147.954088)
			(xy 35.409701 -147.93812) (xy 35.49623 -147.930102) (xy 35.53968 -147.9296) (xy 35.58313 -147.930102)
			(xy 35.669659 -147.93812) (xy 35.755079 -147.954088) (xy 35.838661 -147.977869) (xy 35.919693 -148.009261)
			(xy 35.997482 -148.047995) (xy 36.071366 -148.093742) (xy 36.140713 -148.146111) (xy 36.204933 -148.204655)
			(xy 36.263477 -148.268875) (xy 36.315846 -148.338222) (xy 36.361593 -148.412106) (xy 36.400327 -148.489895)
			(xy 36.422674 -148.547578) (xy 83.270326 -148.547578) (xy 83.270326 -148.487642) (xy 83.278149 -148.42822)
			(xy 83.293662 -148.370327) (xy 83.316598 -148.314954) (xy 83.346565 -148.263048) (xy 83.383052 -148.215498)
			(xy 83.425432 -148.173118) (xy 83.472982 -148.136631) (xy 83.524888 -148.106664) (xy 83.580261 -148.083728)
			(xy 83.638154 -148.068215) (xy 83.697576 -148.060392) (xy 83.727544 -148.059902) (xy 83.757512 -148.060392)
			(xy 83.816934 -148.068215) (xy 83.874827 -148.083728) (xy 83.9302 -148.106664) (xy 83.982106 -148.136631)
			(xy 84.029656 -148.173118) (xy 84.072036 -148.215498) (xy 84.108523 -148.263048) (xy 84.13849 -148.314954)
			(xy 84.161426 -148.370327) (xy 84.176939 -148.42822) (xy 84.184762 -148.487642) (xy 84.184762 -148.547578)
			(xy 84.176939 -148.607) (xy 84.161426 -148.664893) (xy 84.13849 -148.720266) (xy 84.108523 -148.772172)
			(xy 84.072036 -148.819722) (xy 84.029656 -148.862102) (xy 83.982106 -148.898589) (xy 83.9302 -148.928556)
			(xy 83.920949 -148.932388) (xy 85.23908 -148.932388) (xy 85.23908 -148.872452) (xy 85.246903 -148.81303)
			(xy 85.262416 -148.755137) (xy 85.285352 -148.699764) (xy 85.315319 -148.647858) (xy 85.351806 -148.600308)
			(xy 85.394186 -148.557928) (xy 85.441736 -148.521441) (xy 85.493642 -148.491474) (xy 85.549015 -148.468538)
			(xy 85.606908 -148.453025) (xy 85.66633 -148.445202) (xy 85.696298 -148.444712) (xy 85.726266 -148.445202)
			(xy 85.785688 -148.453025) (xy 85.843581 -148.468538) (xy 85.898954 -148.491474) (xy 85.95086 -148.521441)
			(xy 85.99841 -148.557928) (xy 86.04079 -148.600308) (xy 86.077277 -148.647858) (xy 86.107244 -148.699764)
			(xy 86.13018 -148.755137) (xy 86.145693 -148.81303) (xy 86.153516 -148.872452) (xy 86.153516 -148.932388)
			(xy 86.145693 -148.99181) (xy 86.13018 -149.049703) (xy 86.107244 -149.105076) (xy 86.077277 -149.156982)
			(xy 86.04079 -149.204532) (xy 85.99841 -149.246912) (xy 85.95086 -149.283399) (xy 85.898954 -149.313366)
			(xy 85.843581 -149.336302) (xy 85.785688 -149.351815) (xy 85.726266 -149.359638) (xy 85.66633 -149.359638)
			(xy 85.606908 -149.351815) (xy 85.549015 -149.336302) (xy 85.493642 -149.313366) (xy 85.441736 -149.283399)
			(xy 85.394186 -149.246912) (xy 85.351806 -149.204532) (xy 85.315319 -149.156982) (xy 85.285352 -149.105076)
			(xy 85.262416 -149.049703) (xy 85.246903 -148.99181) (xy 85.23908 -148.932388) (xy 83.920949 -148.932388)
			(xy 83.874827 -148.951492) (xy 83.816934 -148.967005) (xy 83.757512 -148.974828) (xy 83.697576 -148.974828)
			(xy 83.638154 -148.967005) (xy 83.580261 -148.951492) (xy 83.524888 -148.928556) (xy 83.472982 -148.898589)
			(xy 83.425432 -148.862102) (xy 83.383052 -148.819722) (xy 83.346565 -148.772172) (xy 83.316598 -148.720266)
			(xy 83.293662 -148.664893) (xy 83.278149 -148.607) (xy 83.270326 -148.547578) (xy 36.422674 -148.547578)
			(xy 36.431719 -148.570927) (xy 36.4555 -148.654509) (xy 36.471468 -148.739929) (xy 36.479486 -148.826458)
			(xy 36.479486 -148.913358) (xy 36.471468 -148.999887) (xy 36.4555 -149.085307) (xy 36.431719 -149.168889)
			(xy 36.400327 -149.249921) (xy 36.361593 -149.32771) (xy 36.315846 -149.401594) (xy 36.282714 -149.445468)
			(xy 80.244678 -149.445468) (xy 80.244678 -149.385532) (xy 80.252501 -149.32611) (xy 80.268014 -149.268217)
			(xy 80.29095 -149.212844) (xy 80.320917 -149.160938) (xy 80.357404 -149.113388) (xy 80.399784 -149.071008)
			(xy 80.447334 -149.034521) (xy 80.49924 -149.004554) (xy 80.554613 -148.981618) (xy 80.612506 -148.966105)
			(xy 80.671928 -148.958282) (xy 80.701896 -148.957792) (xy 80.731864 -148.958282) (xy 80.791286 -148.966105)
			(xy 80.849179 -148.981618) (xy 80.904552 -149.004554) (xy 80.956458 -149.034521) (xy 81.004008 -149.071008)
			(xy 81.046388 -149.113388) (xy 81.082875 -149.160938) (xy 81.112842 -149.212844) (xy 81.135778 -149.268217)
			(xy 81.151291 -149.32611) (xy 81.159114 -149.385532) (xy 81.159114 -149.445468) (xy 81.151291 -149.50489)
			(xy 81.135778 -149.562783) (xy 81.112842 -149.618156) (xy 81.082875 -149.670062) (xy 81.078827 -149.675338)
			(xy 81.775536 -149.675338) (xy 81.775536 -149.615402) (xy 81.783359 -149.55598) (xy 81.798872 -149.498087)
			(xy 81.821808 -149.442714) (xy 81.851775 -149.390808) (xy 81.888262 -149.343258) (xy 81.930642 -149.300878)
			(xy 81.978192 -149.264391) (xy 82.030098 -149.234424) (xy 82.085471 -149.211488) (xy 82.143364 -149.195975)
			(xy 82.202786 -149.188152) (xy 82.232754 -149.187662) (xy 82.262722 -149.188152) (xy 82.322144 -149.195975)
			(xy 82.380037 -149.211488) (xy 82.43541 -149.234424) (xy 82.487316 -149.264391) (xy 82.534866 -149.300878)
			(xy 82.577246 -149.343258) (xy 82.613733 -149.390808) (xy 82.6437 -149.442714) (xy 82.666636 -149.498087)
			(xy 82.682149 -149.55598) (xy 82.689972 -149.615402) (xy 82.689972 -149.675338) (xy 82.682149 -149.73476)
			(xy 82.666636 -149.792653) (xy 82.646317 -149.841708) (xy 83.837 -149.841708) (xy 83.837 -149.781772)
			(xy 83.844823 -149.72235) (xy 83.860336 -149.664457) (xy 83.883272 -149.609084) (xy 83.913239 -149.557178)
			(xy 83.949726 -149.509628) (xy 83.992106 -149.467248) (xy 84.039656 -149.430761) (xy 84.091562 -149.400794)
			(xy 84.146935 -149.377858) (xy 84.204828 -149.362345) (xy 84.26425 -149.354522) (xy 84.294218 -149.354032)
			(xy 84.324186 -149.354522) (xy 84.383608 -149.362345) (xy 84.441501 -149.377858) (xy 84.496874 -149.400794)
			(xy 84.54878 -149.430761) (xy 84.59633 -149.467248) (xy 84.63871 -149.509628) (xy 84.675197 -149.557178)
			(xy 84.705164 -149.609084) (xy 84.7281 -149.664457) (xy 84.743613 -149.72235) (xy 84.751436 -149.781772)
			(xy 84.751436 -149.841708) (xy 84.743613 -149.90113) (xy 84.7281 -149.959023) (xy 84.705164 -150.014396)
			(xy 84.675197 -150.066302) (xy 84.63871 -150.113852) (xy 84.59633 -150.156232) (xy 84.54878 -150.192719)
			(xy 84.496874 -150.222686) (xy 84.441501 -150.245622) (xy 84.383608 -150.261135) (xy 84.324186 -150.268958)
			(xy 84.26425 -150.268958) (xy 84.204828 -150.261135) (xy 84.146935 -150.245622) (xy 84.091562 -150.222686)
			(xy 84.039656 -150.192719) (xy 83.992106 -150.156232) (xy 83.949726 -150.113852) (xy 83.913239 -150.066302)
			(xy 83.883272 -150.014396) (xy 83.860336 -149.959023) (xy 83.844823 -149.90113) (xy 83.837 -149.841708)
			(xy 82.646317 -149.841708) (xy 82.6437 -149.848026) (xy 82.613733 -149.899932) (xy 82.577246 -149.947482)
			(xy 82.534866 -149.989862) (xy 82.487316 -150.026349) (xy 82.43541 -150.056316) (xy 82.380037 -150.079252)
			(xy 82.322144 -150.094765) (xy 82.262722 -150.102588) (xy 82.202786 -150.102588) (xy 82.143364 -150.094765)
			(xy 82.085471 -150.079252) (xy 82.030098 -150.056316) (xy 81.978192 -150.026349) (xy 81.930642 -149.989862)
			(xy 81.888262 -149.947482) (xy 81.851775 -149.899932) (xy 81.821808 -149.848026) (xy 81.798872 -149.792653)
			(xy 81.783359 -149.73476) (xy 81.775536 -149.675338) (xy 81.078827 -149.675338) (xy 81.046388 -149.717612)
			(xy 81.004008 -149.759992) (xy 80.956458 -149.796479) (xy 80.904552 -149.826446) (xy 80.849179 -149.849382)
			(xy 80.791286 -149.864895) (xy 80.731864 -149.872718) (xy 80.671928 -149.872718) (xy 80.612506 -149.864895)
			(xy 80.554613 -149.849382) (xy 80.49924 -149.826446) (xy 80.447334 -149.796479) (xy 80.399784 -149.759992)
			(xy 80.357404 -149.717612) (xy 80.320917 -149.670062) (xy 80.29095 -149.618156) (xy 80.268014 -149.562783)
			(xy 80.252501 -149.50489) (xy 80.244678 -149.445468) (xy 36.282714 -149.445468) (xy 36.263477 -149.470941)
			(xy 36.204933 -149.535161) (xy 36.140713 -149.593705) (xy 36.071366 -149.646074) (xy 35.997482 -149.691821)
			(xy 35.919693 -149.730555) (xy 35.838661 -149.761947) (xy 35.755079 -149.785728) (xy 35.669659 -149.801696)
			(xy 35.58313 -149.809714) (xy 35.49623 -149.809714) (xy 35.409701 -149.801696) (xy 35.324281 -149.785728)
			(xy 35.240699 -149.761947) (xy 35.159667 -149.730555) (xy 35.081878 -149.691821) (xy 35.007994 -149.646074)
			(xy 34.938647 -149.593705) (xy 34.874427 -149.535161) (xy 34.815883 -149.470941) (xy 34.763514 -149.401594)
			(xy 34.717767 -149.32771) (xy 34.679033 -149.249921) (xy 34.647641 -149.168889) (xy 34.62386 -149.085307)
			(xy 34.607892 -148.999887) (xy 34.599874 -148.913358) (xy 31.399486 -148.913358) (xy 31.391468 -148.999887)
			(xy 31.3755 -149.085307) (xy 31.351719 -149.168889) (xy 31.320327 -149.249921) (xy 31.281593 -149.32771)
			(xy 31.235846 -149.401594) (xy 31.183477 -149.470941) (xy 31.124933 -149.535161) (xy 31.060713 -149.593705)
			(xy 30.991366 -149.646074) (xy 30.917482 -149.691821) (xy 30.839693 -149.730555) (xy 30.758661 -149.761947)
			(xy 30.675079 -149.785728) (xy 30.589659 -149.801696) (xy 30.50313 -149.809714) (xy 30.41623 -149.809714)
			(xy 30.329701 -149.801696) (xy 30.244281 -149.785728) (xy 30.160699 -149.761947) (xy 30.079667 -149.730555)
			(xy 30.001878 -149.691821) (xy 29.927994 -149.646074) (xy 29.858647 -149.593705) (xy 29.794427 -149.535161)
			(xy 29.735883 -149.470941) (xy 29.683514 -149.401594) (xy 29.637767 -149.32771) (xy 29.599033 -149.249921)
			(xy 29.567641 -149.168889) (xy 29.54386 -149.085307) (xy 29.527892 -148.999887) (xy 29.519874 -148.913358)
			(xy 28.804108 -148.913358) (xy 28.804108 -150.389691) (xy 67.225156 -150.389691) (xy 67.225156 -150.318369)
			(xy 67.233142 -150.247495) (xy 67.249012 -150.17796) (xy 67.272569 -150.11064) (xy 67.303514 -150.046381)
			(xy 67.34146 -149.98599) (xy 67.385929 -149.930228) (xy 67.436362 -149.879795) (xy 67.492124 -149.835326)
			(xy 67.552515 -149.79738) (xy 67.616774 -149.766435) (xy 67.684094 -149.742878) (xy 67.753629 -149.727008)
			(xy 67.824503 -149.719022) (xy 67.860164 -149.718522) (xy 67.895825 -149.719022) (xy 67.966699 -149.727008)
			(xy 68.036234 -149.742878) (xy 68.103554 -149.766435) (xy 68.167813 -149.79738) (xy 68.228204 -149.835326)
			(xy 68.283966 -149.879795) (xy 68.334399 -149.930228) (xy 68.378868 -149.98599) (xy 68.416814 -150.046381)
			(xy 68.447759 -150.11064) (xy 68.471316 -150.17796) (xy 68.487186 -150.247495) (xy 68.495172 -150.318369)
			(xy 68.495172 -150.389691) (xy 70.216768 -150.389691) (xy 70.216768 -150.318369) (xy 70.224754 -150.247495)
			(xy 70.240624 -150.17796) (xy 70.264181 -150.11064) (xy 70.295126 -150.046381) (xy 70.333072 -149.98599)
			(xy 70.377541 -149.930228) (xy 70.427974 -149.879795) (xy 70.483736 -149.835326) (xy 70.544127 -149.79738)
			(xy 70.608386 -149.766435) (xy 70.675706 -149.742878) (xy 70.745241 -149.727008) (xy 70.816115 -149.719022)
			(xy 70.851776 -149.718522) (xy 70.887437 -149.719022) (xy 70.958311 -149.727008) (xy 71.027846 -149.742878)
			(xy 71.095166 -149.766435) (xy 71.159425 -149.79738) (xy 71.219816 -149.835326) (xy 71.275578 -149.879795)
			(xy 71.326011 -149.930228) (xy 71.37048 -149.98599) (xy 71.408426 -150.046381) (xy 71.439371 -150.11064)
			(xy 71.462928 -150.17796) (xy 71.478798 -150.247495) (xy 71.486784 -150.318369) (xy 71.486784 -150.389691)
			(xy 71.478798 -150.460565) (xy 71.462928 -150.5301) (xy 71.439371 -150.59742) (xy 71.408426 -150.661679)
			(xy 71.37048 -150.72207) (xy 71.35954 -150.735788) (xy 80.78519 -150.735788) (xy 80.78519 -150.675852)
			(xy 80.793013 -150.61643) (xy 80.808526 -150.558537) (xy 80.831462 -150.503164) (xy 80.861429 -150.451258)
			(xy 80.897916 -150.403708) (xy 80.940296 -150.361328) (xy 80.987846 -150.324841) (xy 81.039752 -150.294874)
			(xy 81.095125 -150.271938) (xy 81.153018 -150.256425) (xy 81.21244 -150.248602) (xy 81.242408 -150.248112)
			(xy 81.272376 -150.248602) (xy 81.331798 -150.256425) (xy 81.389691 -150.271938) (xy 81.445064 -150.294874)
			(xy 81.49697 -150.324841) (xy 81.54452 -150.361328) (xy 81.5869 -150.403708) (xy 81.623387 -150.451258)
			(xy 81.653354 -150.503164) (xy 81.67629 -150.558537) (xy 81.691803 -150.61643) (xy 81.699626 -150.675852)
			(xy 81.699626 -150.735788) (xy 81.691803 -150.79521) (xy 81.67629 -150.853103) (xy 81.653354 -150.908476)
			(xy 81.623387 -150.960382) (xy 81.5869 -151.007932) (xy 81.54452 -151.050312) (xy 81.49697 -151.086799)
			(xy 81.445064 -151.116766) (xy 81.389691 -151.139702) (xy 81.331798 -151.155215) (xy 81.272376 -151.163038)
			(xy 81.21244 -151.163038) (xy 81.153018 -151.155215) (xy 81.095125 -151.139702) (xy 81.039752 -151.116766)
			(xy 80.987846 -151.086799) (xy 80.940296 -151.050312) (xy 80.897916 -151.007932) (xy 80.861429 -150.960382)
			(xy 80.831462 -150.908476) (xy 80.808526 -150.853103) (xy 80.793013 -150.79521) (xy 80.78519 -150.735788)
			(xy 71.35954 -150.735788) (xy 71.326011 -150.777832) (xy 71.275578 -150.828265) (xy 71.219816 -150.872734)
			(xy 71.159425 -150.91068) (xy 71.095166 -150.941625) (xy 71.027846 -150.965182) (xy 70.958311 -150.981052)
			(xy 70.887437 -150.989038) (xy 70.816115 -150.989038) (xy 70.745241 -150.981052) (xy 70.675706 -150.965182)
			(xy 70.608386 -150.941625) (xy 70.544127 -150.91068) (xy 70.483736 -150.872734) (xy 70.427974 -150.828265)
			(xy 70.377541 -150.777832) (xy 70.333072 -150.72207) (xy 70.295126 -150.661679) (xy 70.264181 -150.59742)
			(xy 70.240624 -150.5301) (xy 70.224754 -150.460565) (xy 70.216768 -150.389691) (xy 68.495172 -150.389691)
			(xy 68.487186 -150.460565) (xy 68.471316 -150.5301) (xy 68.447759 -150.59742) (xy 68.416814 -150.661679)
			(xy 68.378868 -150.72207) (xy 68.334399 -150.777832) (xy 68.283966 -150.828265) (xy 68.228204 -150.872734)
			(xy 68.167813 -150.91068) (xy 68.103554 -150.941625) (xy 68.036234 -150.965182) (xy 67.966699 -150.981052)
			(xy 67.895825 -150.989038) (xy 67.824503 -150.989038) (xy 67.753629 -150.981052) (xy 67.684094 -150.965182)
			(xy 67.616774 -150.941625) (xy 67.552515 -150.91068) (xy 67.492124 -150.872734) (xy 67.436362 -150.828265)
			(xy 67.385929 -150.777832) (xy 67.34146 -150.72207) (xy 67.303514 -150.661679) (xy 67.272569 -150.59742)
			(xy 67.249012 -150.5301) (xy 67.233142 -150.460565) (xy 67.225156 -150.389691) (xy 28.804108 -150.389691)
			(xy 28.804108 -151.453358) (xy 29.519874 -151.453358) (xy 29.519874 -151.366458) (xy 29.527892 -151.279929)
			(xy 29.54386 -151.194509) (xy 29.567641 -151.110927) (xy 29.599033 -151.029895) (xy 29.637767 -150.952106)
			(xy 29.683514 -150.878222) (xy 29.735883 -150.808875) (xy 29.794427 -150.744655) (xy 29.858647 -150.686111)
			(xy 29.927994 -150.633742) (xy 30.001878 -150.587995) (xy 30.079667 -150.549261) (xy 30.160699 -150.517869)
			(xy 30.244281 -150.494088) (xy 30.329701 -150.47812) (xy 30.41623 -150.470102) (xy 30.45968 -150.4696)
			(xy 30.50313 -150.470102) (xy 30.589659 -150.47812) (xy 30.675079 -150.494088) (xy 30.758661 -150.517869)
			(xy 30.839693 -150.549261) (xy 30.917482 -150.587995) (xy 30.991366 -150.633742) (xy 31.060713 -150.686111)
			(xy 31.124933 -150.744655) (xy 31.183477 -150.808875) (xy 31.235846 -150.878222) (xy 31.281593 -150.952106)
			(xy 31.320327 -151.029895) (xy 31.351719 -151.110927) (xy 31.3755 -151.194509) (xy 31.391468 -151.279929)
			(xy 31.399486 -151.366458) (xy 31.399486 -151.453358) (xy 34.599874 -151.453358) (xy 34.599874 -151.366458)
			(xy 34.607892 -151.279929) (xy 34.62386 -151.194509) (xy 34.647641 -151.110927) (xy 34.679033 -151.029895)
			(xy 34.717767 -150.952106) (xy 34.763514 -150.878222) (xy 34.815883 -150.808875) (xy 34.874427 -150.744655)
			(xy 34.938647 -150.686111) (xy 35.007994 -150.633742) (xy 35.081878 -150.587995) (xy 35.159667 -150.549261)
			(xy 35.240699 -150.517869) (xy 35.324281 -150.494088) (xy 35.409701 -150.47812) (xy 35.49623 -150.470102)
			(xy 35.53968 -150.4696) (xy 35.58313 -150.470102) (xy 35.669659 -150.47812) (xy 35.755079 -150.494088)
			(xy 35.838661 -150.517869) (xy 35.919693 -150.549261) (xy 35.997482 -150.587995) (xy 36.071366 -150.633742)
			(xy 36.140713 -150.686111) (xy 36.204933 -150.744655) (xy 36.263477 -150.808875) (xy 36.315846 -150.878222)
			(xy 36.361593 -150.952106) (xy 36.400327 -151.029895) (xy 36.427103 -151.099012) (xy 51.667664 -151.099012)
			(xy 53.31968 -151.099012) (xy 53.31968 -151.242772) (xy 84.315282 -151.242772) (xy 84.315282 -151.182836)
			(xy 84.323105 -151.123414) (xy 84.338618 -151.065521) (xy 84.361554 -151.010148) (xy 84.391521 -150.958242)
			(xy 84.428008 -150.910692) (xy 84.470388 -150.868312) (xy 84.517938 -150.831825) (xy 84.569844 -150.801858)
			(xy 84.625217 -150.778922) (xy 84.68311 -150.763409) (xy 84.742532 -150.755586) (xy 84.7725 -150.755096)
			(xy 84.802468 -150.755586) (xy 84.86189 -150.763409) (xy 84.919783 -150.778922) (xy 84.975156 -150.801858)
			(xy 85.027062 -150.831825) (xy 85.074612 -150.868312) (xy 85.116992 -150.910692) (xy 85.153479 -150.958242)
			(xy 85.183446 -151.010148) (xy 85.206382 -151.065521) (xy 85.221895 -151.123414) (xy 85.229718 -151.182836)
			(xy 85.229718 -151.242772) (xy 85.221895 -151.302194) (xy 85.206382 -151.360087) (xy 85.183446 -151.41546)
			(xy 85.153479 -151.467366) (xy 85.116992 -151.514916) (xy 85.074612 -151.557296) (xy 85.027062 -151.593783)
			(xy 84.975156 -151.62375) (xy 84.919783 -151.646686) (xy 84.86189 -151.662199) (xy 84.802468 -151.670022)
			(xy 84.742532 -151.670022) (xy 84.68311 -151.662199) (xy 84.625217 -151.646686) (xy 84.569844 -151.62375)
			(xy 84.517938 -151.593783) (xy 84.470388 -151.557296) (xy 84.428008 -151.514916) (xy 84.391521 -151.467366)
			(xy 84.361554 -151.41546) (xy 84.338618 -151.360087) (xy 84.323105 -151.302194) (xy 84.315282 -151.242772)
			(xy 53.31968 -151.242772) (xy 53.31968 -152.751028) (xy 51.667664 -152.751028) (xy 51.667664 -151.099012)
			(xy 36.427103 -151.099012) (xy 36.431719 -151.110927) (xy 36.4555 -151.194509) (xy 36.471468 -151.279929)
			(xy 36.479486 -151.366458) (xy 36.479486 -151.453358) (xy 36.471468 -151.539887) (xy 36.4555 -151.625307)
			(xy 36.431719 -151.708889) (xy 36.400327 -151.789921) (xy 36.361593 -151.86771) (xy 36.315846 -151.941594)
			(xy 36.263477 -152.010941) (xy 36.204933 -152.075161) (xy 36.140713 -152.133705) (xy 36.071366 -152.186074)
			(xy 35.997482 -152.231821) (xy 35.919693 -152.270555) (xy 35.838661 -152.301947) (xy 35.755079 -152.325728)
			(xy 35.669659 -152.341696) (xy 35.58313 -152.349714) (xy 35.49623 -152.349714) (xy 35.409701 -152.341696)
			(xy 35.324281 -152.325728) (xy 35.240699 -152.301947) (xy 35.159667 -152.270555) (xy 35.081878 -152.231821)
			(xy 35.007994 -152.186074) (xy 34.938647 -152.133705) (xy 34.874427 -152.075161) (xy 34.815883 -152.010941)
			(xy 34.763514 -151.941594) (xy 34.717767 -151.86771) (xy 34.679033 -151.789921) (xy 34.647641 -151.708889)
			(xy 34.62386 -151.625307) (xy 34.607892 -151.539887) (xy 34.599874 -151.453358) (xy 31.399486 -151.453358)
			(xy 31.391468 -151.539887) (xy 31.3755 -151.625307) (xy 31.351719 -151.708889) (xy 31.320327 -151.789921)
			(xy 31.281593 -151.86771) (xy 31.235846 -151.941594) (xy 31.183477 -152.010941) (xy 31.124933 -152.075161)
			(xy 31.060713 -152.133705) (xy 30.991366 -152.186074) (xy 30.917482 -152.231821) (xy 30.839693 -152.270555)
			(xy 30.758661 -152.301947) (xy 30.675079 -152.325728) (xy 30.589659 -152.341696) (xy 30.50313 -152.349714)
			(xy 30.41623 -152.349714) (xy 30.329701 -152.341696) (xy 30.244281 -152.325728) (xy 30.160699 -152.301947)
			(xy 30.079667 -152.270555) (xy 30.001878 -152.231821) (xy 29.927994 -152.186074) (xy 29.858647 -152.133705)
			(xy 29.794427 -152.075161) (xy 29.735883 -152.010941) (xy 29.683514 -151.941594) (xy 29.637767 -151.86771)
			(xy 29.599033 -151.789921) (xy 29.567641 -151.708889) (xy 29.54386 -151.625307) (xy 29.527892 -151.539887)
			(xy 29.519874 -151.453358) (xy 28.804108 -151.453358) (xy 28.804108 -152.761289) (xy 67.225156 -152.761289)
			(xy 67.225156 -152.689967) (xy 67.233142 -152.619093) (xy 67.249012 -152.549558) (xy 67.272569 -152.482238)
			(xy 67.303514 -152.417979) (xy 67.34146 -152.357588) (xy 67.385929 -152.301826) (xy 67.436362 -152.251393)
			(xy 67.492124 -152.206924) (xy 67.552515 -152.168978) (xy 67.616774 -152.138033) (xy 67.684094 -152.114476)
			(xy 67.753629 -152.098606) (xy 67.824503 -152.09062) (xy 67.860164 -152.09012) (xy 67.895825 -152.09062)
			(xy 67.966699 -152.098606) (xy 68.036234 -152.114476) (xy 68.103554 -152.138033) (xy 68.167813 -152.168978)
			(xy 68.228204 -152.206924) (xy 68.283966 -152.251393) (xy 68.334399 -152.301826) (xy 68.378868 -152.357588)
			(xy 68.416814 -152.417979) (xy 68.447759 -152.482238) (xy 68.471316 -152.549558) (xy 68.487186 -152.619093)
			(xy 68.495172 -152.689967) (xy 68.495172 -152.761289) (xy 70.216768 -152.761289) (xy 70.216768 -152.689967)
			(xy 70.224754 -152.619093) (xy 70.240624 -152.549558) (xy 70.264181 -152.482238) (xy 70.295126 -152.417979)
			(xy 70.333072 -152.357588) (xy 70.377541 -152.301826) (xy 70.427974 -152.251393) (xy 70.483736 -152.206924)
			(xy 70.544127 -152.168978) (xy 70.608386 -152.138033) (xy 70.675706 -152.114476) (xy 70.745241 -152.098606)
			(xy 70.816115 -152.09062) (xy 70.851776 -152.09012) (xy 70.887437 -152.09062) (xy 70.958311 -152.098606)
			(xy 71.027846 -152.114476) (xy 71.095166 -152.138033) (xy 71.159425 -152.168978) (xy 71.187123 -152.186382)
			(xy 81.26525 -152.186382) (xy 81.26525 -152.126446) (xy 81.273073 -152.067024) (xy 81.288586 -152.009131)
			(xy 81.311522 -151.953758) (xy 81.341489 -151.901852) (xy 81.377976 -151.854302) (xy 81.420356 -151.811922)
			(xy 81.467906 -151.775435) (xy 81.519812 -151.745468) (xy 81.575185 -151.722532) (xy 81.633078 -151.707019)
			(xy 81.6925 -151.699196) (xy 81.722468 -151.698706) (xy 81.752436 -151.699196) (xy 81.811858 -151.707019)
			(xy 81.869751 -151.722532) (xy 81.925124 -151.745468) (xy 81.97703 -151.775435) (xy 82.02458 -151.811922)
			(xy 82.06696 -151.854302) (xy 82.103447 -151.901852) (xy 82.133414 -151.953758) (xy 82.15635 -152.009131)
			(xy 82.171863 -152.067024) (xy 82.179686 -152.126446) (xy 82.179686 -152.186382) (xy 82.171863 -152.245804)
			(xy 82.15635 -152.303697) (xy 82.133414 -152.35907) (xy 82.103447 -152.410976) (xy 82.06696 -152.458526)
			(xy 82.02458 -152.500906) (xy 81.97703 -152.537393) (xy 81.925124 -152.56736) (xy 81.869751 -152.590296)
			(xy 81.811858 -152.605809) (xy 81.752436 -152.613632) (xy 81.6925 -152.613632) (xy 81.633078 -152.605809)
			(xy 81.575185 -152.590296) (xy 81.519812 -152.56736) (xy 81.467906 -152.537393) (xy 81.420356 -152.500906)
			(xy 81.377976 -152.458526) (xy 81.341489 -152.410976) (xy 81.311522 -152.35907) (xy 81.288586 -152.303697)
			(xy 81.273073 -152.245804) (xy 81.26525 -152.186382) (xy 71.187123 -152.186382) (xy 71.219816 -152.206924)
			(xy 71.275578 -152.251393) (xy 71.326011 -152.301826) (xy 71.37048 -152.357588) (xy 71.408426 -152.417979)
			(xy 71.439371 -152.482238) (xy 71.462928 -152.549558) (xy 71.478798 -152.619093) (xy 71.486784 -152.689967)
			(xy 71.486784 -152.761289) (xy 71.478798 -152.832163) (xy 71.462928 -152.901698) (xy 71.439371 -152.969018)
			(xy 71.408426 -153.033277) (xy 71.37048 -153.093668) (xy 71.326011 -153.14943) (xy 71.275578 -153.199863)
			(xy 71.219816 -153.244332) (xy 71.159425 -153.282278) (xy 71.095166 -153.313223) (xy 71.027846 -153.33678)
			(xy 70.958311 -153.35265) (xy 70.887437 -153.360636) (xy 70.816115 -153.360636) (xy 70.745241 -153.35265)
			(xy 70.675706 -153.33678) (xy 70.608386 -153.313223) (xy 70.544127 -153.282278) (xy 70.483736 -153.244332)
			(xy 70.427974 -153.199863) (xy 70.377541 -153.14943) (xy 70.333072 -153.093668) (xy 70.295126 -153.033277)
			(xy 70.264181 -152.969018) (xy 70.240624 -152.901698) (xy 70.224754 -152.832163) (xy 70.216768 -152.761289)
			(xy 68.495172 -152.761289) (xy 68.487186 -152.832163) (xy 68.471316 -152.901698) (xy 68.447759 -152.969018)
			(xy 68.416814 -153.033277) (xy 68.378868 -153.093668) (xy 68.334399 -153.14943) (xy 68.283966 -153.199863)
			(xy 68.228204 -153.244332) (xy 68.167813 -153.282278) (xy 68.103554 -153.313223) (xy 68.036234 -153.33678)
			(xy 67.966699 -153.35265) (xy 67.895825 -153.360636) (xy 67.824503 -153.360636) (xy 67.753629 -153.35265)
			(xy 67.684094 -153.33678) (xy 67.616774 -153.313223) (xy 67.552515 -153.282278) (xy 67.492124 -153.244332)
			(xy 67.436362 -153.199863) (xy 67.385929 -153.14943) (xy 67.34146 -153.093668) (xy 67.303514 -153.033277)
			(xy 67.272569 -152.969018) (xy 67.249012 -152.901698) (xy 67.233142 -152.832163) (xy 67.225156 -152.761289)
			(xy 28.804108 -152.761289) (xy 28.804108 -153.993358) (xy 29.519874 -153.993358) (xy 29.519874 -153.906458)
			(xy 29.527892 -153.819929) (xy 29.54386 -153.734509) (xy 29.567641 -153.650927) (xy 29.599033 -153.569895)
			(xy 29.637767 -153.492106) (xy 29.683514 -153.418222) (xy 29.735883 -153.348875) (xy 29.794427 -153.284655)
			(xy 29.858647 -153.226111) (xy 29.927994 -153.173742) (xy 30.001878 -153.127995) (xy 30.079667 -153.089261)
			(xy 30.160699 -153.057869) (xy 30.244281 -153.034088) (xy 30.329701 -153.01812) (xy 30.41623 -153.010102)
			(xy 30.45968 -153.0096) (xy 30.50313 -153.010102) (xy 30.589659 -153.01812) (xy 30.675079 -153.034088)
			(xy 30.758661 -153.057869) (xy 30.839693 -153.089261) (xy 30.917482 -153.127995) (xy 30.991366 -153.173742)
			(xy 31.060713 -153.226111) (xy 31.124933 -153.284655) (xy 31.183477 -153.348875) (xy 31.235846 -153.418222)
			(xy 31.281593 -153.492106) (xy 31.320327 -153.569895) (xy 31.351719 -153.650927) (xy 31.3755 -153.734509)
			(xy 31.391468 -153.819929) (xy 31.399486 -153.906458) (xy 31.399486 -153.993358) (xy 34.599874 -153.993358)
			(xy 34.599874 -153.906458) (xy 34.607892 -153.819929) (xy 34.62386 -153.734509) (xy 34.647641 -153.650927)
			(xy 34.679033 -153.569895) (xy 34.717767 -153.492106) (xy 34.763514 -153.418222) (xy 34.815883 -153.348875)
			(xy 34.874427 -153.284655) (xy 34.938647 -153.226111) (xy 35.007994 -153.173742) (xy 35.081878 -153.127995)
			(xy 35.159667 -153.089261) (xy 35.240699 -153.057869) (xy 35.324281 -153.034088) (xy 35.409701 -153.01812)
			(xy 35.49623 -153.010102) (xy 35.53968 -153.0096) (xy 35.58313 -153.010102) (xy 35.669659 -153.01812)
			(xy 35.755079 -153.034088) (xy 35.838661 -153.057869) (xy 35.919693 -153.089261) (xy 35.997482 -153.127995)
			(xy 36.071366 -153.173742) (xy 36.140713 -153.226111) (xy 36.204933 -153.284655) (xy 36.263477 -153.348875)
			(xy 36.315846 -153.418222) (xy 36.361593 -153.492106) (xy 36.400327 -153.569895) (xy 36.430586 -153.648003)
			(xy 39.31208 -153.648003) (xy 39.31208 -153.576681) (xy 39.320066 -153.505807) (xy 39.335936 -153.436272)
			(xy 39.359493 -153.368952) (xy 39.390438 -153.304693) (xy 39.428384 -153.244302) (xy 39.472853 -153.18854)
			(xy 39.523286 -153.138107) (xy 39.579048 -153.093638) (xy 39.639439 -153.055692) (xy 39.703698 -153.024747)
			(xy 39.771018 -153.00119) (xy 39.840553 -152.98532) (xy 39.911427 -152.977334) (xy 39.947088 -152.976834)
			(xy 39.982749 -152.977334) (xy 40.053623 -152.98532) (xy 40.123158 -153.00119) (xy 40.190478 -153.024747)
			(xy 40.254737 -153.055692) (xy 40.315128 -153.093638) (xy 40.37089 -153.138107) (xy 40.421323 -153.18854)
			(xy 40.465792 -153.244302) (xy 40.503738 -153.304693) (xy 40.534683 -153.368952) (xy 40.549191 -153.410411)
			(xy 86.399122 -153.410411) (xy 86.401115 -153.210283) (xy 86.411112 -153.010394) (xy 86.429099 -152.811066)
			(xy 86.455047 -152.612617) (xy 86.488914 -152.415365) (xy 86.530646 -152.219626) (xy 86.580175 -152.025713)
			(xy 86.637424 -151.833938) (xy 86.702299 -151.644606) (xy 86.774698 -151.458022) (xy 86.854504 -151.274483)
			(xy 86.941589 -151.094285) (xy 87.035814 -150.917715) (xy 87.137028 -150.745056) (xy 87.245069 -150.576586)
			(xy 87.359764 -150.412572) (xy 87.48093 -150.253279) (xy 87.608371 -150.098962) (xy 87.741885 -149.949866)
			(xy 87.881257 -149.806232) (xy 88.026264 -149.66829) (xy 88.176675 -149.536259) (xy 88.332247 -149.410352)
			(xy 88.492732 -149.29077) (xy 88.657873 -149.177705) (xy 88.827405 -149.071337) (xy 89.001058 -148.971838)
			(xy 89.178552 -148.879366) (xy 89.359604 -148.79407) (xy 89.543924 -148.716086) (xy 89.731216 -148.645538)
			(xy 89.921181 -148.582541) (xy 90.113514 -148.527195) (xy 90.307908 -148.479588) (xy 90.504051 -148.439797)
			(xy 90.701628 -148.407885) (xy 90.900325 -148.383904) (xy 91.099821 -148.367891) (xy 91.299799 -148.359874)
			(xy 91.399868 -148.359368) (xy 91.499937 -148.359864) (xy 91.699915 -148.367861) (xy 91.899414 -148.383853)
			(xy 92.098112 -148.407814) (xy 92.295693 -148.439706) (xy 92.49184 -148.479477) (xy 92.686239 -148.527064)
			(xy 92.878578 -148.582391) (xy 93.068549 -148.645369) (xy 93.255848 -148.715897) (xy 93.440176 -148.793863)
			(xy 93.621237 -148.879141) (xy 93.79874 -148.971594) (xy 93.972403 -149.071076) (xy 94.141946 -149.177426)
			(xy 94.307099 -149.290475) (xy 94.467596 -149.41004) (xy 94.623181 -149.535932) (xy 94.773605 -149.667947)
			(xy 94.918626 -149.805875) (xy 95.058012 -149.949495) (xy 95.191541 -150.098576) (xy 95.318999 -150.252881)
			(xy 95.44018 -150.412162) (xy 95.554892 -150.576163) (xy 95.66295 -150.744623) (xy 95.764182 -150.917272)
			(xy 95.858425 -151.093832) (xy 95.945528 -151.274022) (xy 96.025353 -151.457552) (xy 96.09777 -151.644129)
			(xy 96.162665 -151.833454) (xy 96.219933 -152.025224) (xy 96.269483 -152.219131) (xy 96.311234 -152.414866)
			(xy 96.345121 -152.612115) (xy 96.371089 -152.810561) (xy 96.389096 -153.009888) (xy 96.399114 -153.209775)
			(xy 96.401127 -153.409903) (xy 96.395131 -153.609951) (xy 96.381135 -153.8096) (xy 96.359164 -154.008528)
			(xy 96.32925 -154.206418) (xy 96.291443 -154.402953) (xy 96.245804 -154.597818) (xy 96.192404 -154.790701)
			(xy 96.13133 -154.981293) (xy 96.062679 -155.169288) (xy 95.986561 -155.354387) (xy 95.903099 -155.536292)
			(xy 95.812426 -155.714711) (xy 95.714687 -155.889361) (xy 95.610038 -156.05996) (xy 95.498648 -156.226235)
			(xy 95.380694 -156.38792) (xy 95.256365 -156.544757) (xy 95.125862 -156.696494) (xy 94.989391 -156.842888)
			(xy 94.847173 -156.983704) (xy 94.699435 -157.118718) (xy 94.546413 -157.247713) (xy 94.388353 -157.370482)
			(xy 94.225507 -157.486829) (xy 94.058137 -157.596567) (xy 93.88651 -157.699521) (xy 93.710902 -157.795526)
			(xy 93.531592 -157.884428) (xy 93.34887 -157.966084) (xy 93.163027 -158.040365) (xy 92.97436 -158.107151)
			(xy 92.783173 -158.166334) (xy 92.589771 -158.217821) (xy 92.394464 -158.261529) (xy 92.197564 -158.297388)
			(xy 91.999387 -158.32534) (xy 91.800251 -158.34534) (xy 91.600474 -158.357358) (xy 91.400376 -158.361372)
			(xy 91.200278 -158.357378) (xy 91.000499 -158.345381) (xy 90.801361 -158.325401) (xy 90.603182 -158.297469)
			(xy 90.406278 -158.26163) (xy 90.210967 -158.217942) (xy 90.017559 -158.166475) (xy 89.826366 -158.107311)
			(xy 89.637693 -158.040544) (xy 89.451842 -157.966282) (xy 89.269111 -157.884644) (xy 89.089793 -157.795761)
			(xy 88.914175 -157.699774) (xy 88.742537 -157.596837) (xy 88.575156 -157.487116) (xy 88.412298 -157.370785)
			(xy 88.254226 -157.248032) (xy 88.101191 -157.119053) (xy 87.953439 -156.984055) (xy 87.811206 -156.843252)
			(xy 87.674721 -156.696872) (xy 87.544202 -156.545149) (xy 87.419858 -156.388325) (xy 87.301888 -156.226651)
			(xy 87.19048 -156.060387) (xy 87.085814 -155.889799) (xy 86.988057 -155.71516) (xy 86.897366 -155.536749)
			(xy 86.813885 -155.354853) (xy 86.737749 -155.169762) (xy 86.669079 -154.981773) (xy 86.607986 -154.791188)
			(xy 86.554566 -154.59831) (xy 86.508906 -154.40345) (xy 86.47108 -154.206919) (xy 86.441146 -154.009032)
			(xy 86.419154 -153.810106) (xy 86.405139 -153.610459) (xy 86.399122 -153.410411) (xy 40.549191 -153.410411)
			(xy 40.55824 -153.436272) (xy 40.57411 -153.505807) (xy 40.582096 -153.576681) (xy 40.582096 -153.648003)
			(xy 40.57411 -153.718877) (xy 40.55824 -153.788412) (xy 40.534683 -153.855732) (xy 40.503738 -153.919991)
			(xy 40.465792 -153.980382) (xy 40.421323 -154.036144) (xy 40.37089 -154.086577) (xy 40.315128 -154.131046)
			(xy 40.254737 -154.168992) (xy 40.190478 -154.199937) (xy 40.123158 -154.223494) (xy 40.053623 -154.239364)
			(xy 39.982749 -154.24735) (xy 39.911427 -154.24735) (xy 39.840553 -154.239364) (xy 39.771018 -154.223494)
			(xy 39.703698 -154.199937) (xy 39.639439 -154.168992) (xy 39.579048 -154.131046) (xy 39.523286 -154.086577)
			(xy 39.472853 -154.036144) (xy 39.428384 -153.980382) (xy 39.390438 -153.919991) (xy 39.359493 -153.855732)
			(xy 39.335936 -153.788412) (xy 39.320066 -153.718877) (xy 39.31208 -153.648003) (xy 36.430586 -153.648003)
			(xy 36.431719 -153.650927) (xy 36.4555 -153.734509) (xy 36.471468 -153.819929) (xy 36.479486 -153.906458)
			(xy 36.479486 -153.993358) (xy 36.471468 -154.079887) (xy 36.4555 -154.165307) (xy 36.431719 -154.248889)
			(xy 36.400327 -154.329921) (xy 36.361593 -154.40771) (xy 36.315846 -154.481594) (xy 36.263477 -154.550941)
			(xy 36.204933 -154.615161) (xy 36.140713 -154.673705) (xy 36.073846 -154.724201) (xy 67.225156 -154.724201)
			(xy 67.225156 -154.652879) (xy 67.233142 -154.582005) (xy 67.249012 -154.51247) (xy 67.272569 -154.44515)
			(xy 67.303514 -154.380891) (xy 67.34146 -154.3205) (xy 67.385929 -154.264738) (xy 67.436362 -154.214305)
			(xy 67.492124 -154.169836) (xy 67.552515 -154.13189) (xy 67.616774 -154.100945) (xy 67.684094 -154.077388)
			(xy 67.753629 -154.061518) (xy 67.824503 -154.053532) (xy 67.860164 -154.053032) (xy 67.895825 -154.053532)
			(xy 67.966699 -154.061518) (xy 68.036234 -154.077388) (xy 68.103554 -154.100945) (xy 68.167813 -154.13189)
			(xy 68.228204 -154.169836) (xy 68.283966 -154.214305) (xy 68.334399 -154.264738) (xy 68.378868 -154.3205)
			(xy 68.416814 -154.380891) (xy 68.447759 -154.44515) (xy 68.471316 -154.51247) (xy 68.487186 -154.582005)
			(xy 68.495172 -154.652879) (xy 68.495172 -154.724201) (xy 70.216768 -154.724201) (xy 70.216768 -154.652879)
			(xy 70.224754 -154.582005) (xy 70.240624 -154.51247) (xy 70.264181 -154.44515) (xy 70.295126 -154.380891)
			(xy 70.333072 -154.3205) (xy 70.377541 -154.264738) (xy 70.427974 -154.214305) (xy 70.483736 -154.169836)
			(xy 70.544127 -154.13189) (xy 70.608386 -154.100945) (xy 70.675706 -154.077388) (xy 70.745241 -154.061518)
			(xy 70.816115 -154.053532) (xy 70.851776 -154.053032) (xy 70.887437 -154.053532) (xy 70.958311 -154.061518)
			(xy 71.027846 -154.077388) (xy 71.095166 -154.100945) (xy 71.159425 -154.13189) (xy 71.219816 -154.169836)
			(xy 71.275578 -154.214305) (xy 71.326011 -154.264738) (xy 71.37048 -154.3205) (xy 71.408426 -154.380891)
			(xy 71.439371 -154.44515) (xy 71.462928 -154.51247) (xy 71.478798 -154.582005) (xy 71.486784 -154.652879)
			(xy 71.486784 -154.724201) (xy 71.478798 -154.795075) (xy 71.462928 -154.86461) (xy 71.439371 -154.93193)
			(xy 71.408426 -154.996189) (xy 71.37048 -155.05658) (xy 71.326011 -155.112342) (xy 71.275578 -155.162775)
			(xy 71.219816 -155.207244) (xy 71.159425 -155.24519) (xy 71.095166 -155.276135) (xy 71.027846 -155.299692)
			(xy 70.958311 -155.315562) (xy 70.887437 -155.323548) (xy 70.816115 -155.323548) (xy 70.745241 -155.315562)
			(xy 70.675706 -155.299692) (xy 70.608386 -155.276135) (xy 70.544127 -155.24519) (xy 70.483736 -155.207244)
			(xy 70.427974 -155.162775) (xy 70.377541 -155.112342) (xy 70.333072 -155.05658) (xy 70.295126 -154.996189)
			(xy 70.264181 -154.93193) (xy 70.240624 -154.86461) (xy 70.224754 -154.795075) (xy 70.216768 -154.724201)
			(xy 68.495172 -154.724201) (xy 68.487186 -154.795075) (xy 68.471316 -154.86461) (xy 68.447759 -154.93193)
			(xy 68.416814 -154.996189) (xy 68.378868 -155.05658) (xy 68.334399 -155.112342) (xy 68.283966 -155.162775)
			(xy 68.228204 -155.207244) (xy 68.167813 -155.24519) (xy 68.103554 -155.276135) (xy 68.036234 -155.299692)
			(xy 67.966699 -155.315562) (xy 67.895825 -155.323548) (xy 67.824503 -155.323548) (xy 67.753629 -155.315562)
			(xy 67.684094 -155.299692) (xy 67.616774 -155.276135) (xy 67.552515 -155.24519) (xy 67.492124 -155.207244)
			(xy 67.436362 -155.162775) (xy 67.385929 -155.112342) (xy 67.34146 -155.05658) (xy 67.303514 -154.996189)
			(xy 67.272569 -154.93193) (xy 67.249012 -154.86461) (xy 67.233142 -154.795075) (xy 67.225156 -154.724201)
			(xy 36.073846 -154.724201) (xy 36.071366 -154.726074) (xy 35.997482 -154.771821) (xy 35.919693 -154.810555)
			(xy 35.838661 -154.841947) (xy 35.755079 -154.865728) (xy 35.669659 -154.881696) (xy 35.58313 -154.889714)
			(xy 35.49623 -154.889714) (xy 35.409701 -154.881696) (xy 35.324281 -154.865728) (xy 35.240699 -154.841947)
			(xy 35.159667 -154.810555) (xy 35.081878 -154.771821) (xy 35.007994 -154.726074) (xy 34.938647 -154.673705)
			(xy 34.874427 -154.615161) (xy 34.815883 -154.550941) (xy 34.763514 -154.481594) (xy 34.717767 -154.40771)
			(xy 34.679033 -154.329921) (xy 34.647641 -154.248889) (xy 34.62386 -154.165307) (xy 34.607892 -154.079887)
			(xy 34.599874 -153.993358) (xy 31.399486 -153.993358) (xy 31.391468 -154.079887) (xy 31.3755 -154.165307)
			(xy 31.351719 -154.248889) (xy 31.320327 -154.329921) (xy 31.281593 -154.40771) (xy 31.235846 -154.481594)
			(xy 31.183477 -154.550941) (xy 31.124933 -154.615161) (xy 31.060713 -154.673705) (xy 30.991366 -154.726074)
			(xy 30.917482 -154.771821) (xy 30.839693 -154.810555) (xy 30.758661 -154.841947) (xy 30.675079 -154.865728)
			(xy 30.589659 -154.881696) (xy 30.50313 -154.889714) (xy 30.41623 -154.889714) (xy 30.329701 -154.881696)
			(xy 30.244281 -154.865728) (xy 30.160699 -154.841947) (xy 30.079667 -154.810555) (xy 30.001878 -154.771821)
			(xy 29.927994 -154.726074) (xy 29.858647 -154.673705) (xy 29.794427 -154.615161) (xy 29.735883 -154.550941)
			(xy 29.683514 -154.481594) (xy 29.637767 -154.40771) (xy 29.599033 -154.329921) (xy 29.567641 -154.248889)
			(xy 29.54386 -154.165307) (xy 29.527892 -154.079887) (xy 29.519874 -153.993358) (xy 28.804108 -153.993358)
			(xy 28.804108 -156.533358) (xy 29.519874 -156.533358) (xy 29.519874 -156.446458) (xy 29.527892 -156.359929)
			(xy 29.54386 -156.274509) (xy 29.567641 -156.190927) (xy 29.599033 -156.109895) (xy 29.637767 -156.032106)
			(xy 29.683514 -155.958222) (xy 29.735883 -155.888875) (xy 29.794427 -155.824655) (xy 29.858647 -155.766111)
			(xy 29.927994 -155.713742) (xy 30.001878 -155.667995) (xy 30.079667 -155.629261) (xy 30.160699 -155.597869)
			(xy 30.244281 -155.574088) (xy 30.329701 -155.55812) (xy 30.41623 -155.550102) (xy 30.45968 -155.5496)
			(xy 30.50313 -155.550102) (xy 30.589659 -155.55812) (xy 30.675079 -155.574088) (xy 30.758661 -155.597869)
			(xy 30.839693 -155.629261) (xy 30.917482 -155.667995) (xy 30.991366 -155.713742) (xy 31.060713 -155.766111)
			(xy 31.124933 -155.824655) (xy 31.183477 -155.888875) (xy 31.235846 -155.958222) (xy 31.281593 -156.032106)
			(xy 31.320327 -156.109895) (xy 31.351719 -156.190927) (xy 31.3755 -156.274509) (xy 31.391468 -156.359929)
			(xy 31.399486 -156.446458) (xy 31.399486 -156.533358) (xy 34.599874 -156.533358) (xy 34.599874 -156.446458)
			(xy 34.607892 -156.359929) (xy 34.62386 -156.274509) (xy 34.647641 -156.190927) (xy 34.679033 -156.109895)
			(xy 34.717767 -156.032106) (xy 34.763514 -155.958222) (xy 34.815883 -155.888875) (xy 34.874427 -155.824655)
			(xy 34.938647 -155.766111) (xy 35.007994 -155.713742) (xy 35.081878 -155.667995) (xy 35.159667 -155.629261)
			(xy 35.240699 -155.597869) (xy 35.324281 -155.574088) (xy 35.409701 -155.55812) (xy 35.49623 -155.550102)
			(xy 35.53968 -155.5496) (xy 35.58313 -155.550102) (xy 35.669659 -155.55812) (xy 35.755079 -155.574088)
			(xy 35.838661 -155.597869) (xy 35.919693 -155.629261) (xy 35.997482 -155.667995) (xy 36.071366 -155.713742)
			(xy 36.140713 -155.766111) (xy 36.204933 -155.824655) (xy 36.258538 -155.883457) (xy 39.31208 -155.883457)
			(xy 39.31208 -155.812135) (xy 39.320066 -155.741261) (xy 39.335936 -155.671726) (xy 39.359493 -155.604406)
			(xy 39.390438 -155.540147) (xy 39.428384 -155.479756) (xy 39.472853 -155.423994) (xy 39.523286 -155.373561)
			(xy 39.579048 -155.329092) (xy 39.639439 -155.291146) (xy 39.703698 -155.260201) (xy 39.771018 -155.236644)
			(xy 39.840553 -155.220774) (xy 39.911427 -155.212788) (xy 39.947088 -155.212288) (xy 39.982749 -155.212788)
			(xy 40.053623 -155.220774) (xy 40.123158 -155.236644) (xy 40.190478 -155.260201) (xy 40.254737 -155.291146)
			(xy 40.315128 -155.329092) (xy 40.37089 -155.373561) (xy 40.421323 -155.423994) (xy 40.465792 -155.479756)
			(xy 40.503738 -155.540147) (xy 40.534683 -155.604406) (xy 40.55824 -155.671726) (xy 40.57411 -155.741261)
			(xy 40.582096 -155.812135) (xy 40.582096 -155.883457) (xy 40.57411 -155.954331) (xy 40.55824 -156.023866)
			(xy 40.534683 -156.091186) (xy 40.503738 -156.155445) (xy 40.465792 -156.215836) (xy 40.421323 -156.271598)
			(xy 40.37089 -156.322031) (xy 40.315128 -156.3665) (xy 40.254737 -156.404446) (xy 40.190478 -156.435391)
			(xy 40.123158 -156.458948) (xy 40.053623 -156.474818) (xy 39.982749 -156.482804) (xy 39.911427 -156.482804)
			(xy 39.840553 -156.474818) (xy 39.771018 -156.458948) (xy 39.703698 -156.435391) (xy 39.639439 -156.404446)
			(xy 39.579048 -156.3665) (xy 39.523286 -156.322031) (xy 39.472853 -156.271598) (xy 39.428384 -156.215836)
			(xy 39.390438 -156.155445) (xy 39.359493 -156.091186) (xy 39.335936 -156.023866) (xy 39.320066 -155.954331)
			(xy 39.31208 -155.883457) (xy 36.258538 -155.883457) (xy 36.263477 -155.888875) (xy 36.315846 -155.958222)
			(xy 36.361593 -156.032106) (xy 36.400327 -156.109895) (xy 36.431719 -156.190927) (xy 36.4555 -156.274509)
			(xy 36.471468 -156.359929) (xy 36.479486 -156.446458) (xy 36.479486 -156.533358) (xy 36.471468 -156.619887)
			(xy 36.4555 -156.705307) (xy 36.431719 -156.788889) (xy 36.401185 -156.867707) (xy 67.225156 -156.867707)
			(xy 67.225156 -156.796385) (xy 67.233142 -156.725511) (xy 67.249012 -156.655976) (xy 67.272569 -156.588656)
			(xy 67.303514 -156.524397) (xy 67.34146 -156.464006) (xy 67.385929 -156.408244) (xy 67.436362 -156.357811)
			(xy 67.492124 -156.313342) (xy 67.552515 -156.275396) (xy 67.616774 -156.244451) (xy 67.684094 -156.220894)
			(xy 67.753629 -156.205024) (xy 67.824503 -156.197038) (xy 67.860164 -156.196538) (xy 67.895825 -156.197038)
			(xy 67.966699 -156.205024) (xy 68.036234 -156.220894) (xy 68.103554 -156.244451) (xy 68.167813 -156.275396)
			(xy 68.228204 -156.313342) (xy 68.283966 -156.357811) (xy 68.334399 -156.408244) (xy 68.378868 -156.464006)
			(xy 68.416814 -156.524397) (xy 68.447759 -156.588656) (xy 68.471316 -156.655976) (xy 68.487186 -156.725511)
			(xy 68.495172 -156.796385) (xy 68.495172 -156.867707) (xy 70.216768 -156.867707) (xy 70.216768 -156.796385)
			(xy 70.224754 -156.725511) (xy 70.240624 -156.655976) (xy 70.264181 -156.588656) (xy 70.295126 -156.524397)
			(xy 70.333072 -156.464006) (xy 70.377541 -156.408244) (xy 70.427974 -156.357811) (xy 70.483736 -156.313342)
			(xy 70.544127 -156.275396) (xy 70.608386 -156.244451) (xy 70.675706 -156.220894) (xy 70.745241 -156.205024)
			(xy 70.816115 -156.197038) (xy 70.851776 -156.196538) (xy 70.887437 -156.197038) (xy 70.958311 -156.205024)
			(xy 71.027846 -156.220894) (xy 71.095166 -156.244451) (xy 71.159425 -156.275396) (xy 71.219816 -156.313342)
			(xy 71.275578 -156.357811) (xy 71.326011 -156.408244) (xy 71.37048 -156.464006) (xy 71.408426 -156.524397)
			(xy 71.439371 -156.588656) (xy 71.462928 -156.655976) (xy 71.478798 -156.725511) (xy 71.486784 -156.796385)
			(xy 71.486784 -156.867707) (xy 71.478798 -156.938581) (xy 71.462928 -157.008116) (xy 71.439371 -157.075436)
			(xy 71.408426 -157.139695) (xy 71.37048 -157.200086) (xy 71.326011 -157.255848) (xy 71.275578 -157.306281)
			(xy 71.219816 -157.35075) (xy 71.159425 -157.388696) (xy 71.095166 -157.419641) (xy 71.027846 -157.443198)
			(xy 70.958311 -157.459068) (xy 70.887437 -157.467054) (xy 70.816115 -157.467054) (xy 70.745241 -157.459068)
			(xy 70.675706 -157.443198) (xy 70.608386 -157.419641) (xy 70.544127 -157.388696) (xy 70.483736 -157.35075)
			(xy 70.427974 -157.306281) (xy 70.377541 -157.255848) (xy 70.333072 -157.200086) (xy 70.295126 -157.139695)
			(xy 70.264181 -157.075436) (xy 70.240624 -157.008116) (xy 70.224754 -156.938581) (xy 70.216768 -156.867707)
			(xy 68.495172 -156.867707) (xy 68.487186 -156.938581) (xy 68.471316 -157.008116) (xy 68.447759 -157.075436)
			(xy 68.416814 -157.139695) (xy 68.378868 -157.200086) (xy 68.334399 -157.255848) (xy 68.283966 -157.306281)
			(xy 68.228204 -157.35075) (xy 68.167813 -157.388696) (xy 68.103554 -157.419641) (xy 68.036234 -157.443198)
			(xy 67.966699 -157.459068) (xy 67.895825 -157.467054) (xy 67.824503 -157.467054) (xy 67.753629 -157.459068)
			(xy 67.684094 -157.443198) (xy 67.616774 -157.419641) (xy 67.552515 -157.388696) (xy 67.492124 -157.35075)
			(xy 67.436362 -157.306281) (xy 67.385929 -157.255848) (xy 67.34146 -157.200086) (xy 67.303514 -157.139695)
			(xy 67.272569 -157.075436) (xy 67.249012 -157.008116) (xy 67.233142 -156.938581) (xy 67.225156 -156.867707)
			(xy 36.401185 -156.867707) (xy 36.400327 -156.869921) (xy 36.361593 -156.94771) (xy 36.315846 -157.021594)
			(xy 36.263477 -157.090941) (xy 36.204933 -157.155161) (xy 36.140713 -157.213705) (xy 36.071366 -157.266074)
			(xy 35.997482 -157.311821) (xy 35.919693 -157.350555) (xy 35.838661 -157.381947) (xy 35.755079 -157.405728)
			(xy 35.669659 -157.421696) (xy 35.58313 -157.429714) (xy 35.49623 -157.429714) (xy 35.409701 -157.421696)
			(xy 35.324281 -157.405728) (xy 35.240699 -157.381947) (xy 35.159667 -157.350555) (xy 35.081878 -157.311821)
			(xy 35.007994 -157.266074) (xy 34.938647 -157.213705) (xy 34.874427 -157.155161) (xy 34.815883 -157.090941)
			(xy 34.763514 -157.021594) (xy 34.717767 -156.94771) (xy 34.679033 -156.869921) (xy 34.647641 -156.788889)
			(xy 34.62386 -156.705307) (xy 34.607892 -156.619887) (xy 34.599874 -156.533358) (xy 31.399486 -156.533358)
			(xy 31.391468 -156.619887) (xy 31.3755 -156.705307) (xy 31.351719 -156.788889) (xy 31.320327 -156.869921)
			(xy 31.281593 -156.94771) (xy 31.235846 -157.021594) (xy 31.183477 -157.090941) (xy 31.124933 -157.155161)
			(xy 31.060713 -157.213705) (xy 30.991366 -157.266074) (xy 30.917482 -157.311821) (xy 30.839693 -157.350555)
			(xy 30.758661 -157.381947) (xy 30.675079 -157.405728) (xy 30.589659 -157.421696) (xy 30.50313 -157.429714)
			(xy 30.41623 -157.429714) (xy 30.329701 -157.421696) (xy 30.244281 -157.405728) (xy 30.160699 -157.381947)
			(xy 30.079667 -157.350555) (xy 30.001878 -157.311821) (xy 29.927994 -157.266074) (xy 29.858647 -157.213705)
			(xy 29.794427 -157.155161) (xy 29.735883 -157.090941) (xy 29.683514 -157.021594) (xy 29.637767 -156.94771)
			(xy 29.599033 -156.869921) (xy 29.567641 -156.788889) (xy 29.54386 -156.705307) (xy 29.527892 -156.619887)
			(xy 29.519874 -156.533358) (xy 28.804108 -156.533358) (xy 28.804108 -159.073358) (xy 29.519874 -159.073358)
			(xy 29.519874 -158.986458) (xy 29.527892 -158.899929) (xy 29.54386 -158.814509) (xy 29.567641 -158.730927)
			(xy 29.599033 -158.649895) (xy 29.637767 -158.572106) (xy 29.683514 -158.498222) (xy 29.735883 -158.428875)
			(xy 29.794427 -158.364655) (xy 29.858647 -158.306111) (xy 29.927994 -158.253742) (xy 30.001878 -158.207995)
			(xy 30.079667 -158.169261) (xy 30.160699 -158.137869) (xy 30.244281 -158.114088) (xy 30.329701 -158.09812)
			(xy 30.41623 -158.090102) (xy 30.45968 -158.0896) (xy 30.50313 -158.090102) (xy 30.589659 -158.09812)
			(xy 30.675079 -158.114088) (xy 30.758661 -158.137869) (xy 30.839693 -158.169261) (xy 30.917482 -158.207995)
			(xy 30.991366 -158.253742) (xy 31.060713 -158.306111) (xy 31.124933 -158.364655) (xy 31.183477 -158.428875)
			(xy 31.235846 -158.498222) (xy 31.281593 -158.572106) (xy 31.320327 -158.649895) (xy 31.351719 -158.730927)
			(xy 31.3755 -158.814509) (xy 31.391468 -158.899929) (xy 31.399486 -158.986458) (xy 31.399486 -159.073358)
			(xy 34.599874 -159.073358) (xy 34.599874 -158.986458) (xy 34.607892 -158.899929) (xy 34.62386 -158.814509)
			(xy 34.647641 -158.730927) (xy 34.679033 -158.649895) (xy 34.717767 -158.572106) (xy 34.763514 -158.498222)
			(xy 34.815883 -158.428875) (xy 34.874427 -158.364655) (xy 34.938647 -158.306111) (xy 35.007994 -158.253742)
			(xy 35.081878 -158.207995) (xy 35.159667 -158.169261) (xy 35.240699 -158.137869) (xy 35.324281 -158.114088)
			(xy 35.409701 -158.09812) (xy 35.49623 -158.090102) (xy 35.53968 -158.0896) (xy 35.58313 -158.090102)
			(xy 35.669659 -158.09812) (xy 35.755079 -158.114088) (xy 35.838661 -158.137869) (xy 35.919693 -158.169261)
			(xy 35.997482 -158.207995) (xy 36.071366 -158.253742) (xy 36.140713 -158.306111) (xy 36.204933 -158.364655)
			(xy 36.263477 -158.428875) (xy 36.315846 -158.498222) (xy 36.348975 -158.551727) (xy 39.31208 -158.551727)
			(xy 39.31208 -158.480405) (xy 39.320066 -158.409531) (xy 39.335936 -158.339996) (xy 39.359493 -158.272676)
			(xy 39.390438 -158.208417) (xy 39.428384 -158.148026) (xy 39.472853 -158.092264) (xy 39.523286 -158.041831)
			(xy 39.579048 -157.997362) (xy 39.639439 -157.959416) (xy 39.703698 -157.928471) (xy 39.771018 -157.904914)
			(xy 39.840553 -157.889044) (xy 39.911427 -157.881058) (xy 39.947088 -157.880558) (xy 39.982749 -157.881058)
			(xy 40.053623 -157.889044) (xy 40.123158 -157.904914) (xy 40.190478 -157.928471) (xy 40.254737 -157.959416)
			(xy 40.315128 -157.997362) (xy 40.37089 -158.041831) (xy 40.421323 -158.092264) (xy 40.465792 -158.148026)
			(xy 40.503738 -158.208417) (xy 40.534683 -158.272676) (xy 40.55824 -158.339996) (xy 40.57411 -158.409531)
			(xy 40.582096 -158.480405) (xy 40.582096 -158.551727) (xy 40.57411 -158.622601) (xy 40.55824 -158.692136)
			(xy 40.534683 -158.759456) (xy 40.503738 -158.823715) (xy 40.465792 -158.884106) (xy 40.421323 -158.939868)
			(xy 40.37089 -158.990301) (xy 40.315128 -159.03477) (xy 40.254737 -159.072716) (xy 40.190478 -159.103661)
			(xy 40.123158 -159.127218) (xy 40.053623 -159.143088) (xy 39.982749 -159.151074) (xy 39.911427 -159.151074)
			(xy 39.840553 -159.143088) (xy 39.771018 -159.127218) (xy 39.703698 -159.103661) (xy 39.639439 -159.072716)
			(xy 39.579048 -159.03477) (xy 39.523286 -158.990301) (xy 39.472853 -158.939868) (xy 39.428384 -158.884106)
			(xy 39.390438 -158.823715) (xy 39.359493 -158.759456) (xy 39.335936 -158.692136) (xy 39.320066 -158.622601)
			(xy 39.31208 -158.551727) (xy 36.348975 -158.551727) (xy 36.361593 -158.572106) (xy 36.400327 -158.649895)
			(xy 36.431719 -158.730927) (xy 36.4555 -158.814509) (xy 36.471468 -158.899929) (xy 36.479486 -158.986458)
			(xy 36.479486 -159.073358) (xy 36.471468 -159.159887) (xy 36.4555 -159.245307) (xy 36.431719 -159.328889)
			(xy 36.400327 -159.409921) (xy 36.361593 -159.48771) (xy 36.315846 -159.561594) (xy 36.263477 -159.630941)
			(xy 36.204933 -159.695161) (xy 36.140713 -159.753705) (xy 36.071366 -159.806074) (xy 35.997482 -159.851821)
			(xy 35.919693 -159.890555) (xy 35.838661 -159.921947) (xy 35.755079 -159.945728) (xy 35.669659 -159.961696)
			(xy 35.58313 -159.969714) (xy 35.49623 -159.969714) (xy 35.409701 -159.961696) (xy 35.324281 -159.945728)
			(xy 35.240699 -159.921947) (xy 35.159667 -159.890555) (xy 35.081878 -159.851821) (xy 35.007994 -159.806074)
			(xy 34.938647 -159.753705) (xy 34.874427 -159.695161) (xy 34.815883 -159.630941) (xy 34.763514 -159.561594)
			(xy 34.717767 -159.48771) (xy 34.679033 -159.409921) (xy 34.647641 -159.328889) (xy 34.62386 -159.245307)
			(xy 34.607892 -159.159887) (xy 34.599874 -159.073358) (xy 31.399486 -159.073358) (xy 31.391468 -159.159887)
			(xy 31.3755 -159.245307) (xy 31.351719 -159.328889) (xy 31.320327 -159.409921) (xy 31.281593 -159.48771)
			(xy 31.235846 -159.561594) (xy 31.183477 -159.630941) (xy 31.124933 -159.695161) (xy 31.060713 -159.753705)
			(xy 30.991366 -159.806074) (xy 30.917482 -159.851821) (xy 30.839693 -159.890555) (xy 30.758661 -159.921947)
			(xy 30.675079 -159.945728) (xy 30.589659 -159.961696) (xy 30.50313 -159.969714) (xy 30.41623 -159.969714)
			(xy 30.329701 -159.961696) (xy 30.244281 -159.945728) (xy 30.160699 -159.921947) (xy 30.079667 -159.890555)
			(xy 30.001878 -159.851821) (xy 29.927994 -159.806074) (xy 29.858647 -159.753705) (xy 29.794427 -159.695161)
			(xy 29.735883 -159.630941) (xy 29.683514 -159.561594) (xy 29.637767 -159.48771) (xy 29.599033 -159.409921)
			(xy 29.567641 -159.328889) (xy 29.54386 -159.245307) (xy 29.527892 -159.159887) (xy 29.519874 -159.073358)
			(xy 28.804108 -159.073358) (xy 28.804108 -161.613358) (xy 29.519874 -161.613358) (xy 29.519874 -161.526458)
			(xy 29.527892 -161.439929) (xy 29.54386 -161.354509) (xy 29.567641 -161.270927) (xy 29.599033 -161.189895)
			(xy 29.637767 -161.112106) (xy 29.683514 -161.038222) (xy 29.735883 -160.968875) (xy 29.794427 -160.904655)
			(xy 29.858647 -160.846111) (xy 29.927994 -160.793742) (xy 30.001878 -160.747995) (xy 30.079667 -160.709261)
			(xy 30.160699 -160.677869) (xy 30.244281 -160.654088) (xy 30.329701 -160.63812) (xy 30.41623 -160.630102)
			(xy 30.45968 -160.6296) (xy 30.50313 -160.630102) (xy 30.589659 -160.63812) (xy 30.675079 -160.654088)
			(xy 30.758661 -160.677869) (xy 30.839693 -160.709261) (xy 30.917482 -160.747995) (xy 30.991366 -160.793742)
			(xy 31.060713 -160.846111) (xy 31.124933 -160.904655) (xy 31.183477 -160.968875) (xy 31.235846 -161.038222)
			(xy 31.281593 -161.112106) (xy 31.320327 -161.189895) (xy 31.351719 -161.270927) (xy 31.3755 -161.354509)
			(xy 31.391468 -161.439929) (xy 31.399486 -161.526458) (xy 31.399486 -161.613358) (xy 34.599874 -161.613358)
			(xy 34.599874 -161.526458) (xy 34.607892 -161.439929) (xy 34.62386 -161.354509) (xy 34.647641 -161.270927)
			(xy 34.679033 -161.189895) (xy 34.717767 -161.112106) (xy 34.763514 -161.038222) (xy 34.815883 -160.968875)
			(xy 34.874427 -160.904655) (xy 34.938647 -160.846111) (xy 35.007994 -160.793742) (xy 35.081878 -160.747995)
			(xy 35.159667 -160.709261) (xy 35.240699 -160.677869) (xy 35.324281 -160.654088) (xy 35.409701 -160.63812)
			(xy 35.49623 -160.630102) (xy 35.53968 -160.6296) (xy 35.58313 -160.630102) (xy 35.669659 -160.63812)
			(xy 35.755079 -160.654088) (xy 35.838661 -160.677869) (xy 35.919693 -160.709261) (xy 35.997482 -160.747995)
			(xy 36.071366 -160.793742) (xy 36.140713 -160.846111) (xy 36.204933 -160.904655) (xy 36.221953 -160.923325)
			(xy 39.31208 -160.923325) (xy 39.31208 -160.852003) (xy 39.320066 -160.781129) (xy 39.335936 -160.711594)
			(xy 39.359493 -160.644274) (xy 39.390438 -160.580015) (xy 39.428384 -160.519624) (xy 39.472853 -160.463862)
			(xy 39.523286 -160.413429) (xy 39.579048 -160.36896) (xy 39.639439 -160.331014) (xy 39.703698 -160.300069)
			(xy 39.771018 -160.276512) (xy 39.840553 -160.260642) (xy 39.911427 -160.252656) (xy 39.947088 -160.252156)
			(xy 39.982749 -160.252656) (xy 40.053623 -160.260642) (xy 40.123158 -160.276512) (xy 40.190478 -160.300069)
			(xy 40.254737 -160.331014) (xy 40.315128 -160.36896) (xy 40.37089 -160.413429) (xy 40.421323 -160.463862)
			(xy 40.465792 -160.519624) (xy 40.503738 -160.580015) (xy 40.534683 -160.644274) (xy 40.55824 -160.711594)
			(xy 40.57411 -160.781129) (xy 40.582096 -160.852003) (xy 40.582096 -160.923325) (xy 40.57411 -160.994199)
			(xy 40.55824 -161.063734) (xy 40.534683 -161.131054) (xy 40.503738 -161.195313) (xy 40.465792 -161.255704)
			(xy 40.421323 -161.311466) (xy 40.37089 -161.361899) (xy 40.315128 -161.406368) (xy 40.254737 -161.444314)
			(xy 40.190478 -161.475259) (xy 40.123158 -161.498816) (xy 40.053623 -161.514686) (xy 39.982749 -161.522672)
			(xy 39.911427 -161.522672) (xy 39.840553 -161.514686) (xy 39.771018 -161.498816) (xy 39.703698 -161.475259)
			(xy 39.639439 -161.444314) (xy 39.579048 -161.406368) (xy 39.523286 -161.361899) (xy 39.472853 -161.311466)
			(xy 39.428384 -161.255704) (xy 39.390438 -161.195313) (xy 39.359493 -161.131054) (xy 39.335936 -161.063734)
			(xy 39.320066 -160.994199) (xy 39.31208 -160.923325) (xy 36.221953 -160.923325) (xy 36.263477 -160.968875)
			(xy 36.315846 -161.038222) (xy 36.361593 -161.112106) (xy 36.400327 -161.189895) (xy 36.431719 -161.270927)
			(xy 36.4555 -161.354509) (xy 36.471468 -161.439929) (xy 36.479486 -161.526458) (xy 36.479486 -161.613358)
			(xy 36.471468 -161.699887) (xy 36.4555 -161.785307) (xy 36.431719 -161.868889) (xy 36.400327 -161.949921)
			(xy 36.361593 -162.02771) (xy 36.315846 -162.101594) (xy 36.263477 -162.170941) (xy 36.204933 -162.235161)
			(xy 36.140713 -162.293705) (xy 36.071366 -162.346074) (xy 35.997482 -162.391821) (xy 35.919693 -162.430555)
			(xy 35.838661 -162.461947) (xy 35.755079 -162.485728) (xy 35.669659 -162.501696) (xy 35.58313 -162.509714)
			(xy 35.49623 -162.509714) (xy 35.409701 -162.501696) (xy 35.324281 -162.485728) (xy 35.240699 -162.461947)
			(xy 35.159667 -162.430555) (xy 35.081878 -162.391821) (xy 35.007994 -162.346074) (xy 34.938647 -162.293705)
			(xy 34.874427 -162.235161) (xy 34.815883 -162.170941) (xy 34.763514 -162.101594) (xy 34.717767 -162.02771)
			(xy 34.679033 -161.949921) (xy 34.647641 -161.868889) (xy 34.62386 -161.785307) (xy 34.607892 -161.699887)
			(xy 34.599874 -161.613358) (xy 31.399486 -161.613358) (xy 31.391468 -161.699887) (xy 31.3755 -161.785307)
			(xy 31.351719 -161.868889) (xy 31.320327 -161.949921) (xy 31.281593 -162.02771) (xy 31.235846 -162.101594)
			(xy 31.183477 -162.170941) (xy 31.124933 -162.235161) (xy 31.060713 -162.293705) (xy 30.991366 -162.346074)
			(xy 30.917482 -162.391821) (xy 30.839693 -162.430555) (xy 30.758661 -162.461947) (xy 30.675079 -162.485728)
			(xy 30.589659 -162.501696) (xy 30.50313 -162.509714) (xy 30.41623 -162.509714) (xy 30.329701 -162.501696)
			(xy 30.244281 -162.485728) (xy 30.160699 -162.461947) (xy 30.079667 -162.430555) (xy 30.001878 -162.391821)
			(xy 29.927994 -162.346074) (xy 29.858647 -162.293705) (xy 29.794427 -162.235161) (xy 29.735883 -162.170941)
			(xy 29.683514 -162.101594) (xy 29.637767 -162.02771) (xy 29.599033 -161.949921) (xy 29.567641 -161.868889)
			(xy 29.54386 -161.785307) (xy 29.527892 -161.699887) (xy 29.519874 -161.613358) (xy 28.804108 -161.613358)
			(xy 28.804108 -162.886237) (xy 39.31208 -162.886237) (xy 39.31208 -162.814915) (xy 39.320066 -162.744041)
			(xy 39.335936 -162.674506) (xy 39.359493 -162.607186) (xy 39.390438 -162.542927) (xy 39.428384 -162.482536)
			(xy 39.472853 -162.426774) (xy 39.523286 -162.376341) (xy 39.579048 -162.331872) (xy 39.639439 -162.293926)
			(xy 39.703698 -162.262981) (xy 39.771018 -162.239424) (xy 39.840553 -162.223554) (xy 39.911427 -162.215568)
			(xy 39.947088 -162.215068) (xy 39.982749 -162.215568) (xy 40.053623 -162.223554) (xy 40.123158 -162.239424)
			(xy 40.190478 -162.262981) (xy 40.254737 -162.293926) (xy 40.315128 -162.331872) (xy 40.37089 -162.376341)
			(xy 40.421323 -162.426774) (xy 40.465792 -162.482536) (xy 40.503738 -162.542927) (xy 40.534683 -162.607186)
			(xy 40.55824 -162.674506) (xy 40.57411 -162.744041) (xy 40.582096 -162.814915) (xy 40.582096 -162.886237)
			(xy 40.57411 -162.957111) (xy 40.55824 -163.026646) (xy 40.534683 -163.093966) (xy 40.503738 -163.158225)
			(xy 40.465792 -163.218616) (xy 40.421323 -163.274378) (xy 40.37089 -163.324811) (xy 40.315128 -163.36928)
			(xy 40.254737 -163.407226) (xy 40.190478 -163.438171) (xy 40.123158 -163.461728) (xy 40.053623 -163.477598)
			(xy 39.982749 -163.485584) (xy 39.911427 -163.485584) (xy 39.840553 -163.477598) (xy 39.771018 -163.461728)
			(xy 39.703698 -163.438171) (xy 39.639439 -163.407226) (xy 39.579048 -163.36928) (xy 39.523286 -163.324811)
			(xy 39.472853 -163.274378) (xy 39.428384 -163.218616) (xy 39.390438 -163.158225) (xy 39.359493 -163.093966)
			(xy 39.335936 -163.026646) (xy 39.320066 -162.957111) (xy 39.31208 -162.886237) (xy 28.804108 -162.886237)
			(xy 28.804108 -164.153358) (xy 29.519874 -164.153358) (xy 29.519874 -164.066458) (xy 29.527892 -163.979929)
			(xy 29.54386 -163.894509) (xy 29.567641 -163.810927) (xy 29.599033 -163.729895) (xy 29.637767 -163.652106)
			(xy 29.683514 -163.578222) (xy 29.735883 -163.508875) (xy 29.794427 -163.444655) (xy 29.858647 -163.386111)
			(xy 29.927994 -163.333742) (xy 30.001878 -163.287995) (xy 30.079667 -163.249261) (xy 30.160699 -163.217869)
			(xy 30.244281 -163.194088) (xy 30.329701 -163.17812) (xy 30.41623 -163.170102) (xy 30.45968 -163.1696)
			(xy 30.50313 -163.170102) (xy 30.589659 -163.17812) (xy 30.675079 -163.194088) (xy 30.758661 -163.217869)
			(xy 30.839693 -163.249261) (xy 30.917482 -163.287995) (xy 30.991366 -163.333742) (xy 31.060713 -163.386111)
			(xy 31.124933 -163.444655) (xy 31.183477 -163.508875) (xy 31.235846 -163.578222) (xy 31.281593 -163.652106)
			(xy 31.320327 -163.729895) (xy 31.351719 -163.810927) (xy 31.3755 -163.894509) (xy 31.391468 -163.979929)
			(xy 31.399486 -164.066458) (xy 31.399486 -164.153358) (xy 34.599874 -164.153358) (xy 34.599874 -164.066458)
			(xy 34.607892 -163.979929) (xy 34.62386 -163.894509) (xy 34.647641 -163.810927) (xy 34.679033 -163.729895)
			(xy 34.717767 -163.652106) (xy 34.763514 -163.578222) (xy 34.815883 -163.508875) (xy 34.874427 -163.444655)
			(xy 34.938647 -163.386111) (xy 35.007994 -163.333742) (xy 35.081878 -163.287995) (xy 35.159667 -163.249261)
			(xy 35.240699 -163.217869) (xy 35.324281 -163.194088) (xy 35.409701 -163.17812) (xy 35.49623 -163.170102)
			(xy 35.53968 -163.1696) (xy 35.58313 -163.170102) (xy 35.669659 -163.17812) (xy 35.755079 -163.194088)
			(xy 35.838661 -163.217869) (xy 35.919693 -163.249261) (xy 35.997482 -163.287995) (xy 36.071366 -163.333742)
			(xy 36.140713 -163.386111) (xy 36.204933 -163.444655) (xy 36.263477 -163.508875) (xy 36.315846 -163.578222)
			(xy 36.361593 -163.652106) (xy 36.400327 -163.729895) (xy 36.431719 -163.810927) (xy 36.4555 -163.894509)
			(xy 36.471468 -163.979929) (xy 36.479486 -164.066458) (xy 36.479486 -164.153358) (xy 36.471468 -164.239887)
			(xy 36.4555 -164.325307) (xy 36.431719 -164.408889) (xy 36.400327 -164.489921) (xy 36.361593 -164.56771)
			(xy 36.315846 -164.641594) (xy 36.263477 -164.710941) (xy 36.204933 -164.775161) (xy 36.140713 -164.833705)
			(xy 36.071366 -164.886074) (xy 35.997482 -164.931821) (xy 35.919693 -164.970555) (xy 35.838661 -165.001947)
			(xy 35.755079 -165.025728) (xy 35.733601 -165.029743) (xy 39.31208 -165.029743) (xy 39.31208 -164.958421)
			(xy 39.320066 -164.887547) (xy 39.335936 -164.818012) (xy 39.359493 -164.750692) (xy 39.390438 -164.686433)
			(xy 39.428384 -164.626042) (xy 39.472853 -164.57028) (xy 39.523286 -164.519847) (xy 39.579048 -164.475378)
			(xy 39.639439 -164.437432) (xy 39.703698 -164.406487) (xy 39.771018 -164.38293) (xy 39.840553 -164.36706)
			(xy 39.911427 -164.359074) (xy 39.947088 -164.358574) (xy 39.982749 -164.359074) (xy 40.053623 -164.36706)
			(xy 40.123158 -164.38293) (xy 40.190478 -164.406487) (xy 40.254737 -164.437432) (xy 40.315128 -164.475378)
			(xy 40.37089 -164.519847) (xy 40.421323 -164.57028) (xy 40.465792 -164.626042) (xy 40.503738 -164.686433)
			(xy 40.534683 -164.750692) (xy 40.55824 -164.818012) (xy 40.57411 -164.887547) (xy 40.582096 -164.958421)
			(xy 40.582096 -165.029743) (xy 40.57411 -165.100617) (xy 40.55824 -165.170152) (xy 40.534683 -165.237472)
			(xy 40.503738 -165.301731) (xy 40.465792 -165.362122) (xy 40.421323 -165.417884) (xy 40.37089 -165.468317)
			(xy 40.315128 -165.512786) (xy 40.254737 -165.550732) (xy 40.190478 -165.581677) (xy 40.123158 -165.605234)
			(xy 40.053623 -165.621104) (xy 39.982749 -165.62909) (xy 39.911427 -165.62909) (xy 39.840553 -165.621104)
			(xy 39.771018 -165.605234) (xy 39.703698 -165.581677) (xy 39.639439 -165.550732) (xy 39.579048 -165.512786)
			(xy 39.523286 -165.468317) (xy 39.472853 -165.417884) (xy 39.428384 -165.362122) (xy 39.390438 -165.301731)
			(xy 39.359493 -165.237472) (xy 39.335936 -165.170152) (xy 39.320066 -165.100617) (xy 39.31208 -165.029743)
			(xy 35.733601 -165.029743) (xy 35.669659 -165.041696) (xy 35.58313 -165.049714) (xy 35.49623 -165.049714)
			(xy 35.409701 -165.041696) (xy 35.324281 -165.025728) (xy 35.240699 -165.001947) (xy 35.159667 -164.970555)
			(xy 35.081878 -164.931821) (xy 35.007994 -164.886074) (xy 34.938647 -164.833705) (xy 34.874427 -164.775161)
			(xy 34.815883 -164.710941) (xy 34.763514 -164.641594) (xy 34.717767 -164.56771) (xy 34.679033 -164.489921)
			(xy 34.647641 -164.408889) (xy 34.62386 -164.325307) (xy 34.607892 -164.239887) (xy 34.599874 -164.153358)
			(xy 31.399486 -164.153358) (xy 31.391468 -164.239887) (xy 31.3755 -164.325307) (xy 31.351719 -164.408889)
			(xy 31.320327 -164.489921) (xy 31.281593 -164.56771) (xy 31.235846 -164.641594) (xy 31.183477 -164.710941)
			(xy 31.124933 -164.775161) (xy 31.060713 -164.833705) (xy 30.991366 -164.886074) (xy 30.917482 -164.931821)
			(xy 30.839693 -164.970555) (xy 30.758661 -165.001947) (xy 30.675079 -165.025728) (xy 30.589659 -165.041696)
			(xy 30.50313 -165.049714) (xy 30.41623 -165.049714) (xy 30.329701 -165.041696) (xy 30.244281 -165.025728)
			(xy 30.160699 -165.001947) (xy 30.079667 -164.970555) (xy 30.001878 -164.931821) (xy 29.927994 -164.886074)
			(xy 29.858647 -164.833705) (xy 29.794427 -164.775161) (xy 29.735883 -164.710941) (xy 29.683514 -164.641594)
			(xy 29.637767 -164.56771) (xy 29.599033 -164.489921) (xy 29.567641 -164.408889) (xy 29.54386 -164.325307)
			(xy 29.527892 -164.239887) (xy 29.519874 -164.153358) (xy 28.804108 -164.153358) (xy 28.804108 -166.693358)
			(xy 29.519874 -166.693358) (xy 29.519874 -166.606458) (xy 29.527892 -166.519929) (xy 29.54386 -166.434509)
			(xy 29.567641 -166.350927) (xy 29.599033 -166.269895) (xy 29.637767 -166.192106) (xy 29.683514 -166.118222)
			(xy 29.735883 -166.048875) (xy 29.794427 -165.984655) (xy 29.858647 -165.926111) (xy 29.927994 -165.873742)
			(xy 30.001878 -165.827995) (xy 30.079667 -165.789261) (xy 30.160699 -165.757869) (xy 30.244281 -165.734088)
			(xy 30.329701 -165.71812) (xy 30.41623 -165.710102) (xy 30.45968 -165.7096) (xy 30.50313 -165.710102)
			(xy 30.589659 -165.71812) (xy 30.675079 -165.734088) (xy 30.758661 -165.757869) (xy 30.839693 -165.789261)
			(xy 30.917482 -165.827995) (xy 30.991366 -165.873742) (xy 31.060713 -165.926111) (xy 31.124933 -165.984655)
			(xy 31.183477 -166.048875) (xy 31.235846 -166.118222) (xy 31.281593 -166.192106) (xy 31.320327 -166.269895)
			(xy 31.351719 -166.350927) (xy 31.3755 -166.434509) (xy 31.391468 -166.519929) (xy 31.399486 -166.606458)
			(xy 31.399486 -166.693358) (xy 34.599874 -166.693358) (xy 34.599874 -166.606458) (xy 34.607892 -166.519929)
			(xy 34.62386 -166.434509) (xy 34.647641 -166.350927) (xy 34.679033 -166.269895) (xy 34.717767 -166.192106)
			(xy 34.763514 -166.118222) (xy 34.815883 -166.048875) (xy 34.874427 -165.984655) (xy 34.938647 -165.926111)
			(xy 35.007994 -165.873742) (xy 35.081878 -165.827995) (xy 35.159667 -165.789261) (xy 35.240699 -165.757869)
			(xy 35.324281 -165.734088) (xy 35.409701 -165.71812) (xy 35.49623 -165.710102) (xy 35.53968 -165.7096)
			(xy 35.58313 -165.710102) (xy 35.669659 -165.71812) (xy 35.755079 -165.734088) (xy 35.838661 -165.757869)
			(xy 35.843488 -165.759739) (xy 76.618076 -165.759739) (xy 76.618076 -165.688417) (xy 76.626062 -165.617543)
			(xy 76.641932 -165.548008) (xy 76.665489 -165.480688) (xy 76.696434 -165.416429) (xy 76.73438 -165.356038)
			(xy 76.778849 -165.300276) (xy 76.829282 -165.249843) (xy 76.885044 -165.205374) (xy 76.945435 -165.167428)
			(xy 77.009694 -165.136483) (xy 77.077014 -165.112926) (xy 77.146549 -165.097056) (xy 77.217423 -165.08907)
			(xy 77.253084 -165.08857) (xy 77.288745 -165.08907) (xy 77.359619 -165.097056) (xy 77.429154 -165.112926)
			(xy 77.496474 -165.136483) (xy 77.560733 -165.167428) (xy 77.621124 -165.205374) (xy 77.676886 -165.249843)
			(xy 77.727319 -165.300276) (xy 77.771788 -165.356038) (xy 77.809734 -165.416429) (xy 77.840679 -165.480688)
			(xy 77.864236 -165.548008) (xy 77.880106 -165.617543) (xy 77.888092 -165.688417) (xy 77.888092 -165.759739)
			(xy 79.42249 -165.759739) (xy 79.42249 -165.688417) (xy 79.430476 -165.617543) (xy 79.446346 -165.548008)
			(xy 79.469903 -165.480688) (xy 79.500848 -165.416429) (xy 79.538794 -165.356038) (xy 79.583263 -165.300276)
			(xy 79.633696 -165.249843) (xy 79.689458 -165.205374) (xy 79.749849 -165.167428) (xy 79.814108 -165.136483)
			(xy 79.881428 -165.112926) (xy 79.950963 -165.097056) (xy 80.021837 -165.08907) (xy 80.057498 -165.08857)
			(xy 80.093159 -165.08907) (xy 80.164033 -165.097056) (xy 80.233568 -165.112926) (xy 80.300888 -165.136483)
			(xy 80.365147 -165.167428) (xy 80.425538 -165.205374) (xy 80.4813 -165.249843) (xy 80.531733 -165.300276)
			(xy 80.576202 -165.356038) (xy 80.614148 -165.416429) (xy 80.645093 -165.480688) (xy 80.66865 -165.548008)
			(xy 80.68452 -165.617543) (xy 80.692506 -165.688417) (xy 80.692506 -165.759739) (xy 80.68452 -165.830613)
			(xy 80.66865 -165.900148) (xy 80.645093 -165.967468) (xy 80.614148 -166.031727) (xy 80.576202 -166.092118)
			(xy 80.531733 -166.14788) (xy 80.4813 -166.198313) (xy 80.425538 -166.242782) (xy 80.365147 -166.280728)
			(xy 80.300888 -166.311673) (xy 80.233568 -166.33523) (xy 80.164033 -166.3511) (xy 80.093159 -166.359086)
			(xy 80.021837 -166.359086) (xy 79.950963 -166.3511) (xy 79.881428 -166.33523) (xy 79.814108 -166.311673)
			(xy 79.749849 -166.280728) (xy 79.689458 -166.242782) (xy 79.633696 -166.198313) (xy 79.583263 -166.14788)
			(xy 79.538794 -166.092118) (xy 79.500848 -166.031727) (xy 79.469903 -165.967468) (xy 79.446346 -165.900148)
			(xy 79.430476 -165.830613) (xy 79.42249 -165.759739) (xy 77.888092 -165.759739) (xy 77.880106 -165.830613)
			(xy 77.864236 -165.900148) (xy 77.840679 -165.967468) (xy 77.809734 -166.031727) (xy 77.771788 -166.092118)
			(xy 77.727319 -166.14788) (xy 77.676886 -166.198313) (xy 77.621124 -166.242782) (xy 77.560733 -166.280728)
			(xy 77.496474 -166.311673) (xy 77.429154 -166.33523) (xy 77.359619 -166.3511) (xy 77.288745 -166.359086)
			(xy 77.217423 -166.359086) (xy 77.146549 -166.3511) (xy 77.077014 -166.33523) (xy 77.009694 -166.311673)
			(xy 76.945435 -166.280728) (xy 76.885044 -166.242782) (xy 76.829282 -166.198313) (xy 76.778849 -166.14788)
			(xy 76.73438 -166.092118) (xy 76.696434 -166.031727) (xy 76.665489 -165.967468) (xy 76.641932 -165.900148)
			(xy 76.626062 -165.830613) (xy 76.618076 -165.759739) (xy 35.843488 -165.759739) (xy 35.919693 -165.789261)
			(xy 35.997482 -165.827995) (xy 36.071366 -165.873742) (xy 36.140713 -165.926111) (xy 36.204933 -165.984655)
			(xy 36.263477 -166.048875) (xy 36.315846 -166.118222) (xy 36.361593 -166.192106) (xy 36.400327 -166.269895)
			(xy 36.431719 -166.350927) (xy 36.4555 -166.434509) (xy 36.471468 -166.519929) (xy 36.479486 -166.606458)
			(xy 36.479486 -166.693358) (xy 36.471468 -166.779887) (xy 36.4555 -166.865307) (xy 36.431719 -166.948889)
			(xy 36.400327 -167.029921) (xy 36.361593 -167.10771) (xy 36.315846 -167.181594) (xy 36.263477 -167.250941)
			(xy 36.204933 -167.315161) (xy 36.140713 -167.373705) (xy 36.071366 -167.426074) (xy 35.997482 -167.471821)
			(xy 35.919693 -167.510555) (xy 35.838661 -167.541947) (xy 35.755079 -167.565728) (xy 35.669659 -167.581696)
			(xy 35.58313 -167.589714) (xy 35.49623 -167.589714) (xy 35.409701 -167.581696) (xy 35.324281 -167.565728)
			(xy 35.240699 -167.541947) (xy 35.159667 -167.510555) (xy 35.081878 -167.471821) (xy 35.007994 -167.426074)
			(xy 34.938647 -167.373705) (xy 34.874427 -167.315161) (xy 34.815883 -167.250941) (xy 34.763514 -167.181594)
			(xy 34.717767 -167.10771) (xy 34.679033 -167.029921) (xy 34.647641 -166.948889) (xy 34.62386 -166.865307)
			(xy 34.607892 -166.779887) (xy 34.599874 -166.693358) (xy 31.399486 -166.693358) (xy 31.391468 -166.779887)
			(xy 31.3755 -166.865307) (xy 31.351719 -166.948889) (xy 31.320327 -167.029921) (xy 31.281593 -167.10771)
			(xy 31.235846 -167.181594) (xy 31.183477 -167.250941) (xy 31.124933 -167.315161) (xy 31.060713 -167.373705)
			(xy 30.991366 -167.426074) (xy 30.917482 -167.471821) (xy 30.839693 -167.510555) (xy 30.758661 -167.541947)
			(xy 30.675079 -167.565728) (xy 30.589659 -167.581696) (xy 30.50313 -167.589714) (xy 30.41623 -167.589714)
			(xy 30.329701 -167.581696) (xy 30.244281 -167.565728) (xy 30.160699 -167.541947) (xy 30.079667 -167.510555)
			(xy 30.001878 -167.471821) (xy 29.927994 -167.426074) (xy 29.858647 -167.373705) (xy 29.794427 -167.315161)
			(xy 29.735883 -167.250941) (xy 29.683514 -167.181594) (xy 29.637767 -167.10771) (xy 29.599033 -167.029921)
			(xy 29.567641 -166.948889) (xy 29.54386 -166.865307) (xy 29.527892 -166.779887) (xy 29.519874 -166.693358)
			(xy 28.804108 -166.693358) (xy 28.804108 -167.995193) (xy 76.618076 -167.995193) (xy 76.618076 -167.923871)
			(xy 76.626062 -167.852997) (xy 76.641932 -167.783462) (xy 76.665489 -167.716142) (xy 76.696434 -167.651883)
			(xy 76.73438 -167.591492) (xy 76.778849 -167.53573) (xy 76.829282 -167.485297) (xy 76.885044 -167.440828)
			(xy 76.945435 -167.402882) (xy 77.009694 -167.371937) (xy 77.077014 -167.34838) (xy 77.146549 -167.33251)
			(xy 77.217423 -167.324524) (xy 77.253084 -167.324024) (xy 77.288745 -167.324524) (xy 77.359619 -167.33251)
			(xy 77.429154 -167.34838) (xy 77.496474 -167.371937) (xy 77.560733 -167.402882) (xy 77.621124 -167.440828)
			(xy 77.676886 -167.485297) (xy 77.727319 -167.53573) (xy 77.771788 -167.591492) (xy 77.809734 -167.651883)
			(xy 77.840679 -167.716142) (xy 77.864236 -167.783462) (xy 77.880106 -167.852997) (xy 77.888092 -167.923871)
			(xy 77.888092 -167.995193) (xy 79.42249 -167.995193) (xy 79.42249 -167.923871) (xy 79.430476 -167.852997)
			(xy 79.446346 -167.783462) (xy 79.469903 -167.716142) (xy 79.500848 -167.651883) (xy 79.538794 -167.591492)
			(xy 79.583263 -167.53573) (xy 79.633696 -167.485297) (xy 79.689458 -167.440828) (xy 79.749849 -167.402882)
			(xy 79.814108 -167.371937) (xy 79.881428 -167.34838) (xy 79.950963 -167.33251) (xy 80.021837 -167.324524)
			(xy 80.057498 -167.324024) (xy 80.093159 -167.324524) (xy 80.164033 -167.33251) (xy 80.233568 -167.34838)
			(xy 80.300888 -167.371937) (xy 80.365147 -167.402882) (xy 80.425538 -167.440828) (xy 80.4813 -167.485297)
			(xy 80.531733 -167.53573) (xy 80.576202 -167.591492) (xy 80.614148 -167.651883) (xy 80.645093 -167.716142)
			(xy 80.66865 -167.783462) (xy 80.68452 -167.852997) (xy 80.692506 -167.923871) (xy 80.692506 -167.995193)
			(xy 80.68452 -168.066067) (xy 80.66865 -168.135602) (xy 80.645093 -168.202922) (xy 80.614148 -168.267181)
			(xy 80.576202 -168.327572) (xy 80.531733 -168.383334) (xy 80.4813 -168.433767) (xy 80.425538 -168.478236)
			(xy 80.365147 -168.516182) (xy 80.300888 -168.547127) (xy 80.233568 -168.570684) (xy 80.164033 -168.586554)
			(xy 80.093159 -168.59454) (xy 80.021837 -168.59454) (xy 79.950963 -168.586554) (xy 79.881428 -168.570684)
			(xy 79.814108 -168.547127) (xy 79.749849 -168.516182) (xy 79.689458 -168.478236) (xy 79.633696 -168.433767)
			(xy 79.583263 -168.383334) (xy 79.538794 -168.327572) (xy 79.500848 -168.267181) (xy 79.469903 -168.202922)
			(xy 79.446346 -168.135602) (xy 79.430476 -168.066067) (xy 79.42249 -167.995193) (xy 77.888092 -167.995193)
			(xy 77.880106 -168.066067) (xy 77.864236 -168.135602) (xy 77.840679 -168.202922) (xy 77.809734 -168.267181)
			(xy 77.771788 -168.327572) (xy 77.727319 -168.383334) (xy 77.676886 -168.433767) (xy 77.621124 -168.478236)
			(xy 77.560733 -168.516182) (xy 77.496474 -168.547127) (xy 77.429154 -168.570684) (xy 77.359619 -168.586554)
			(xy 77.288745 -168.59454) (xy 77.217423 -168.59454) (xy 77.146549 -168.586554) (xy 77.077014 -168.570684)
			(xy 77.009694 -168.547127) (xy 76.945435 -168.516182) (xy 76.885044 -168.478236) (xy 76.829282 -168.433767)
			(xy 76.778849 -168.383334) (xy 76.73438 -168.327572) (xy 76.696434 -168.267181) (xy 76.665489 -168.202922)
			(xy 76.641932 -168.135602) (xy 76.626062 -168.066067) (xy 76.618076 -167.995193) (xy 28.804108 -167.995193)
			(xy 28.804108 -169.233358) (xy 29.519874 -169.233358) (xy 29.519874 -169.146458) (xy 29.527892 -169.059929)
			(xy 29.54386 -168.974509) (xy 29.567641 -168.890927) (xy 29.599033 -168.809895) (xy 29.637767 -168.732106)
			(xy 29.683514 -168.658222) (xy 29.735883 -168.588875) (xy 29.794427 -168.524655) (xy 29.858647 -168.466111)
			(xy 29.927994 -168.413742) (xy 30.001878 -168.367995) (xy 30.079667 -168.329261) (xy 30.160699 -168.297869)
			(xy 30.244281 -168.274088) (xy 30.329701 -168.25812) (xy 30.41623 -168.250102) (xy 30.45968 -168.2496)
			(xy 30.50313 -168.250102) (xy 30.589659 -168.25812) (xy 30.675079 -168.274088) (xy 30.758661 -168.297869)
			(xy 30.839693 -168.329261) (xy 30.917482 -168.367995) (xy 30.991366 -168.413742) (xy 31.060713 -168.466111)
			(xy 31.124933 -168.524655) (xy 31.183477 -168.588875) (xy 31.235846 -168.658222) (xy 31.281593 -168.732106)
			(xy 31.320327 -168.809895) (xy 31.351719 -168.890927) (xy 31.3755 -168.974509) (xy 31.391468 -169.059929)
			(xy 31.399486 -169.146458) (xy 31.399486 -169.233358) (xy 34.599874 -169.233358) (xy 34.599874 -169.146458)
			(xy 34.607892 -169.059929) (xy 34.62386 -168.974509) (xy 34.647641 -168.890927) (xy 34.679033 -168.809895)
			(xy 34.717767 -168.732106) (xy 34.763514 -168.658222) (xy 34.815883 -168.588875) (xy 34.874427 -168.524655)
			(xy 34.938647 -168.466111) (xy 35.007994 -168.413742) (xy 35.081878 -168.367995) (xy 35.159667 -168.329261)
			(xy 35.240699 -168.297869) (xy 35.324281 -168.274088) (xy 35.409701 -168.25812) (xy 35.49623 -168.250102)
			(xy 35.53968 -168.2496) (xy 35.58313 -168.250102) (xy 35.669659 -168.25812) (xy 35.755079 -168.274088)
			(xy 35.838661 -168.297869) (xy 35.919693 -168.329261) (xy 35.997482 -168.367995) (xy 36.071366 -168.413742)
			(xy 36.140713 -168.466111) (xy 36.204933 -168.524655) (xy 36.263477 -168.588875) (xy 36.315846 -168.658222)
			(xy 36.361593 -168.732106) (xy 36.400327 -168.809895) (xy 36.431719 -168.890927) (xy 36.4555 -168.974509)
			(xy 36.471468 -169.059929) (xy 36.479486 -169.146458) (xy 36.479486 -169.233358) (xy 36.471468 -169.319887)
			(xy 36.4555 -169.405307) (xy 36.431719 -169.488889) (xy 36.400327 -169.569921) (xy 36.361593 -169.64771)
			(xy 36.315846 -169.721594) (xy 36.263477 -169.790941) (xy 36.204933 -169.855161) (xy 36.140713 -169.913705)
			(xy 36.071366 -169.966074) (xy 35.997482 -170.011821) (xy 35.919693 -170.050555) (xy 35.838661 -170.081947)
			(xy 35.755079 -170.105728) (xy 35.669659 -170.121696) (xy 35.58313 -170.129714) (xy 35.49623 -170.129714)
			(xy 35.409701 -170.121696) (xy 35.324281 -170.105728) (xy 35.240699 -170.081947) (xy 35.159667 -170.050555)
			(xy 35.081878 -170.011821) (xy 35.007994 -169.966074) (xy 34.938647 -169.913705) (xy 34.874427 -169.855161)
			(xy 34.815883 -169.790941) (xy 34.763514 -169.721594) (xy 34.717767 -169.64771) (xy 34.679033 -169.569921)
			(xy 34.647641 -169.488889) (xy 34.62386 -169.405307) (xy 34.607892 -169.319887) (xy 34.599874 -169.233358)
			(xy 31.399486 -169.233358) (xy 31.391468 -169.319887) (xy 31.3755 -169.405307) (xy 31.351719 -169.488889)
			(xy 31.320327 -169.569921) (xy 31.281593 -169.64771) (xy 31.235846 -169.721594) (xy 31.183477 -169.790941)
			(xy 31.124933 -169.855161) (xy 31.060713 -169.913705) (xy 30.991366 -169.966074) (xy 30.917482 -170.011821)
			(xy 30.839693 -170.050555) (xy 30.758661 -170.081947) (xy 30.675079 -170.105728) (xy 30.589659 -170.121696)
			(xy 30.50313 -170.129714) (xy 30.41623 -170.129714) (xy 30.329701 -170.121696) (xy 30.244281 -170.105728)
			(xy 30.160699 -170.081947) (xy 30.079667 -170.050555) (xy 30.001878 -170.011821) (xy 29.927994 -169.966074)
			(xy 29.858647 -169.913705) (xy 29.794427 -169.855161) (xy 29.735883 -169.790941) (xy 29.683514 -169.721594)
			(xy 29.637767 -169.64771) (xy 29.599033 -169.569921) (xy 29.567641 -169.488889) (xy 29.54386 -169.405307)
			(xy 29.527892 -169.319887) (xy 29.519874 -169.233358) (xy 28.804108 -169.233358) (xy 28.804108 -170.663463)
			(xy 76.618076 -170.663463) (xy 76.618076 -170.592141) (xy 76.626062 -170.521267) (xy 76.641932 -170.451732)
			(xy 76.665489 -170.384412) (xy 76.696434 -170.320153) (xy 76.73438 -170.259762) (xy 76.778849 -170.204)
			(xy 76.829282 -170.153567) (xy 76.885044 -170.109098) (xy 76.945435 -170.071152) (xy 77.009694 -170.040207)
			(xy 77.077014 -170.01665) (xy 77.146549 -170.00078) (xy 77.217423 -169.992794) (xy 77.253084 -169.992294)
			(xy 77.288745 -169.992794) (xy 77.359619 -170.00078) (xy 77.429154 -170.01665) (xy 77.496474 -170.040207)
			(xy 77.560733 -170.071152) (xy 77.621124 -170.109098) (xy 77.676886 -170.153567) (xy 77.727319 -170.204)
			(xy 77.771788 -170.259762) (xy 77.809734 -170.320153) (xy 77.840679 -170.384412) (xy 77.864236 -170.451732)
			(xy 77.880106 -170.521267) (xy 77.888092 -170.592141) (xy 77.888092 -170.663463) (xy 79.42249 -170.663463)
			(xy 79.42249 -170.592141) (xy 79.430476 -170.521267) (xy 79.446346 -170.451732) (xy 79.469903 -170.384412)
			(xy 79.500848 -170.320153) (xy 79.538794 -170.259762) (xy 79.583263 -170.204) (xy 79.633696 -170.153567)
			(xy 79.689458 -170.109098) (xy 79.749849 -170.071152) (xy 79.814108 -170.040207) (xy 79.881428 -170.01665)
			(xy 79.950963 -170.00078) (xy 80.021837 -169.992794) (xy 80.057498 -169.992294) (xy 80.093159 -169.992794)
			(xy 80.164033 -170.00078) (xy 80.233568 -170.01665) (xy 80.300888 -170.040207) (xy 80.365147 -170.071152)
			(xy 80.425538 -170.109098) (xy 80.4813 -170.153567) (xy 80.531733 -170.204) (xy 80.576202 -170.259762)
			(xy 80.614148 -170.320153) (xy 80.645093 -170.384412) (xy 80.66865 -170.451732) (xy 80.68452 -170.521267)
			(xy 80.692506 -170.592141) (xy 80.692506 -170.663463) (xy 80.68452 -170.734337) (xy 80.66865 -170.803872)
			(xy 80.645093 -170.871192) (xy 80.614148 -170.935451) (xy 80.576202 -170.995842) (xy 80.531733 -171.051604)
			(xy 80.4813 -171.102037) (xy 80.425538 -171.146506) (xy 80.365147 -171.184452) (xy 80.300888 -171.215397)
			(xy 80.233568 -171.238954) (xy 80.164033 -171.254824) (xy 80.093159 -171.26281) (xy 80.021837 -171.26281)
			(xy 79.950963 -171.254824) (xy 79.881428 -171.238954) (xy 79.814108 -171.215397) (xy 79.749849 -171.184452)
			(xy 79.689458 -171.146506) (xy 79.633696 -171.102037) (xy 79.583263 -171.051604) (xy 79.538794 -170.995842)
			(xy 79.500848 -170.935451) (xy 79.469903 -170.871192) (xy 79.446346 -170.803872) (xy 79.430476 -170.734337)
			(xy 79.42249 -170.663463) (xy 77.888092 -170.663463) (xy 77.880106 -170.734337) (xy 77.864236 -170.803872)
			(xy 77.840679 -170.871192) (xy 77.809734 -170.935451) (xy 77.771788 -170.995842) (xy 77.727319 -171.051604)
			(xy 77.676886 -171.102037) (xy 77.621124 -171.146506) (xy 77.560733 -171.184452) (xy 77.496474 -171.215397)
			(xy 77.429154 -171.238954) (xy 77.359619 -171.254824) (xy 77.288745 -171.26281) (xy 77.217423 -171.26281)
			(xy 77.146549 -171.254824) (xy 77.077014 -171.238954) (xy 77.009694 -171.215397) (xy 76.945435 -171.184452)
			(xy 76.885044 -171.146506) (xy 76.829282 -171.102037) (xy 76.778849 -171.051604) (xy 76.73438 -170.995842)
			(xy 76.696434 -170.935451) (xy 76.665489 -170.871192) (xy 76.641932 -170.803872) (xy 76.626062 -170.734337)
			(xy 76.618076 -170.663463) (xy 28.804108 -170.663463) (xy 28.804108 -171.577762) (xy 29.085794 -171.859448)
			(xy 29.102438 -171.87538) (xy 29.140355 -171.901548) (xy 29.182367 -171.920453) (xy 29.227098 -171.931477)
			(xy 29.273084 -171.934259) (xy 29.318818 -171.928707) (xy 29.362803 -171.915004) (xy 29.403598 -171.893598)
			(xy 29.439867 -171.865191) (xy 29.470422 -171.830712) (xy 29.494263 -171.79129) (xy 29.510609 -171.748218)
			(xy 29.518924 -171.702905) (xy 29.519372 -171.67987) (xy 29.519372 -170.7896) (xy 31.399988 -170.7896)
			(xy 31.399988 -171.773358) (xy 34.599874 -171.773358) (xy 34.599874 -171.686458) (xy 34.607892 -171.599929)
			(xy 34.62386 -171.514509) (xy 34.647641 -171.430927) (xy 34.679033 -171.349895) (xy 34.717767 -171.272106)
			(xy 34.763514 -171.198222) (xy 34.815883 -171.128875) (xy 34.874427 -171.064655) (xy 34.938647 -171.006111)
			(xy 35.007994 -170.953742) (xy 35.081878 -170.907995) (xy 35.159667 -170.869261) (xy 35.240699 -170.837869)
			(xy 35.324281 -170.814088) (xy 35.409701 -170.79812) (xy 35.49623 -170.790102) (xy 35.53968 -170.7896)
			(xy 35.58313 -170.790102) (xy 35.669659 -170.79812) (xy 35.755079 -170.814088) (xy 35.838661 -170.837869)
			(xy 35.919693 -170.869261) (xy 35.997482 -170.907995) (xy 36.071366 -170.953742) (xy 36.140713 -171.006111)
			(xy 36.204933 -171.064655) (xy 36.263477 -171.128875) (xy 36.315846 -171.198222) (xy 36.361593 -171.272106)
			(xy 36.400327 -171.349895) (xy 36.431719 -171.430927) (xy 36.4555 -171.514509) (xy 36.471468 -171.599929)
			(xy 36.479486 -171.686458) (xy 36.479486 -171.773358) (xy 36.471468 -171.859887) (xy 36.4555 -171.945307)
			(xy 36.431719 -172.028889) (xy 36.400327 -172.109921) (xy 36.361593 -172.18771) (xy 36.315846 -172.261594)
			(xy 36.277723 -172.312076) (xy 51.141376 -172.312076) (xy 52.793392 -172.312076) (xy 52.793392 -173.035061)
			(xy 76.618076 -173.035061) (xy 76.618076 -172.963739) (xy 76.626062 -172.892865) (xy 76.641932 -172.82333)
			(xy 76.665489 -172.75601) (xy 76.696434 -172.691751) (xy 76.73438 -172.63136) (xy 76.778849 -172.575598)
			(xy 76.829282 -172.525165) (xy 76.885044 -172.480696) (xy 76.945435 -172.44275) (xy 77.009694 -172.411805)
			(xy 77.077014 -172.388248) (xy 77.146549 -172.372378) (xy 77.217423 -172.364392) (xy 77.253084 -172.363892)
			(xy 77.288745 -172.364392) (xy 77.359619 -172.372378) (xy 77.429154 -172.388248) (xy 77.496474 -172.411805)
			(xy 77.560733 -172.44275) (xy 77.621124 -172.480696) (xy 77.676886 -172.525165) (xy 77.727319 -172.575598)
			(xy 77.771788 -172.63136) (xy 77.809734 -172.691751) (xy 77.840679 -172.75601) (xy 77.864236 -172.82333)
			(xy 77.880106 -172.892865) (xy 77.888092 -172.963739) (xy 77.888092 -173.035061) (xy 79.42249 -173.035061)
			(xy 79.42249 -172.963739) (xy 79.430476 -172.892865) (xy 79.446346 -172.82333) (xy 79.469903 -172.75601)
			(xy 79.500848 -172.691751) (xy 79.538794 -172.63136) (xy 79.583263 -172.575598) (xy 79.633696 -172.525165)
			(xy 79.689458 -172.480696) (xy 79.749849 -172.44275) (xy 79.814108 -172.411805) (xy 79.881428 -172.388248)
			(xy 79.950963 -172.372378) (xy 80.021837 -172.364392) (xy 80.057498 -172.363892) (xy 80.093159 -172.364392)
			(xy 80.164033 -172.372378) (xy 80.233568 -172.388248) (xy 80.300888 -172.411805) (xy 80.365147 -172.44275)
			(xy 80.425538 -172.480696) (xy 80.4813 -172.525165) (xy 80.531733 -172.575598) (xy 80.576202 -172.63136)
			(xy 80.614148 -172.691751) (xy 80.645093 -172.75601) (xy 80.66865 -172.82333) (xy 80.68452 -172.892865)
			(xy 80.692506 -172.963739) (xy 80.692506 -173.035061) (xy 80.68452 -173.105935) (xy 80.66865 -173.17547)
			(xy 80.645093 -173.24279) (xy 80.614148 -173.307049) (xy 80.576202 -173.36744) (xy 80.531733 -173.423202)
			(xy 80.4813 -173.473635) (xy 80.425538 -173.518104) (xy 80.365147 -173.55605) (xy 80.300888 -173.586995)
			(xy 80.233568 -173.610552) (xy 80.164033 -173.626422) (xy 80.093159 -173.634408) (xy 80.021837 -173.634408)
			(xy 79.950963 -173.626422) (xy 79.881428 -173.610552) (xy 79.814108 -173.586995) (xy 79.749849 -173.55605)
			(xy 79.689458 -173.518104) (xy 79.633696 -173.473635) (xy 79.583263 -173.423202) (xy 79.538794 -173.36744)
			(xy 79.500848 -173.307049) (xy 79.469903 -173.24279) (xy 79.446346 -173.17547) (xy 79.430476 -173.105935)
			(xy 79.42249 -173.035061) (xy 77.888092 -173.035061) (xy 77.880106 -173.105935) (xy 77.864236 -173.17547)
			(xy 77.840679 -173.24279) (xy 77.809734 -173.307049) (xy 77.771788 -173.36744) (xy 77.727319 -173.423202)
			(xy 77.676886 -173.473635) (xy 77.621124 -173.518104) (xy 77.560733 -173.55605) (xy 77.496474 -173.586995)
			(xy 77.429154 -173.610552) (xy 77.359619 -173.626422) (xy 77.288745 -173.634408) (xy 77.217423 -173.634408)
			(xy 77.146549 -173.626422) (xy 77.077014 -173.610552) (xy 77.009694 -173.586995) (xy 76.945435 -173.55605)
			(xy 76.885044 -173.518104) (xy 76.829282 -173.473635) (xy 76.778849 -173.423202) (xy 76.73438 -173.36744)
			(xy 76.696434 -173.307049) (xy 76.665489 -173.24279) (xy 76.641932 -173.17547) (xy 76.626062 -173.105935)
			(xy 76.618076 -173.035061) (xy 52.793392 -173.035061) (xy 52.793392 -173.963584) (xy 51.141376 -173.963584)
			(xy 51.141376 -172.312076) (xy 36.277723 -172.312076) (xy 36.263477 -172.330941) (xy 36.204933 -172.395161)
			(xy 36.140713 -172.453705) (xy 36.071366 -172.506074) (xy 35.997482 -172.551821) (xy 35.919693 -172.590555)
			(xy 35.838661 -172.621947) (xy 35.755079 -172.645728) (xy 35.669659 -172.661696) (xy 35.58313 -172.669714)
			(xy 35.49623 -172.669714) (xy 35.409701 -172.661696) (xy 35.324281 -172.645728) (xy 35.240699 -172.621947)
			(xy 35.159667 -172.590555) (xy 35.081878 -172.551821) (xy 35.007994 -172.506074) (xy 34.938647 -172.453705)
			(xy 34.874427 -172.395161) (xy 34.815883 -172.330941) (xy 34.763514 -172.261594) (xy 34.717767 -172.18771)
			(xy 34.679033 -172.109921) (xy 34.647641 -172.028889) (xy 34.62386 -171.945307) (xy 34.607892 -171.859887)
			(xy 34.599874 -171.773358) (xy 31.399988 -171.773358) (xy 31.399988 -172.670216) (xy 30.509718 -172.670216)
			(xy 30.486682 -172.670715) (xy 30.441364 -172.679017) (xy 30.398285 -172.695353) (xy 30.358856 -172.719186)
			(xy 30.32437 -172.749737) (xy 30.295956 -172.786004) (xy 30.274546 -172.826799) (xy 30.26084 -172.870786)
			(xy 30.255288 -172.916522) (xy 30.258072 -172.96251) (xy 30.2691 -173.007243) (xy 30.288011 -173.049255)
			(xy 30.314187 -173.087169) (xy 30.33014 -173.103794) (xy 32.224451 -174.997973) (xy 76.618076 -174.997973)
			(xy 76.618076 -174.926651) (xy 76.626062 -174.855777) (xy 76.641932 -174.786242) (xy 76.665489 -174.718922)
			(xy 76.696434 -174.654663) (xy 76.73438 -174.594272) (xy 76.778849 -174.53851) (xy 76.829282 -174.488077)
			(xy 76.885044 -174.443608) (xy 76.945435 -174.405662) (xy 77.009694 -174.374717) (xy 77.077014 -174.35116)
			(xy 77.146549 -174.33529) (xy 77.217423 -174.327304) (xy 77.253084 -174.326804) (xy 77.288745 -174.327304)
			(xy 77.359619 -174.33529) (xy 77.429154 -174.35116) (xy 77.496474 -174.374717) (xy 77.560733 -174.405662)
			(xy 77.621124 -174.443608) (xy 77.676886 -174.488077) (xy 77.727319 -174.53851) (xy 77.771788 -174.594272)
			(xy 77.809734 -174.654663) (xy 77.840679 -174.718922) (xy 77.864236 -174.786242) (xy 77.880106 -174.855777)
			(xy 77.888092 -174.926651) (xy 77.888092 -174.997973) (xy 79.42249 -174.997973) (xy 79.42249 -174.926651)
			(xy 79.430476 -174.855777) (xy 79.446346 -174.786242) (xy 79.469903 -174.718922) (xy 79.500848 -174.654663)
			(xy 79.538794 -174.594272) (xy 79.583263 -174.53851) (xy 79.633696 -174.488077) (xy 79.689458 -174.443608)
			(xy 79.749849 -174.405662) (xy 79.814108 -174.374717) (xy 79.881428 -174.35116) (xy 79.950963 -174.33529)
			(xy 80.021837 -174.327304) (xy 80.057498 -174.326804) (xy 80.093159 -174.327304) (xy 80.164033 -174.33529)
			(xy 80.233568 -174.35116) (xy 80.300888 -174.374717) (xy 80.365147 -174.405662) (xy 80.425538 -174.443608)
			(xy 80.4813 -174.488077) (xy 80.531733 -174.53851) (xy 80.576202 -174.594272) (xy 80.614148 -174.654663)
			(xy 80.645093 -174.718922) (xy 80.66865 -174.786242) (xy 80.68452 -174.855777) (xy 80.692506 -174.926651)
			(xy 80.692506 -174.997973) (xy 80.68452 -175.068847) (xy 80.66865 -175.138382) (xy 80.645093 -175.205702)
			(xy 80.614148 -175.269961) (xy 80.576202 -175.330352) (xy 80.531733 -175.386114) (xy 80.4813 -175.436547)
			(xy 80.425538 -175.481016) (xy 80.365147 -175.518962) (xy 80.300888 -175.549907) (xy 80.233568 -175.573464)
			(xy 80.164033 -175.589334) (xy 80.093159 -175.59732) (xy 80.021837 -175.59732) (xy 79.950963 -175.589334)
			(xy 79.881428 -175.573464) (xy 79.814108 -175.549907) (xy 79.749849 -175.518962) (xy 79.689458 -175.481016)
			(xy 79.633696 -175.436547) (xy 79.583263 -175.386114) (xy 79.538794 -175.330352) (xy 79.500848 -175.269961)
			(xy 79.469903 -175.205702) (xy 79.446346 -175.138382) (xy 79.430476 -175.068847) (xy 79.42249 -174.997973)
			(xy 77.888092 -174.997973) (xy 77.880106 -175.068847) (xy 77.864236 -175.138382) (xy 77.840679 -175.205702)
			(xy 77.809734 -175.269961) (xy 77.771788 -175.330352) (xy 77.727319 -175.386114) (xy 77.676886 -175.436547)
			(xy 77.621124 -175.481016) (xy 77.560733 -175.518962) (xy 77.496474 -175.549907) (xy 77.429154 -175.573464)
			(xy 77.359619 -175.589334) (xy 77.288745 -175.59732) (xy 77.217423 -175.59732) (xy 77.146549 -175.589334)
			(xy 77.077014 -175.573464) (xy 77.009694 -175.549907) (xy 76.945435 -175.518962) (xy 76.885044 -175.481016)
			(xy 76.829282 -175.436547) (xy 76.778849 -175.386114) (xy 76.73438 -175.330352) (xy 76.696434 -175.269961)
			(xy 76.665489 -175.205702) (xy 76.641932 -175.138382) (xy 76.626062 -175.068847) (xy 76.618076 -174.997973)
			(xy 32.224451 -174.997973) (xy 33.983676 -176.757076) (xy 37.375592 -176.757076) (xy 37.759995 -177.141479)
			(xy 76.618076 -177.141479) (xy 76.618076 -177.070157) (xy 76.626062 -176.999283) (xy 76.641932 -176.929748)
			(xy 76.665489 -176.862428) (xy 76.696434 -176.798169) (xy 76.73438 -176.737778) (xy 76.778849 -176.682016)
			(xy 76.829282 -176.631583) (xy 76.885044 -176.587114) (xy 76.945435 -176.549168) (xy 77.009694 -176.518223)
			(xy 77.077014 -176.494666) (xy 77.146549 -176.478796) (xy 77.217423 -176.47081) (xy 77.253084 -176.47031)
			(xy 77.288745 -176.47081) (xy 77.359619 -176.478796) (xy 77.429154 -176.494666) (xy 77.496474 -176.518223)
			(xy 77.560733 -176.549168) (xy 77.621124 -176.587114) (xy 77.676886 -176.631583) (xy 77.727319 -176.682016)
			(xy 77.771788 -176.737778) (xy 77.809734 -176.798169) (xy 77.840679 -176.862428) (xy 77.864236 -176.929748)
			(xy 77.880106 -176.999283) (xy 77.888092 -177.070157) (xy 77.888092 -177.141479) (xy 79.42249 -177.141479)
			(xy 79.42249 -177.070157) (xy 79.430476 -176.999283) (xy 79.446346 -176.929748) (xy 79.469903 -176.862428)
			(xy 79.500848 -176.798169) (xy 79.538794 -176.737778) (xy 79.583263 -176.682016) (xy 79.633696 -176.631583)
			(xy 79.689458 -176.587114) (xy 79.749849 -176.549168) (xy 79.814108 -176.518223) (xy 79.881428 -176.494666)
			(xy 79.950963 -176.478796) (xy 80.021837 -176.47081) (xy 80.057498 -176.47031) (xy 80.093159 -176.47081)
			(xy 80.164033 -176.478796) (xy 80.233568 -176.494666) (xy 80.300888 -176.518223) (xy 80.365147 -176.549168)
			(xy 80.425538 -176.587114) (xy 80.4813 -176.631583) (xy 80.531733 -176.682016) (xy 80.576202 -176.737778)
			(xy 80.614148 -176.798169) (xy 80.645093 -176.862428) (xy 80.66865 -176.929748) (xy 80.68452 -176.999283)
			(xy 80.692506 -177.070157) (xy 80.692506 -177.141479) (xy 80.68452 -177.212353) (xy 80.66865 -177.281888)
			(xy 80.645093 -177.349208) (xy 80.614148 -177.413467) (xy 80.576202 -177.473858) (xy 80.531733 -177.52962)
			(xy 80.4813 -177.580053) (xy 80.425538 -177.624522) (xy 80.365147 -177.662468) (xy 80.300888 -177.693413)
			(xy 80.233568 -177.71697) (xy 80.164033 -177.73284) (xy 80.093159 -177.740826) (xy 80.021837 -177.740826)
			(xy 79.950963 -177.73284) (xy 79.881428 -177.71697) (xy 79.814108 -177.693413) (xy 79.749849 -177.662468)
			(xy 79.689458 -177.624522) (xy 79.633696 -177.580053) (xy 79.583263 -177.52962) (xy 79.538794 -177.473858)
			(xy 79.500848 -177.413467) (xy 79.469903 -177.349208) (xy 79.446346 -177.281888) (xy 79.430476 -177.212353)
			(xy 79.42249 -177.141479) (xy 77.888092 -177.141479) (xy 77.880106 -177.212353) (xy 77.864236 -177.281888)
			(xy 77.840679 -177.349208) (xy 77.809734 -177.413467) (xy 77.771788 -177.473858) (xy 77.727319 -177.52962)
			(xy 77.676886 -177.580053) (xy 77.621124 -177.624522) (xy 77.560733 -177.662468) (xy 77.496474 -177.693413)
			(xy 77.429154 -177.71697) (xy 77.359619 -177.73284) (xy 77.288745 -177.740826) (xy 77.217423 -177.740826)
			(xy 77.146549 -177.73284) (xy 77.077014 -177.71697) (xy 77.009694 -177.693413) (xy 76.945435 -177.662468)
			(xy 76.885044 -177.624522) (xy 76.829282 -177.580053) (xy 76.778849 -177.52962) (xy 76.73438 -177.473858)
			(xy 76.696434 -177.413467) (xy 76.665489 -177.349208) (xy 76.641932 -177.281888) (xy 76.626062 -177.212353)
			(xy 76.618076 -177.141479) (xy 37.759995 -177.141479) (xy 40.056816 -179.4383) (xy 40.056816 -183.184038)
			(xy 40.057288 -183.205849) (xy 40.064779 -183.248823) (xy 40.079499 -183.289886) (xy 40.101016 -183.327832)
			(xy 40.128698 -183.361546) (xy 40.161732 -183.390036) (xy 40.199146 -183.412465) (xy 40.239841 -183.428175)
			(xy 40.282621 -183.436704) (xy 40.32623 -183.437801) (xy 40.369385 -183.431433) (xy 40.410818 -183.417789)
			(xy 40.449312 -183.397269) (xy 40.466772 -183.38419) (xy 40.512857 -183.348893) (xy 40.609132 -183.284014)
			(xy 40.709654 -183.225934) (xy 40.813944 -183.174929) (xy 40.921505 -183.131242) (xy 41.031824 -183.095081)
			(xy 41.144376 -183.066619) (xy 41.258624 -183.045992) (xy 41.374022 -183.033297) (xy 41.490022 -183.028596)
			(xy 41.606069 -183.03191) (xy 41.721611 -183.043225) (xy 41.836097 -183.062485) (xy 41.948981 -183.0896)
			(xy 42.059725 -183.124439) (xy 42.1678 -183.166838) (xy 42.272693 -183.216593) (xy 42.373902 -183.273468)
			(xy 42.470945 -183.337191) (xy 42.476087 -183.341101) (xy 63.648083 -183.341101) (xy 63.654132 -183.265531)
			(xy 63.668179 -183.191033) (xy 63.690065 -183.11845) (xy 63.719542 -183.048604) (xy 63.756277 -182.982287)
			(xy 63.799852 -182.920251) (xy 63.849774 -182.863198) (xy 63.905478 -182.811774) (xy 63.966333 -182.766563)
			(xy 64.031648 -182.728076) (xy 64.100684 -182.69675) (xy 64.172659 -182.67294) (xy 64.246757 -182.656915)
			(xy 64.322138 -182.648856) (xy 64.360044 -182.648352) (xy 64.39795 -182.648856) (xy 64.473331 -182.656915)
			(xy 64.547429 -182.67294) (xy 64.619404 -182.69675) (xy 64.68844 -182.728076) (xy 64.753755 -182.766563)
			(xy 64.81461 -182.811774) (xy 64.870314 -182.863198) (xy 64.920236 -182.920251) (xy 64.963811 -182.982287)
			(xy 65.000546 -183.048604) (xy 65.030023 -183.11845) (xy 65.051909 -183.191033) (xy 65.065956 -183.265531)
			(xy 65.072005 -183.341101) (xy 66.188083 -183.341101) (xy 66.194132 -183.265531) (xy 66.208179 -183.191033)
			(xy 66.230065 -183.11845) (xy 66.259542 -183.048604) (xy 66.296277 -182.982287) (xy 66.339852 -182.920251)
			(xy 66.389774 -182.863198) (xy 66.445478 -182.811774) (xy 66.506333 -182.766563) (xy 66.571648 -182.728076)
			(xy 66.640684 -182.69675) (xy 66.712659 -182.67294) (xy 66.786757 -182.656915) (xy 66.862138 -182.648856)
			(xy 66.900044 -182.648352) (xy 66.93795 -182.648856) (xy 67.013331 -182.656915) (xy 67.087429 -182.67294)
			(xy 67.159404 -182.69675) (xy 67.22844 -182.728076) (xy 67.293755 -182.766563) (xy 67.35461 -182.811774)
			(xy 67.410314 -182.863198) (xy 67.460236 -182.920251) (xy 67.503811 -182.982287) (xy 67.540546 -183.048604)
			(xy 67.570023 -183.11845) (xy 67.591909 -183.191033) (xy 67.605956 -183.265531) (xy 67.612005 -183.341101)
			(xy 68.728083 -183.341101) (xy 68.734132 -183.265531) (xy 68.748179 -183.191033) (xy 68.770065 -183.11845)
			(xy 68.799542 -183.048604) (xy 68.836277 -182.982287) (xy 68.879852 -182.920251) (xy 68.929774 -182.863198)
			(xy 68.985478 -182.811774) (xy 69.046333 -182.766563) (xy 69.111648 -182.728076) (xy 69.180684 -182.69675)
			(xy 69.252659 -182.67294) (xy 69.326757 -182.656915) (xy 69.402138 -182.648856) (xy 69.440044 -182.648352)
			(xy 69.47795 -182.648856) (xy 69.553331 -182.656915) (xy 69.627429 -182.67294) (xy 69.699404 -182.69675)
			(xy 69.76844 -182.728076) (xy 69.833755 -182.766563) (xy 69.89461 -182.811774) (xy 69.950314 -182.863198)
			(xy 70.000236 -182.920251) (xy 70.043811 -182.982287) (xy 70.080546 -183.048604) (xy 70.110023 -183.11845)
			(xy 70.131909 -183.191033) (xy 70.145956 -183.265531) (xy 70.152005 -183.341101) (xy 71.268083 -183.341101)
			(xy 71.274132 -183.265531) (xy 71.288179 -183.191033) (xy 71.310065 -183.11845) (xy 71.339542 -183.048604)
			(xy 71.376277 -182.982287) (xy 71.419852 -182.920251) (xy 71.469774 -182.863198) (xy 71.525478 -182.811774)
			(xy 71.586333 -182.766563) (xy 71.651648 -182.728076) (xy 71.720684 -182.69675) (xy 71.792659 -182.67294)
			(xy 71.866757 -182.656915) (xy 71.942138 -182.648856) (xy 71.980044 -182.648352) (xy 72.01795 -182.648856)
			(xy 72.093331 -182.656915) (xy 72.167429 -182.67294) (xy 72.239404 -182.69675) (xy 72.30844 -182.728076)
			(xy 72.373755 -182.766563) (xy 72.43461 -182.811774) (xy 72.490314 -182.863198) (xy 72.540236 -182.920251)
			(xy 72.583811 -182.982287) (xy 72.620546 -183.048604) (xy 72.650023 -183.11845) (xy 72.671909 -183.191033)
			(xy 72.685956 -183.265531) (xy 72.692005 -183.341101) (xy 73.808083 -183.341101) (xy 73.814132 -183.265531)
			(xy 73.828179 -183.191033) (xy 73.850065 -183.11845) (xy 73.879542 -183.048604) (xy 73.916277 -182.982287)
			(xy 73.959852 -182.920251) (xy 74.009774 -182.863198) (xy 74.065478 -182.811774) (xy 74.126333 -182.766563)
			(xy 74.191648 -182.728076) (xy 74.260684 -182.69675) (xy 74.332659 -182.67294) (xy 74.406757 -182.656915)
			(xy 74.482138 -182.648856) (xy 74.520044 -182.648352) (xy 74.55795 -182.648856) (xy 74.633331 -182.656915)
			(xy 74.707429 -182.67294) (xy 74.779404 -182.69675) (xy 74.84844 -182.728076) (xy 74.913755 -182.766563)
			(xy 74.97461 -182.811774) (xy 75.030314 -182.863198) (xy 75.080236 -182.920251) (xy 75.123811 -182.982287)
			(xy 75.160546 -183.048604) (xy 75.190023 -183.11845) (xy 75.211909 -183.191033) (xy 75.225956 -183.265531)
			(xy 75.232005 -183.341101) (xy 76.348083 -183.341101) (xy 76.354132 -183.265531) (xy 76.368179 -183.191033)
			(xy 76.390065 -183.11845) (xy 76.419542 -183.048604) (xy 76.456277 -182.982287) (xy 76.499852 -182.920251)
			(xy 76.549774 -182.863198) (xy 76.605478 -182.811774) (xy 76.666333 -182.766563) (xy 76.731648 -182.728076)
			(xy 76.800684 -182.69675) (xy 76.872659 -182.67294) (xy 76.946757 -182.656915) (xy 77.022138 -182.648856)
			(xy 77.060044 -182.648352) (xy 77.09795 -182.648856) (xy 77.173331 -182.656915) (xy 77.247429 -182.67294)
			(xy 77.319404 -182.69675) (xy 77.38844 -182.728076) (xy 77.453755 -182.766563) (xy 77.51461 -182.811774)
			(xy 77.570314 -182.863198) (xy 77.620236 -182.920251) (xy 77.663811 -182.982287) (xy 77.700546 -183.048604)
			(xy 77.730023 -183.11845) (xy 77.751909 -183.191033) (xy 77.765956 -183.265531) (xy 77.772005 -183.341101)
			(xy 78.888083 -183.341101) (xy 78.894132 -183.265531) (xy 78.908179 -183.191033) (xy 78.930065 -183.11845)
			(xy 78.959542 -183.048604) (xy 78.996277 -182.982287) (xy 79.039852 -182.920251) (xy 79.089774 -182.863198)
			(xy 79.145478 -182.811774) (xy 79.206333 -182.766563) (xy 79.271648 -182.728076) (xy 79.340684 -182.69675)
			(xy 79.412659 -182.67294) (xy 79.486757 -182.656915) (xy 79.562138 -182.648856) (xy 79.600044 -182.648352)
			(xy 79.63795 -182.648856) (xy 79.713331 -182.656915) (xy 79.787429 -182.67294) (xy 79.859404 -182.69675)
			(xy 79.92844 -182.728076) (xy 79.993755 -182.766563) (xy 80.05461 -182.811774) (xy 80.110314 -182.863198)
			(xy 80.160236 -182.920251) (xy 80.203811 -182.982287) (xy 80.240546 -183.048604) (xy 80.270023 -183.11845)
			(xy 80.291909 -183.191033) (xy 80.305956 -183.265531) (xy 80.312005 -183.341101) (xy 81.428083 -183.341101)
			(xy 81.434132 -183.265531) (xy 81.448179 -183.191033) (xy 81.470065 -183.11845) (xy 81.499542 -183.048604)
			(xy 81.536277 -182.982287) (xy 81.579852 -182.920251) (xy 81.629774 -182.863198) (xy 81.685478 -182.811774)
			(xy 81.746333 -182.766563) (xy 81.811648 -182.728076) (xy 81.880684 -182.69675) (xy 81.952659 -182.67294)
			(xy 82.026757 -182.656915) (xy 82.102138 -182.648856) (xy 82.140044 -182.648352) (xy 82.17795 -182.648856)
			(xy 82.253331 -182.656915) (xy 82.327429 -182.67294) (xy 82.399404 -182.69675) (xy 82.46844 -182.728076)
			(xy 82.533755 -182.766563) (xy 82.560067 -182.786111) (xy 86.198203 -182.786111) (xy 86.204252 -182.710541)
			(xy 86.218299 -182.636043) (xy 86.240185 -182.56346) (xy 86.269662 -182.493614) (xy 86.306397 -182.427297)
			(xy 86.349972 -182.365261) (xy 86.399894 -182.308208) (xy 86.455598 -182.256784) (xy 86.516453 -182.211573)
			(xy 86.581768 -182.173086) (xy 86.650804 -182.14176) (xy 86.722779 -182.11795) (xy 86.796877 -182.101925)
			(xy 86.872258 -182.093866) (xy 86.910164 -182.093362) (xy 86.94807 -182.093866) (xy 87.023451 -182.101925)
			(xy 87.097549 -182.11795) (xy 87.169524 -182.14176) (xy 87.23856 -182.173086) (xy 87.303875 -182.211573)
			(xy 87.36473 -182.256784) (xy 87.420434 -182.308208) (xy 87.470356 -182.365261) (xy 87.513931 -182.427297)
			(xy 87.550666 -182.493614) (xy 87.580143 -182.56346) (xy 87.602029 -182.636043) (xy 87.616076 -182.710541)
			(xy 87.622125 -182.786111) (xy 88.738203 -182.786111) (xy 88.744252 -182.710541) (xy 88.758299 -182.636043)
			(xy 88.780185 -182.56346) (xy 88.809662 -182.493614) (xy 88.846397 -182.427297) (xy 88.889972 -182.365261)
			(xy 88.939894 -182.308208) (xy 88.995598 -182.256784) (xy 89.056453 -182.211573) (xy 89.121768 -182.173086)
			(xy 89.190804 -182.14176) (xy 89.262779 -182.11795) (xy 89.336877 -182.101925) (xy 89.412258 -182.093866)
			(xy 89.450164 -182.093362) (xy 89.48807 -182.093866) (xy 89.563451 -182.101925) (xy 89.637549 -182.11795)
			(xy 89.709524 -182.14176) (xy 89.77856 -182.173086) (xy 89.843875 -182.211573) (xy 89.90473 -182.256784)
			(xy 89.960434 -182.308208) (xy 90.010356 -182.365261) (xy 90.053931 -182.427297) (xy 90.090666 -182.493614)
			(xy 90.120143 -182.56346) (xy 90.142029 -182.636043) (xy 90.156076 -182.710541) (xy 90.162125 -182.786111)
			(xy 91.278203 -182.786111) (xy 91.284252 -182.710541) (xy 91.298299 -182.636043) (xy 91.320185 -182.56346)
			(xy 91.349662 -182.493614) (xy 91.386397 -182.427297) (xy 91.429972 -182.365261) (xy 91.479894 -182.308208)
			(xy 91.535598 -182.256784) (xy 91.596453 -182.211573) (xy 91.661768 -182.173086) (xy 91.730804 -182.14176)
			(xy 91.802779 -182.11795) (xy 91.876877 -182.101925) (xy 91.952258 -182.093866) (xy 91.990164 -182.093362)
			(xy 92.02807 -182.093866) (xy 92.103451 -182.101925) (xy 92.177549 -182.11795) (xy 92.249524 -182.14176)
			(xy 92.31856 -182.173086) (xy 92.383875 -182.211573) (xy 92.44473 -182.256784) (xy 92.500434 -182.308208)
			(xy 92.550356 -182.365261) (xy 92.593931 -182.427297) (xy 92.630666 -182.493614) (xy 92.660143 -182.56346)
			(xy 92.682029 -182.636043) (xy 92.696076 -182.710541) (xy 92.702125 -182.786111) (xy 92.700106 -182.861895)
			(xy 92.690044 -182.937035) (xy 92.672052 -183.01068) (xy 92.646334 -183.081996) (xy 92.613182 -183.150173)
			(xy 92.57297 -183.214441) (xy 92.526155 -183.27407) (xy 92.473267 -183.328386) (xy 92.414905 -183.376772)
			(xy 92.35173 -183.41868) (xy 92.284459 -183.453636) (xy 92.213854 -183.481243) (xy 92.140713 -183.501189)
			(xy 92.065868 -183.513248) (xy 91.990164 -183.517283) (xy 91.91446 -183.513248) (xy 91.839615 -183.501189)
			(xy 91.766474 -183.481243) (xy 91.695869 -183.453636) (xy 91.628598 -183.41868) (xy 91.565423 -183.376772)
			(xy 91.507061 -183.328386) (xy 91.454173 -183.27407) (xy 91.407358 -183.214441) (xy 91.367146 -183.150173)
			(xy 91.333994 -183.081996) (xy 91.308276 -183.01068) (xy 91.290284 -182.937035) (xy 91.280222 -182.861895)
			(xy 91.278203 -182.786111) (xy 90.162125 -182.786111) (xy 90.160106 -182.861895) (xy 90.150044 -182.937035)
			(xy 90.132052 -183.01068) (xy 90.106334 -183.081996) (xy 90.073182 -183.150173) (xy 90.03297 -183.214441)
			(xy 89.986155 -183.27407) (xy 89.933267 -183.328386) (xy 89.874905 -183.376772) (xy 89.81173 -183.41868)
			(xy 89.744459 -183.453636) (xy 89.673854 -183.481243) (xy 89.600713 -183.501189) (xy 89.525868 -183.513248)
			(xy 89.450164 -183.517283) (xy 89.37446 -183.513248) (xy 89.299615 -183.501189) (xy 89.226474 -183.481243)
			(xy 89.155869 -183.453636) (xy 89.088598 -183.41868) (xy 89.025423 -183.376772) (xy 88.967061 -183.328386)
			(xy 88.914173 -183.27407) (xy 88.867358 -183.214441) (xy 88.827146 -183.150173) (xy 88.793994 -183.081996)
			(xy 88.768276 -183.01068) (xy 88.750284 -182.937035) (xy 88.740222 -182.861895) (xy 88.738203 -182.786111)
			(xy 87.622125 -182.786111) (xy 87.620106 -182.861895) (xy 87.610044 -182.937035) (xy 87.592052 -183.01068)
			(xy 87.566334 -183.081996) (xy 87.533182 -183.150173) (xy 87.49297 -183.214441) (xy 87.446155 -183.27407)
			(xy 87.393267 -183.328386) (xy 87.334905 -183.376772) (xy 87.27173 -183.41868) (xy 87.204459 -183.453636)
			(xy 87.133854 -183.481243) (xy 87.060713 -183.501189) (xy 86.985868 -183.513248) (xy 86.910164 -183.517283)
			(xy 86.83446 -183.513248) (xy 86.759615 -183.501189) (xy 86.686474 -183.481243) (xy 86.615869 -183.453636)
			(xy 86.548598 -183.41868) (xy 86.485423 -183.376772) (xy 86.427061 -183.328386) (xy 86.374173 -183.27407)
			(xy 86.327358 -183.214441) (xy 86.287146 -183.150173) (xy 86.253994 -183.081996) (xy 86.228276 -183.01068)
			(xy 86.210284 -182.937035) (xy 86.200222 -182.861895) (xy 86.198203 -182.786111) (xy 82.560067 -182.786111)
			(xy 82.59461 -182.811774) (xy 82.650314 -182.863198) (xy 82.700236 -182.920251) (xy 82.743811 -182.982287)
			(xy 82.780546 -183.048604) (xy 82.810023 -183.11845) (xy 82.831909 -183.191033) (xy 82.845956 -183.265531)
			(xy 82.852005 -183.341101) (xy 82.849986 -183.416885) (xy 82.839924 -183.492025) (xy 82.821932 -183.56567)
			(xy 82.796214 -183.636986) (xy 82.763062 -183.705163) (xy 82.72285 -183.769431) (xy 82.676035 -183.82906)
			(xy 82.623147 -183.883376) (xy 82.564785 -183.931762) (xy 82.50161 -183.97367) (xy 82.434339 -184.008626)
			(xy 82.363734 -184.036233) (xy 82.290842 -184.056111) (xy 84.928203 -184.056111) (xy 84.934252 -183.980541)
			(xy 84.948299 -183.906043) (xy 84.970185 -183.83346) (xy 84.999662 -183.763614) (xy 85.036397 -183.697297)
			(xy 85.079972 -183.635261) (xy 85.129894 -183.578208) (xy 85.185598 -183.526784) (xy 85.246453 -183.481573)
			(xy 85.311768 -183.443086) (xy 85.380804 -183.41176) (xy 85.452779 -183.38795) (xy 85.526877 -183.371925)
			(xy 85.602258 -183.363866) (xy 85.640164 -183.363362) (xy 85.67807 -183.363866) (xy 85.753451 -183.371925)
			(xy 85.827549 -183.38795) (xy 85.899524 -183.41176) (xy 85.96856 -183.443086) (xy 86.033875 -183.481573)
			(xy 86.09473 -183.526784) (xy 86.150434 -183.578208) (xy 86.200356 -183.635261) (xy 86.243931 -183.697297)
			(xy 86.280666 -183.763614) (xy 86.310143 -183.83346) (xy 86.332029 -183.906043) (xy 86.346076 -183.980541)
			(xy 86.352125 -184.056111) (xy 87.468203 -184.056111) (xy 87.474252 -183.980541) (xy 87.488299 -183.906043)
			(xy 87.510185 -183.83346) (xy 87.539662 -183.763614) (xy 87.576397 -183.697297) (xy 87.619972 -183.635261)
			(xy 87.669894 -183.578208) (xy 87.725598 -183.526784) (xy 87.786453 -183.481573) (xy 87.851768 -183.443086)
			(xy 87.920804 -183.41176) (xy 87.992779 -183.38795) (xy 88.066877 -183.371925) (xy 88.142258 -183.363866)
			(xy 88.180164 -183.363362) (xy 88.21807 -183.363866) (xy 88.293451 -183.371925) (xy 88.367549 -183.38795)
			(xy 88.439524 -183.41176) (xy 88.50856 -183.443086) (xy 88.573875 -183.481573) (xy 88.63473 -183.526784)
			(xy 88.690434 -183.578208) (xy 88.740356 -183.635261) (xy 88.783931 -183.697297) (xy 88.820666 -183.763614)
			(xy 88.850143 -183.83346) (xy 88.872029 -183.906043) (xy 88.886076 -183.980541) (xy 88.892125 -184.056111)
			(xy 90.008203 -184.056111) (xy 90.014252 -183.980541) (xy 90.028299 -183.906043) (xy 90.050185 -183.83346)
			(xy 90.079662 -183.763614) (xy 90.116397 -183.697297) (xy 90.159972 -183.635261) (xy 90.209894 -183.578208)
			(xy 90.265598 -183.526784) (xy 90.326453 -183.481573) (xy 90.391768 -183.443086) (xy 90.460804 -183.41176)
			(xy 90.532779 -183.38795) (xy 90.606877 -183.371925) (xy 90.682258 -183.363866) (xy 90.720164 -183.363362)
			(xy 90.75807 -183.363866) (xy 90.833451 -183.371925) (xy 90.907549 -183.38795) (xy 90.979524 -183.41176)
			(xy 91.04856 -183.443086) (xy 91.113875 -183.481573) (xy 91.17473 -183.526784) (xy 91.230434 -183.578208)
			(xy 91.280356 -183.635261) (xy 91.323931 -183.697297) (xy 91.360666 -183.763614) (xy 91.390143 -183.83346)
			(xy 91.412029 -183.906043) (xy 91.426076 -183.980541) (xy 91.432125 -184.056111) (xy 91.430106 -184.131895)
			(xy 91.420044 -184.207035) (xy 91.402052 -184.28068) (xy 91.376334 -184.351996) (xy 91.343182 -184.420173)
			(xy 91.30297 -184.484441) (xy 91.256155 -184.54407) (xy 91.203267 -184.598386) (xy 91.144905 -184.646772)
			(xy 91.08173 -184.68868) (xy 91.014459 -184.723636) (xy 90.943854 -184.751243) (xy 90.870713 -184.771189)
			(xy 90.795868 -184.783248) (xy 90.720164 -184.787283) (xy 90.64446 -184.783248) (xy 90.569615 -184.771189)
			(xy 90.496474 -184.751243) (xy 90.425869 -184.723636) (xy 90.358598 -184.68868) (xy 90.295423 -184.646772)
			(xy 90.237061 -184.598386) (xy 90.184173 -184.54407) (xy 90.137358 -184.484441) (xy 90.097146 -184.420173)
			(xy 90.063994 -184.351996) (xy 90.038276 -184.28068) (xy 90.020284 -184.207035) (xy 90.010222 -184.131895)
			(xy 90.008203 -184.056111) (xy 88.892125 -184.056111) (xy 88.890106 -184.131895) (xy 88.880044 -184.207035)
			(xy 88.862052 -184.28068) (xy 88.836334 -184.351996) (xy 88.803182 -184.420173) (xy 88.76297 -184.484441)
			(xy 88.716155 -184.54407) (xy 88.663267 -184.598386) (xy 88.604905 -184.646772) (xy 88.54173 -184.68868)
			(xy 88.474459 -184.723636) (xy 88.403854 -184.751243) (xy 88.330713 -184.771189) (xy 88.255868 -184.783248)
			(xy 88.180164 -184.787283) (xy 88.10446 -184.783248) (xy 88.029615 -184.771189) (xy 87.956474 -184.751243)
			(xy 87.885869 -184.723636) (xy 87.818598 -184.68868) (xy 87.755423 -184.646772) (xy 87.697061 -184.598386)
			(xy 87.644173 -184.54407) (xy 87.597358 -184.484441) (xy 87.557146 -184.420173) (xy 87.523994 -184.351996)
			(xy 87.498276 -184.28068) (xy 87.480284 -184.207035) (xy 87.470222 -184.131895) (xy 87.468203 -184.056111)
			(xy 86.352125 -184.056111) (xy 86.350106 -184.131895) (xy 86.340044 -184.207035) (xy 86.322052 -184.28068)
			(xy 86.296334 -184.351996) (xy 86.263182 -184.420173) (xy 86.22297 -184.484441) (xy 86.176155 -184.54407)
			(xy 86.123267 -184.598386) (xy 86.064905 -184.646772) (xy 86.00173 -184.68868) (xy 85.934459 -184.723636)
			(xy 85.863854 -184.751243) (xy 85.790713 -184.771189) (xy 85.715868 -184.783248) (xy 85.640164 -184.787283)
			(xy 85.56446 -184.783248) (xy 85.489615 -184.771189) (xy 85.416474 -184.751243) (xy 85.345869 -184.723636)
			(xy 85.278598 -184.68868) (xy 85.215423 -184.646772) (xy 85.157061 -184.598386) (xy 85.104173 -184.54407)
			(xy 85.057358 -184.484441) (xy 85.017146 -184.420173) (xy 84.983994 -184.351996) (xy 84.958276 -184.28068)
			(xy 84.940284 -184.207035) (xy 84.930222 -184.131895) (xy 84.928203 -184.056111) (xy 82.290842 -184.056111)
			(xy 82.290593 -184.056179) (xy 82.215748 -184.068238) (xy 82.140044 -184.072273) (xy 82.06434 -184.068238)
			(xy 81.989495 -184.056179) (xy 81.916354 -184.036233) (xy 81.845749 -184.008626) (xy 81.778478 -183.97367)
			(xy 81.715303 -183.931762) (xy 81.656941 -183.883376) (xy 81.604053 -183.82906) (xy 81.557238 -183.769431)
			(xy 81.517026 -183.705163) (xy 81.483874 -183.636986) (xy 81.458156 -183.56567) (xy 81.440164 -183.492025)
			(xy 81.430102 -183.416885) (xy 81.428083 -183.341101) (xy 80.312005 -183.341101) (xy 80.309986 -183.416885)
			(xy 80.299924 -183.492025) (xy 80.281932 -183.56567) (xy 80.256214 -183.636986) (xy 80.223062 -183.705163)
			(xy 80.18285 -183.769431) (xy 80.136035 -183.82906) (xy 80.083147 -183.883376) (xy 80.024785 -183.931762)
			(xy 79.96161 -183.97367) (xy 79.894339 -184.008626) (xy 79.823734 -184.036233) (xy 79.750593 -184.056179)
			(xy 79.675748 -184.068238) (xy 79.600044 -184.072273) (xy 79.52434 -184.068238) (xy 79.449495 -184.056179)
			(xy 79.376354 -184.036233) (xy 79.305749 -184.008626) (xy 79.238478 -183.97367) (xy 79.175303 -183.931762)
			(xy 79.116941 -183.883376) (xy 79.064053 -183.82906) (xy 79.017238 -183.769431) (xy 78.977026 -183.705163)
			(xy 78.943874 -183.636986) (xy 78.918156 -183.56567) (xy 78.900164 -183.492025) (xy 78.890102 -183.416885)
			(xy 78.888083 -183.341101) (xy 77.772005 -183.341101) (xy 77.769986 -183.416885) (xy 77.759924 -183.492025)
			(xy 77.741932 -183.56567) (xy 77.716214 -183.636986) (xy 77.683062 -183.705163) (xy 77.64285 -183.769431)
			(xy 77.596035 -183.82906) (xy 77.543147 -183.883376) (xy 77.484785 -183.931762) (xy 77.42161 -183.97367)
			(xy 77.354339 -184.008626) (xy 77.283734 -184.036233) (xy 77.210593 -184.056179) (xy 77.135748 -184.068238)
			(xy 77.060044 -184.072273) (xy 76.98434 -184.068238) (xy 76.909495 -184.056179) (xy 76.836354 -184.036233)
			(xy 76.765749 -184.008626) (xy 76.698478 -183.97367) (xy 76.635303 -183.931762) (xy 76.576941 -183.883376)
			(xy 76.524053 -183.82906) (xy 76.477238 -183.769431) (xy 76.437026 -183.705163) (xy 76.403874 -183.636986)
			(xy 76.378156 -183.56567) (xy 76.360164 -183.492025) (xy 76.350102 -183.416885) (xy 76.348083 -183.341101)
			(xy 75.232005 -183.341101) (xy 75.229986 -183.416885) (xy 75.219924 -183.492025) (xy 75.201932 -183.56567)
			(xy 75.176214 -183.636986) (xy 75.143062 -183.705163) (xy 75.10285 -183.769431) (xy 75.056035 -183.82906)
			(xy 75.003147 -183.883376) (xy 74.944785 -183.931762) (xy 74.88161 -183.97367) (xy 74.814339 -184.008626)
			(xy 74.743734 -184.036233) (xy 74.670593 -184.056179) (xy 74.595748 -184.068238) (xy 74.520044 -184.072273)
			(xy 74.44434 -184.068238) (xy 74.369495 -184.056179) (xy 74.296354 -184.036233) (xy 74.225749 -184.008626)
			(xy 74.158478 -183.97367) (xy 74.095303 -183.931762) (xy 74.036941 -183.883376) (xy 73.984053 -183.82906)
			(xy 73.937238 -183.769431) (xy 73.897026 -183.705163) (xy 73.863874 -183.636986) (xy 73.838156 -183.56567)
			(xy 73.820164 -183.492025) (xy 73.810102 -183.416885) (xy 73.808083 -183.341101) (xy 72.692005 -183.341101)
			(xy 72.689986 -183.416885) (xy 72.679924 -183.492025) (xy 72.661932 -183.56567) (xy 72.636214 -183.636986)
			(xy 72.603062 -183.705163) (xy 72.56285 -183.769431) (xy 72.516035 -183.82906) (xy 72.463147 -183.883376)
			(xy 72.404785 -183.931762) (xy 72.34161 -183.97367) (xy 72.274339 -184.008626) (xy 72.203734 -184.036233)
			(xy 72.130593 -184.056179) (xy 72.055748 -184.068238) (xy 71.980044 -184.072273) (xy 71.90434 -184.068238)
			(xy 71.829495 -184.056179) (xy 71.756354 -184.036233) (xy 71.685749 -184.008626) (xy 71.618478 -183.97367)
			(xy 71.555303 -183.931762) (xy 71.496941 -183.883376) (xy 71.444053 -183.82906) (xy 71.397238 -183.769431)
			(xy 71.357026 -183.705163) (xy 71.323874 -183.636986) (xy 71.298156 -183.56567) (xy 71.280164 -183.492025)
			(xy 71.270102 -183.416885) (xy 71.268083 -183.341101) (xy 70.152005 -183.341101) (xy 70.149986 -183.416885)
			(xy 70.139924 -183.492025) (xy 70.121932 -183.56567) (xy 70.096214 -183.636986) (xy 70.063062 -183.705163)
			(xy 70.02285 -183.769431) (xy 69.976035 -183.82906) (xy 69.923147 -183.883376) (xy 69.864785 -183.931762)
			(xy 69.80161 -183.97367) (xy 69.734339 -184.008626) (xy 69.663734 -184.036233) (xy 69.590593 -184.056179)
			(xy 69.515748 -184.068238) (xy 69.440044 -184.072273) (xy 69.36434 -184.068238) (xy 69.289495 -184.056179)
			(xy 69.216354 -184.036233) (xy 69.145749 -184.008626) (xy 69.078478 -183.97367) (xy 69.015303 -183.931762)
			(xy 68.956941 -183.883376) (xy 68.904053 -183.82906) (xy 68.857238 -183.769431) (xy 68.817026 -183.705163)
			(xy 68.783874 -183.636986) (xy 68.758156 -183.56567) (xy 68.740164 -183.492025) (xy 68.730102 -183.416885)
			(xy 68.728083 -183.341101) (xy 67.612005 -183.341101) (xy 67.609986 -183.416885) (xy 67.599924 -183.492025)
			(xy 67.581932 -183.56567) (xy 67.556214 -183.636986) (xy 67.523062 -183.705163) (xy 67.48285 -183.769431)
			(xy 67.436035 -183.82906) (xy 67.383147 -183.883376) (xy 67.324785 -183.931762) (xy 67.26161 -183.97367)
			(xy 67.194339 -184.008626) (xy 67.123734 -184.036233) (xy 67.050593 -184.056179) (xy 66.975748 -184.068238)
			(xy 66.900044 -184.072273) (xy 66.82434 -184.068238) (xy 66.749495 -184.056179) (xy 66.676354 -184.036233)
			(xy 66.605749 -184.008626) (xy 66.538478 -183.97367) (xy 66.475303 -183.931762) (xy 66.416941 -183.883376)
			(xy 66.364053 -183.82906) (xy 66.317238 -183.769431) (xy 66.277026 -183.705163) (xy 66.243874 -183.636986)
			(xy 66.218156 -183.56567) (xy 66.200164 -183.492025) (xy 66.190102 -183.416885) (xy 66.188083 -183.341101)
			(xy 65.072005 -183.341101) (xy 65.069986 -183.416885) (xy 65.059924 -183.492025) (xy 65.041932 -183.56567)
			(xy 65.016214 -183.636986) (xy 64.983062 -183.705163) (xy 64.94285 -183.769431) (xy 64.896035 -183.82906)
			(xy 64.843147 -183.883376) (xy 64.784785 -183.931762) (xy 64.72161 -183.97367) (xy 64.654339 -184.008626)
			(xy 64.583734 -184.036233) (xy 64.510593 -184.056179) (xy 64.435748 -184.068238) (xy 64.360044 -184.072273)
			(xy 64.28434 -184.068238) (xy 64.209495 -184.056179) (xy 64.136354 -184.036233) (xy 64.065749 -184.008626)
			(xy 63.998478 -183.97367) (xy 63.935303 -183.931762) (xy 63.876941 -183.883376) (xy 63.824053 -183.82906)
			(xy 63.777238 -183.769431) (xy 63.737026 -183.705163) (xy 63.703874 -183.636986) (xy 63.678156 -183.56567)
			(xy 63.660164 -183.492025) (xy 63.650102 -183.416885) (xy 63.648083 -183.341101) (xy 42.476087 -183.341101)
			(xy 42.563359 -183.407458) (xy 42.650705 -183.483935) (xy 42.732564 -183.566258) (xy 42.808549 -183.654032)
			(xy 42.878295 -183.746841) (xy 42.94147 -183.844241) (xy 42.997774 -183.945769) (xy 43.046938 -184.05094)
			(xy 43.088727 -184.159253) (xy 43.122942 -184.270191) (xy 43.149421 -184.383225) (xy 43.168036 -184.497818)
			(xy 43.1787 -184.613422) (xy 43.181361 -184.729486) (xy 43.176007 -184.845457) (xy 43.162662 -184.960782)
			(xy 43.141392 -185.074912) (xy 43.112297 -185.187302) (xy 43.075515 -185.297416) (xy 43.063672 -185.326111)
			(xy 86.198203 -185.326111) (xy 86.204252 -185.250541) (xy 86.218299 -185.176043) (xy 86.240185 -185.10346)
			(xy 86.269662 -185.033614) (xy 86.306397 -184.967297) (xy 86.349972 -184.905261) (xy 86.399894 -184.848208)
			(xy 86.455598 -184.796784) (xy 86.516453 -184.751573) (xy 86.581768 -184.713086) (xy 86.650804 -184.68176)
			(xy 86.722779 -184.65795) (xy 86.796877 -184.641925) (xy 86.872258 -184.633866) (xy 86.910164 -184.633362)
			(xy 86.94807 -184.633866) (xy 87.023451 -184.641925) (xy 87.097549 -184.65795) (xy 87.169524 -184.68176)
			(xy 87.23856 -184.713086) (xy 87.303875 -184.751573) (xy 87.36473 -184.796784) (xy 87.420434 -184.848208)
			(xy 87.470356 -184.905261) (xy 87.513931 -184.967297) (xy 87.550666 -185.033614) (xy 87.580143 -185.10346)
			(xy 87.602029 -185.176043) (xy 87.616076 -185.250541) (xy 87.622125 -185.326111) (xy 88.738203 -185.326111)
			(xy 88.744252 -185.250541) (xy 88.758299 -185.176043) (xy 88.780185 -185.10346) (xy 88.809662 -185.033614)
			(xy 88.846397 -184.967297) (xy 88.889972 -184.905261) (xy 88.939894 -184.848208) (xy 88.995598 -184.796784)
			(xy 89.056453 -184.751573) (xy 89.121768 -184.713086) (xy 89.190804 -184.68176) (xy 89.262779 -184.65795)
			(xy 89.336877 -184.641925) (xy 89.412258 -184.633866) (xy 89.450164 -184.633362) (xy 89.48807 -184.633866)
			(xy 89.563451 -184.641925) (xy 89.637549 -184.65795) (xy 89.709524 -184.68176) (xy 89.77856 -184.713086)
			(xy 89.843875 -184.751573) (xy 89.90473 -184.796784) (xy 89.960434 -184.848208) (xy 90.010356 -184.905261)
			(xy 90.053931 -184.967297) (xy 90.090666 -185.033614) (xy 90.120143 -185.10346) (xy 90.142029 -185.176043)
			(xy 90.156076 -185.250541) (xy 90.162125 -185.326111) (xy 91.278203 -185.326111) (xy 91.284252 -185.250541)
			(xy 91.298299 -185.176043) (xy 91.320185 -185.10346) (xy 91.349662 -185.033614) (xy 91.386397 -184.967297)
			(xy 91.429972 -184.905261) (xy 91.479894 -184.848208) (xy 91.535598 -184.796784) (xy 91.596453 -184.751573)
			(xy 91.661768 -184.713086) (xy 91.730804 -184.68176) (xy 91.802779 -184.65795) (xy 91.876877 -184.641925)
			(xy 91.952258 -184.633866) (xy 91.990164 -184.633362) (xy 92.02807 -184.633866) (xy 92.103451 -184.641925)
			(xy 92.177549 -184.65795) (xy 92.249524 -184.68176) (xy 92.31856 -184.713086) (xy 92.383875 -184.751573)
			(xy 92.44473 -184.796784) (xy 92.500434 -184.848208) (xy 92.550356 -184.905261) (xy 92.593931 -184.967297)
			(xy 92.630666 -185.033614) (xy 92.660143 -185.10346) (xy 92.682029 -185.176043) (xy 92.696076 -185.250541)
			(xy 92.702125 -185.326111) (xy 92.700106 -185.401895) (xy 92.690044 -185.477035) (xy 92.672052 -185.55068)
			(xy 92.646334 -185.621996) (xy 92.613182 -185.690173) (xy 92.57297 -185.754441) (xy 92.526155 -185.81407)
			(xy 92.473267 -185.868386) (xy 92.414905 -185.916772) (xy 92.35173 -185.95868) (xy 92.284459 -185.993636)
			(xy 92.213854 -186.021243) (xy 92.178109 -186.030991) (xy 93.155011 -186.030991) (xy 93.161033 -185.914808)
			(xy 93.175056 -185.799317) (xy 93.197014 -185.685069) (xy 93.226801 -185.572608) (xy 93.264276 -185.46247)
			(xy 93.309261 -185.35518) (xy 93.36154 -185.251249) (xy 93.420865 -185.151173) (xy 93.486953 -185.055427)
			(xy 93.559489 -184.96447) (xy 93.638128 -184.878734) (xy 93.722494 -184.798627) (xy 93.812186 -184.724531)
			(xy 93.906776 -184.656801) (xy 94.005814 -184.595757) (xy 94.108827 -184.541692) (xy 94.215324 -184.494862)
			(xy 94.324799 -184.455491) (xy 94.436729 -184.423767) (xy 94.550581 -184.399841) (xy 94.665813 -184.383827)
			(xy 94.781875 -184.3758) (xy 94.840044 -184.375298) (xy 94.898213 -184.3758) (xy 95.014275 -184.383827)
			(xy 95.129507 -184.399841) (xy 95.243359 -184.423767) (xy 95.355289 -184.455491) (xy 95.464764 -184.494862)
			(xy 95.571261 -184.541692) (xy 95.674274 -184.595757) (xy 95.773312 -184.656801) (xy 95.867902 -184.724531)
			(xy 95.957594 -184.798627) (xy 96.04196 -184.878734) (xy 96.120599 -184.96447) (xy 96.193135 -185.055427)
			(xy 96.259223 -185.151173) (xy 96.318548 -185.251249) (xy 96.370827 -185.35518) (xy 96.415812 -185.46247)
			(xy 96.453287 -185.572608) (xy 96.483074 -185.685069) (xy 96.505032 -185.799317) (xy 96.519055 -185.914808)
			(xy 96.525077 -186.030991) (xy 96.523069 -186.147313) (xy 96.51304 -186.263219) (xy 96.495039 -186.378156)
			(xy 96.469151 -186.491579) (xy 96.4355 -186.602944) (xy 96.394246 -186.711723) (xy 96.345585 -186.817397)
			(xy 96.289749 -186.919461) (xy 96.227006 -187.01743) (xy 96.157652 -187.110837) (xy 96.08202 -187.199237)
			(xy 96.000469 -187.282208) (xy 95.913388 -187.359355) (xy 95.821192 -187.43031) (xy 95.72432 -187.494736)
			(xy 95.623235 -187.552325) (xy 95.518417 -187.602802) (xy 95.410366 -187.645928) (xy 95.299598 -187.681497)
			(xy 95.186639 -187.709339) (xy 95.072029 -187.729321) (xy 94.956314 -187.741348) (xy 94.840044 -187.745364)
			(xy 94.723774 -187.741348) (xy 94.608059 -187.729321) (xy 94.493449 -187.709339) (xy 94.38049 -187.681497)
			(xy 94.269722 -187.645928) (xy 94.161671 -187.602802) (xy 94.056853 -187.552325) (xy 93.955768 -187.494736)
			(xy 93.858896 -187.43031) (xy 93.7667 -187.359355) (xy 93.679619 -187.282208) (xy 93.598068 -187.199237)
			(xy 93.522436 -187.110837) (xy 93.453082 -187.01743) (xy 93.390339 -186.919461) (xy 93.334503 -186.817397)
			(xy 93.285842 -186.711723) (xy 93.244588 -186.602944) (xy 93.210937 -186.491579) (xy 93.185049 -186.378156)
			(xy 93.167048 -186.263219) (xy 93.157019 -186.147313) (xy 93.155011 -186.030991) (xy 92.178109 -186.030991)
			(xy 92.140713 -186.041189) (xy 92.065868 -186.053248) (xy 91.990164 -186.057283) (xy 91.91446 -186.053248)
			(xy 91.839615 -186.041189) (xy 91.766474 -186.021243) (xy 91.695869 -185.993636) (xy 91.628598 -185.95868)
			(xy 91.565423 -185.916772) (xy 91.507061 -185.868386) (xy 91.454173 -185.81407) (xy 91.407358 -185.754441)
			(xy 91.367146 -185.690173) (xy 91.333994 -185.621996) (xy 91.308276 -185.55068) (xy 91.290284 -185.477035)
			(xy 91.280222 -185.401895) (xy 91.278203 -185.326111) (xy 90.162125 -185.326111) (xy 90.160106 -185.401895)
			(xy 90.150044 -185.477035) (xy 90.132052 -185.55068) (xy 90.106334 -185.621996) (xy 90.073182 -185.690173)
			(xy 90.03297 -185.754441) (xy 89.986155 -185.81407) (xy 89.933267 -185.868386) (xy 89.874905 -185.916772)
			(xy 89.81173 -185.95868) (xy 89.744459 -185.993636) (xy 89.673854 -186.021243) (xy 89.600713 -186.041189)
			(xy 89.525868 -186.053248) (xy 89.450164 -186.057283) (xy 89.37446 -186.053248) (xy 89.299615 -186.041189)
			(xy 89.226474 -186.021243) (xy 89.155869 -185.993636) (xy 89.088598 -185.95868) (xy 89.025423 -185.916772)
			(xy 88.967061 -185.868386) (xy 88.914173 -185.81407) (xy 88.867358 -185.754441) (xy 88.827146 -185.690173)
			(xy 88.793994 -185.621996) (xy 88.768276 -185.55068) (xy 88.750284 -185.477035) (xy 88.740222 -185.401895)
			(xy 88.738203 -185.326111) (xy 87.622125 -185.326111) (xy 87.620106 -185.401895) (xy 87.610044 -185.477035)
			(xy 87.592052 -185.55068) (xy 87.566334 -185.621996) (xy 87.533182 -185.690173) (xy 87.49297 -185.754441)
			(xy 87.446155 -185.81407) (xy 87.393267 -185.868386) (xy 87.334905 -185.916772) (xy 87.27173 -185.95868)
			(xy 87.204459 -185.993636) (xy 87.133854 -186.021243) (xy 87.060713 -186.041189) (xy 86.985868 -186.053248)
			(xy 86.910164 -186.057283) (xy 86.83446 -186.053248) (xy 86.759615 -186.041189) (xy 86.686474 -186.021243)
			(xy 86.615869 -185.993636) (xy 86.548598 -185.95868) (xy 86.485423 -185.916772) (xy 86.427061 -185.868386)
			(xy 86.374173 -185.81407) (xy 86.327358 -185.754441) (xy 86.287146 -185.690173) (xy 86.253994 -185.621996)
			(xy 86.228276 -185.55068) (xy 86.210284 -185.477035) (xy 86.200222 -185.401895) (xy 86.198203 -185.326111)
			(xy 43.063672 -185.326111) (xy 43.031223 -185.404729) (xy 42.979631 -185.508731) (xy 42.920986 -185.608924)
			(xy 42.855567 -185.704832) (xy 42.783685 -185.795996) (xy 42.705684 -185.881983) (xy 42.621935 -185.962383)
			(xy 42.532838 -186.036812) (xy 42.526889 -186.041121) (xy 63.648083 -186.041121) (xy 63.654132 -185.965551)
			(xy 63.668179 -185.891053) (xy 63.690065 -185.81847) (xy 63.719542 -185.748624) (xy 63.756277 -185.682307)
			(xy 63.799852 -185.620271) (xy 63.849774 -185.563218) (xy 63.905478 -185.511794) (xy 63.966333 -185.466583)
			(xy 64.031648 -185.428096) (xy 64.100684 -185.39677) (xy 64.172659 -185.37296) (xy 64.246757 -185.356935)
			(xy 64.322138 -185.348876) (xy 64.360044 -185.348372) (xy 64.39795 -185.348876) (xy 64.473331 -185.356935)
			(xy 64.547429 -185.37296) (xy 64.619404 -185.39677) (xy 64.68844 -185.428096) (xy 64.753755 -185.466583)
			(xy 64.81461 -185.511794) (xy 64.870314 -185.563218) (xy 64.920236 -185.620271) (xy 64.963811 -185.682307)
			(xy 65.000546 -185.748624) (xy 65.030023 -185.81847) (xy 65.051909 -185.891053) (xy 65.065956 -185.965551)
			(xy 65.072005 -186.041121) (xy 66.188083 -186.041121) (xy 66.194132 -185.965551) (xy 66.208179 -185.891053)
			(xy 66.230065 -185.81847) (xy 66.259542 -185.748624) (xy 66.296277 -185.682307) (xy 66.339852 -185.620271)
			(xy 66.389774 -185.563218) (xy 66.445478 -185.511794) (xy 66.506333 -185.466583) (xy 66.571648 -185.428096)
			(xy 66.640684 -185.39677) (xy 66.712659 -185.37296) (xy 66.786757 -185.356935) (xy 66.862138 -185.348876)
			(xy 66.900044 -185.348372) (xy 66.93795 -185.348876) (xy 67.013331 -185.356935) (xy 67.087429 -185.37296)
			(xy 67.159404 -185.39677) (xy 67.22844 -185.428096) (xy 67.293755 -185.466583) (xy 67.35461 -185.511794)
			(xy 67.410314 -185.563218) (xy 67.460236 -185.620271) (xy 67.503811 -185.682307) (xy 67.540546 -185.748624)
			(xy 67.570023 -185.81847) (xy 67.591909 -185.891053) (xy 67.605956 -185.965551) (xy 67.612005 -186.041121)
			(xy 68.728083 -186.041121) (xy 68.734132 -185.965551) (xy 68.748179 -185.891053) (xy 68.770065 -185.81847)
			(xy 68.799542 -185.748624) (xy 68.836277 -185.682307) (xy 68.879852 -185.620271) (xy 68.929774 -185.563218)
			(xy 68.985478 -185.511794) (xy 69.046333 -185.466583) (xy 69.111648 -185.428096) (xy 69.180684 -185.39677)
			(xy 69.252659 -185.37296) (xy 69.326757 -185.356935) (xy 69.402138 -185.348876) (xy 69.440044 -185.348372)
			(xy 69.47795 -185.348876) (xy 69.553331 -185.356935) (xy 69.627429 -185.37296) (xy 69.699404 -185.39677)
			(xy 69.76844 -185.428096) (xy 69.833755 -185.466583) (xy 69.89461 -185.511794) (xy 69.950314 -185.563218)
			(xy 70.000236 -185.620271) (xy 70.043811 -185.682307) (xy 70.080546 -185.748624) (xy 70.110023 -185.81847)
			(xy 70.131909 -185.891053) (xy 70.145956 -185.965551) (xy 70.152005 -186.041121) (xy 71.268083 -186.041121)
			(xy 71.274132 -185.965551) (xy 71.288179 -185.891053) (xy 71.310065 -185.81847) (xy 71.339542 -185.748624)
			(xy 71.376277 -185.682307) (xy 71.419852 -185.620271) (xy 71.469774 -185.563218) (xy 71.525478 -185.511794)
			(xy 71.586333 -185.466583) (xy 71.651648 -185.428096) (xy 71.720684 -185.39677) (xy 71.792659 -185.37296)
			(xy 71.866757 -185.356935) (xy 71.942138 -185.348876) (xy 71.980044 -185.348372) (xy 72.01795 -185.348876)
			(xy 72.093331 -185.356935) (xy 72.167429 -185.37296) (xy 72.239404 -185.39677) (xy 72.30844 -185.428096)
			(xy 72.373755 -185.466583) (xy 72.43461 -185.511794) (xy 72.490314 -185.563218) (xy 72.540236 -185.620271)
			(xy 72.583811 -185.682307) (xy 72.620546 -185.748624) (xy 72.650023 -185.81847) (xy 72.671909 -185.891053)
			(xy 72.685956 -185.965551) (xy 72.692005 -186.041121) (xy 73.808083 -186.041121) (xy 73.814132 -185.965551)
			(xy 73.828179 -185.891053) (xy 73.850065 -185.81847) (xy 73.879542 -185.748624) (xy 73.916277 -185.682307)
			(xy 73.959852 -185.620271) (xy 74.009774 -185.563218) (xy 74.065478 -185.511794) (xy 74.126333 -185.466583)
			(xy 74.191648 -185.428096) (xy 74.260684 -185.39677) (xy 74.332659 -185.37296) (xy 74.406757 -185.356935)
			(xy 74.482138 -185.348876) (xy 74.520044 -185.348372) (xy 74.55795 -185.348876) (xy 74.633331 -185.356935)
			(xy 74.707429 -185.37296) (xy 74.779404 -185.39677) (xy 74.84844 -185.428096) (xy 74.913755 -185.466583)
			(xy 74.97461 -185.511794) (xy 75.030314 -185.563218) (xy 75.080236 -185.620271) (xy 75.123811 -185.682307)
			(xy 75.160546 -185.748624) (xy 75.190023 -185.81847) (xy 75.211909 -185.891053) (xy 75.225956 -185.965551)
			(xy 75.232005 -186.041121) (xy 76.348083 -186.041121) (xy 76.354132 -185.965551) (xy 76.368179 -185.891053)
			(xy 76.390065 -185.81847) (xy 76.419542 -185.748624) (xy 76.456277 -185.682307) (xy 76.499852 -185.620271)
			(xy 76.549774 -185.563218) (xy 76.605478 -185.511794) (xy 76.666333 -185.466583) (xy 76.731648 -185.428096)
			(xy 76.800684 -185.39677) (xy 76.872659 -185.37296) (xy 76.946757 -185.356935) (xy 77.022138 -185.348876)
			(xy 77.060044 -185.348372) (xy 77.09795 -185.348876) (xy 77.173331 -185.356935) (xy 77.247429 -185.37296)
			(xy 77.319404 -185.39677) (xy 77.38844 -185.428096) (xy 77.453755 -185.466583) (xy 77.51461 -185.511794)
			(xy 77.570314 -185.563218) (xy 77.620236 -185.620271) (xy 77.663811 -185.682307) (xy 77.700546 -185.748624)
			(xy 77.730023 -185.81847) (xy 77.751909 -185.891053) (xy 77.765956 -185.965551) (xy 77.772005 -186.041121)
			(xy 78.888083 -186.041121) (xy 78.894132 -185.965551) (xy 78.908179 -185.891053) (xy 78.930065 -185.81847)
			(xy 78.959542 -185.748624) (xy 78.996277 -185.682307) (xy 79.039852 -185.620271) (xy 79.089774 -185.563218)
			(xy 79.145478 -185.511794) (xy 79.206333 -185.466583) (xy 79.271648 -185.428096) (xy 79.340684 -185.39677)
			(xy 79.412659 -185.37296) (xy 79.486757 -185.356935) (xy 79.562138 -185.348876) (xy 79.600044 -185.348372)
			(xy 79.63795 -185.348876) (xy 79.713331 -185.356935) (xy 79.787429 -185.37296) (xy 79.859404 -185.39677)
			(xy 79.92844 -185.428096) (xy 79.993755 -185.466583) (xy 80.05461 -185.511794) (xy 80.110314 -185.563218)
			(xy 80.160236 -185.620271) (xy 80.203811 -185.682307) (xy 80.240546 -185.748624) (xy 80.270023 -185.81847)
			(xy 80.291909 -185.891053) (xy 80.305956 -185.965551) (xy 80.312005 -186.041121) (xy 81.428083 -186.041121)
			(xy 81.434132 -185.965551) (xy 81.448179 -185.891053) (xy 81.470065 -185.81847) (xy 81.499542 -185.748624)
			(xy 81.536277 -185.682307) (xy 81.579852 -185.620271) (xy 81.629774 -185.563218) (xy 81.685478 -185.511794)
			(xy 81.746333 -185.466583) (xy 81.811648 -185.428096) (xy 81.880684 -185.39677) (xy 81.952659 -185.37296)
			(xy 82.026757 -185.356935) (xy 82.102138 -185.348876) (xy 82.140044 -185.348372) (xy 82.17795 -185.348876)
			(xy 82.253331 -185.356935) (xy 82.327429 -185.37296) (xy 82.399404 -185.39677) (xy 82.46844 -185.428096)
			(xy 82.533755 -185.466583) (xy 82.59461 -185.511794) (xy 82.650314 -185.563218) (xy 82.700236 -185.620271)
			(xy 82.743811 -185.682307) (xy 82.780546 -185.748624) (xy 82.810023 -185.81847) (xy 82.831909 -185.891053)
			(xy 82.845956 -185.965551) (xy 82.852005 -186.041121) (xy 82.849986 -186.116905) (xy 82.839924 -186.192045)
			(xy 82.821932 -186.26569) (xy 82.796214 -186.337006) (xy 82.763062 -186.405183) (xy 82.72285 -186.469451)
			(xy 82.676035 -186.52908) (xy 82.623147 -186.583396) (xy 82.60781 -186.596111) (xy 84.928203 -186.596111)
			(xy 84.934252 -186.520541) (xy 84.948299 -186.446043) (xy 84.970185 -186.37346) (xy 84.999662 -186.303614)
			(xy 85.036397 -186.237297) (xy 85.079972 -186.175261) (xy 85.129894 -186.118208) (xy 85.185598 -186.066784)
			(xy 85.246453 -186.021573) (xy 85.311768 -185.983086) (xy 85.380804 -185.95176) (xy 85.452779 -185.92795)
			(xy 85.526877 -185.911925) (xy 85.602258 -185.903866) (xy 85.640164 -185.903362) (xy 85.67807 -185.903866)
			(xy 85.753451 -185.911925) (xy 85.827549 -185.92795) (xy 85.899524 -185.95176) (xy 85.96856 -185.983086)
			(xy 86.033875 -186.021573) (xy 86.09473 -186.066784) (xy 86.150434 -186.118208) (xy 86.200356 -186.175261)
			(xy 86.243931 -186.237297) (xy 86.280666 -186.303614) (xy 86.310143 -186.37346) (xy 86.332029 -186.446043)
			(xy 86.346076 -186.520541) (xy 86.352125 -186.596111) (xy 87.468203 -186.596111) (xy 87.474252 -186.520541)
			(xy 87.488299 -186.446043) (xy 87.510185 -186.37346) (xy 87.539662 -186.303614) (xy 87.576397 -186.237297)
			(xy 87.619972 -186.175261) (xy 87.669894 -186.118208) (xy 87.725598 -186.066784) (xy 87.786453 -186.021573)
			(xy 87.851768 -185.983086) (xy 87.920804 -185.95176) (xy 87.992779 -185.92795) (xy 88.066877 -185.911925)
			(xy 88.142258 -185.903866) (xy 88.180164 -185.903362) (xy 88.21807 -185.903866) (xy 88.293451 -185.911925)
			(xy 88.367549 -185.92795) (xy 88.439524 -185.95176) (xy 88.50856 -185.983086) (xy 88.573875 -186.021573)
			(xy 88.63473 -186.066784) (xy 88.690434 -186.118208) (xy 88.740356 -186.175261) (xy 88.783931 -186.237297)
			(xy 88.820666 -186.303614) (xy 88.850143 -186.37346) (xy 88.872029 -186.446043) (xy 88.886076 -186.520541)
			(xy 88.892125 -186.596111) (xy 90.008203 -186.596111) (xy 90.014252 -186.520541) (xy 90.028299 -186.446043)
			(xy 90.050185 -186.37346) (xy 90.079662 -186.303614) (xy 90.116397 -186.237297) (xy 90.159972 -186.175261)
			(xy 90.209894 -186.118208) (xy 90.265598 -186.066784) (xy 90.326453 -186.021573) (xy 90.391768 -185.983086)
			(xy 90.460804 -185.95176) (xy 90.532779 -185.92795) (xy 90.606877 -185.911925) (xy 90.682258 -185.903866)
			(xy 90.720164 -185.903362) (xy 90.75807 -185.903866) (xy 90.833451 -185.911925) (xy 90.907549 -185.92795)
			(xy 90.979524 -185.95176) (xy 91.04856 -185.983086) (xy 91.113875 -186.021573) (xy 91.17473 -186.066784)
			(xy 91.230434 -186.118208) (xy 91.280356 -186.175261) (xy 91.323931 -186.237297) (xy 91.360666 -186.303614)
			(xy 91.390143 -186.37346) (xy 91.412029 -186.446043) (xy 91.426076 -186.520541) (xy 91.432125 -186.596111)
			(xy 91.430106 -186.671895) (xy 91.420044 -186.747035) (xy 91.402052 -186.82068) (xy 91.376334 -186.891996)
			(xy 91.343182 -186.960173) (xy 91.30297 -187.024441) (xy 91.256155 -187.08407) (xy 91.203267 -187.138386)
			(xy 91.144905 -187.186772) (xy 91.08173 -187.22868) (xy 91.014459 -187.263636) (xy 90.943854 -187.291243)
			(xy 90.870713 -187.311189) (xy 90.795868 -187.323248) (xy 90.720164 -187.327283) (xy 90.64446 -187.323248)
			(xy 90.569615 -187.311189) (xy 90.496474 -187.291243) (xy 90.425869 -187.263636) (xy 90.358598 -187.22868)
			(xy 90.295423 -187.186772) (xy 90.237061 -187.138386) (xy 90.184173 -187.08407) (xy 90.137358 -187.024441)
			(xy 90.097146 -186.960173) (xy 90.063994 -186.891996) (xy 90.038276 -186.82068) (xy 90.020284 -186.747035)
			(xy 90.010222 -186.671895) (xy 90.008203 -186.596111) (xy 88.892125 -186.596111) (xy 88.890106 -186.671895)
			(xy 88.880044 -186.747035) (xy 88.862052 -186.82068) (xy 88.836334 -186.891996) (xy 88.803182 -186.960173)
			(xy 88.76297 -187.024441) (xy 88.716155 -187.08407) (xy 88.663267 -187.138386) (xy 88.604905 -187.186772)
			(xy 88.54173 -187.22868) (xy 88.474459 -187.263636) (xy 88.403854 -187.291243) (xy 88.330713 -187.311189)
			(xy 88.255868 -187.323248) (xy 88.180164 -187.327283) (xy 88.10446 -187.323248) (xy 88.029615 -187.311189)
			(xy 87.956474 -187.291243) (xy 87.885869 -187.263636) (xy 87.818598 -187.22868) (xy 87.755423 -187.186772)
			(xy 87.697061 -187.138386) (xy 87.644173 -187.08407) (xy 87.597358 -187.024441) (xy 87.557146 -186.960173)
			(xy 87.523994 -186.891996) (xy 87.498276 -186.82068) (xy 87.480284 -186.747035) (xy 87.470222 -186.671895)
			(xy 87.468203 -186.596111) (xy 86.352125 -186.596111) (xy 86.350106 -186.671895) (xy 86.340044 -186.747035)
			(xy 86.322052 -186.82068) (xy 86.296334 -186.891996) (xy 86.263182 -186.960173) (xy 86.22297 -187.024441)
			(xy 86.176155 -187.08407) (xy 86.123267 -187.138386) (xy 86.064905 -187.186772) (xy 86.00173 -187.22868)
			(xy 85.934459 -187.263636) (xy 85.863854 -187.291243) (xy 85.790713 -187.311189) (xy 85.715868 -187.323248)
			(xy 85.640164 -187.327283) (xy 85.56446 -187.323248) (xy 85.489615 -187.311189) (xy 85.416474 -187.291243)
			(xy 85.345869 -187.263636) (xy 85.278598 -187.22868) (xy 85.215423 -187.186772) (xy 85.157061 -187.138386)
			(xy 85.104173 -187.08407) (xy 85.057358 -187.024441) (xy 85.017146 -186.960173) (xy 84.983994 -186.891996)
			(xy 84.958276 -186.82068) (xy 84.940284 -186.747035) (xy 84.930222 -186.671895) (xy 84.928203 -186.596111)
			(xy 82.60781 -186.596111) (xy 82.564785 -186.631782) (xy 82.50161 -186.67369) (xy 82.434339 -186.708646)
			(xy 82.363734 -186.736253) (xy 82.290593 -186.756199) (xy 82.215748 -186.768258) (xy 82.140044 -186.772293)
			(xy 82.06434 -186.768258) (xy 81.989495 -186.756199) (xy 81.916354 -186.736253) (xy 81.845749 -186.708646)
			(xy 81.778478 -186.67369) (xy 81.715303 -186.631782) (xy 81.656941 -186.583396) (xy 81.604053 -186.52908)
			(xy 81.557238 -186.469451) (xy 81.517026 -186.405183) (xy 81.483874 -186.337006) (xy 81.458156 -186.26569)
			(xy 81.440164 -186.192045) (xy 81.430102 -186.116905) (xy 81.428083 -186.041121) (xy 80.312005 -186.041121)
			(xy 80.309986 -186.116905) (xy 80.299924 -186.192045) (xy 80.281932 -186.26569) (xy 80.256214 -186.337006)
			(xy 80.223062 -186.405183) (xy 80.18285 -186.469451) (xy 80.136035 -186.52908) (xy 80.083147 -186.583396)
			(xy 80.024785 -186.631782) (xy 79.96161 -186.67369) (xy 79.894339 -186.708646) (xy 79.823734 -186.736253)
			(xy 79.750593 -186.756199) (xy 79.675748 -186.768258) (xy 79.600044 -186.772293) (xy 79.52434 -186.768258)
			(xy 79.449495 -186.756199) (xy 79.376354 -186.736253) (xy 79.305749 -186.708646) (xy 79.238478 -186.67369)
			(xy 79.175303 -186.631782) (xy 79.116941 -186.583396) (xy 79.064053 -186.52908) (xy 79.017238 -186.469451)
			(xy 78.977026 -186.405183) (xy 78.943874 -186.337006) (xy 78.918156 -186.26569) (xy 78.900164 -186.192045)
			(xy 78.890102 -186.116905) (xy 78.888083 -186.041121) (xy 77.772005 -186.041121) (xy 77.769986 -186.116905)
			(xy 77.759924 -186.192045) (xy 77.741932 -186.26569) (xy 77.716214 -186.337006) (xy 77.683062 -186.405183)
			(xy 77.64285 -186.469451) (xy 77.596035 -186.52908) (xy 77.543147 -186.583396) (xy 77.484785 -186.631782)
			(xy 77.42161 -186.67369) (xy 77.354339 -186.708646) (xy 77.283734 -186.736253) (xy 77.210593 -186.756199)
			(xy 77.135748 -186.768258) (xy 77.060044 -186.772293) (xy 76.98434 -186.768258) (xy 76.909495 -186.756199)
			(xy 76.836354 -186.736253) (xy 76.765749 -186.708646) (xy 76.698478 -186.67369) (xy 76.635303 -186.631782)
			(xy 76.576941 -186.583396) (xy 76.524053 -186.52908) (xy 76.477238 -186.469451) (xy 76.437026 -186.405183)
			(xy 76.403874 -186.337006) (xy 76.378156 -186.26569) (xy 76.360164 -186.192045) (xy 76.350102 -186.116905)
			(xy 76.348083 -186.041121) (xy 75.232005 -186.041121) (xy 75.229986 -186.116905) (xy 75.219924 -186.192045)
			(xy 75.201932 -186.26569) (xy 75.176214 -186.337006) (xy 75.143062 -186.405183) (xy 75.10285 -186.469451)
			(xy 75.056035 -186.52908) (xy 75.003147 -186.583396) (xy 74.944785 -186.631782) (xy 74.88161 -186.67369)
			(xy 74.814339 -186.708646) (xy 74.743734 -186.736253) (xy 74.670593 -186.756199) (xy 74.595748 -186.768258)
			(xy 74.520044 -186.772293) (xy 74.44434 -186.768258) (xy 74.369495 -186.756199) (xy 74.296354 -186.736253)
			(xy 74.225749 -186.708646) (xy 74.158478 -186.67369) (xy 74.095303 -186.631782) (xy 74.036941 -186.583396)
			(xy 73.984053 -186.52908) (xy 73.937238 -186.469451) (xy 73.897026 -186.405183) (xy 73.863874 -186.337006)
			(xy 73.838156 -186.26569) (xy 73.820164 -186.192045) (xy 73.810102 -186.116905) (xy 73.808083 -186.041121)
			(xy 72.692005 -186.041121) (xy 72.689986 -186.116905) (xy 72.679924 -186.192045) (xy 72.661932 -186.26569)
			(xy 72.636214 -186.337006) (xy 72.603062 -186.405183) (xy 72.56285 -186.469451) (xy 72.516035 -186.52908)
			(xy 72.463147 -186.583396) (xy 72.404785 -186.631782) (xy 72.34161 -186.67369) (xy 72.274339 -186.708646)
			(xy 72.203734 -186.736253) (xy 72.130593 -186.756199) (xy 72.055748 -186.768258) (xy 71.980044 -186.772293)
			(xy 71.90434 -186.768258) (xy 71.829495 -186.756199) (xy 71.756354 -186.736253) (xy 71.685749 -186.708646)
			(xy 71.618478 -186.67369) (xy 71.555303 -186.631782) (xy 71.496941 -186.583396) (xy 71.444053 -186.52908)
			(xy 71.397238 -186.469451) (xy 71.357026 -186.405183) (xy 71.323874 -186.337006) (xy 71.298156 -186.26569)
			(xy 71.280164 -186.192045) (xy 71.270102 -186.116905) (xy 71.268083 -186.041121) (xy 70.152005 -186.041121)
			(xy 70.149986 -186.116905) (xy 70.139924 -186.192045) (xy 70.121932 -186.26569) (xy 70.096214 -186.337006)
			(xy 70.063062 -186.405183) (xy 70.02285 -186.469451) (xy 69.976035 -186.52908) (xy 69.923147 -186.583396)
			(xy 69.864785 -186.631782) (xy 69.80161 -186.67369) (xy 69.734339 -186.708646) (xy 69.663734 -186.736253)
			(xy 69.590593 -186.756199) (xy 69.515748 -186.768258) (xy 69.440044 -186.772293) (xy 69.36434 -186.768258)
			(xy 69.289495 -186.756199) (xy 69.216354 -186.736253) (xy 69.145749 -186.708646) (xy 69.078478 -186.67369)
			(xy 69.015303 -186.631782) (xy 68.956941 -186.583396) (xy 68.904053 -186.52908) (xy 68.857238 -186.469451)
			(xy 68.817026 -186.405183) (xy 68.783874 -186.337006) (xy 68.758156 -186.26569) (xy 68.740164 -186.192045)
			(xy 68.730102 -186.116905) (xy 68.728083 -186.041121) (xy 67.612005 -186.041121) (xy 67.609986 -186.116905)
			(xy 67.599924 -186.192045) (xy 67.581932 -186.26569) (xy 67.556214 -186.337006) (xy 67.523062 -186.405183)
			(xy 67.48285 -186.469451) (xy 67.436035 -186.52908) (xy 67.383147 -186.583396) (xy 67.324785 -186.631782)
			(xy 67.26161 -186.67369) (xy 67.194339 -186.708646) (xy 67.123734 -186.736253) (xy 67.050593 -186.756199)
			(xy 66.975748 -186.768258) (xy 66.900044 -186.772293) (xy 66.82434 -186.768258) (xy 66.749495 -186.756199)
			(xy 66.676354 -186.736253) (xy 66.605749 -186.708646) (xy 66.538478 -186.67369) (xy 66.475303 -186.631782)
			(xy 66.416941 -186.583396) (xy 66.364053 -186.52908) (xy 66.317238 -186.469451) (xy 66.277026 -186.405183)
			(xy 66.243874 -186.337006) (xy 66.218156 -186.26569) (xy 66.200164 -186.192045) (xy 66.190102 -186.116905)
			(xy 66.188083 -186.041121) (xy 65.072005 -186.041121) (xy 65.069986 -186.116905) (xy 65.059924 -186.192045)
			(xy 65.041932 -186.26569) (xy 65.016214 -186.337006) (xy 64.983062 -186.405183) (xy 64.94285 -186.469451)
			(xy 64.896035 -186.52908) (xy 64.843147 -186.583396) (xy 64.784785 -186.631782) (xy 64.72161 -186.67369)
			(xy 64.654339 -186.708646) (xy 64.583734 -186.736253) (xy 64.510593 -186.756199) (xy 64.435748 -186.768258)
			(xy 64.360044 -186.772293) (xy 64.28434 -186.768258) (xy 64.209495 -186.756199) (xy 64.136354 -186.736253)
			(xy 64.065749 -186.708646) (xy 63.998478 -186.67369) (xy 63.935303 -186.631782) (xy 63.876941 -186.583396)
			(xy 63.824053 -186.52908) (xy 63.777238 -186.469451) (xy 63.737026 -186.405183) (xy 63.703874 -186.337006)
			(xy 63.678156 -186.26569) (xy 63.660164 -186.192045) (xy 63.650102 -186.116905) (xy 63.648083 -186.041121)
			(xy 42.526889 -186.041121) (xy 42.438817 -186.104916) (xy 42.340321 -186.166369) (xy 42.237819 -186.220879)
			(xy 42.1318 -186.268186) (xy 42.02277 -186.308064) (xy 41.911247 -186.340324) (xy 41.797764 -186.364811)
			(xy 41.682862 -186.381409) (xy 41.625012 -186.386216) (xy 41.602806 -186.388364) (xy 41.559594 -186.399445)
			(xy 41.518979 -186.417896) (xy 41.482207 -186.443154) (xy 41.450408 -186.474441) (xy 41.424558 -186.510797)
			(xy 41.405449 -186.551108) (xy 41.393669 -186.594134) (xy 41.389579 -186.638556) (xy 41.393305 -186.683011)
			(xy 41.404732 -186.726132) (xy 41.423509 -186.766598) (xy 41.449061 -186.803165) (xy 41.464484 -186.819286)
			(xy 45.51426 -190.869062) (xy 45.51426 -191.750289) (xy 58.80404 -191.750289) (xy 58.80404 -191.678967)
			(xy 58.812026 -191.608093) (xy 58.827896 -191.538558) (xy 58.851453 -191.471238) (xy 58.882398 -191.406979)
			(xy 58.920344 -191.346588) (xy 58.964813 -191.290826) (xy 59.015246 -191.240393) (xy 59.071008 -191.195924)
			(xy 59.131399 -191.157978) (xy 59.195658 -191.127033) (xy 59.262978 -191.103476) (xy 59.332513 -191.087606)
			(xy 59.403387 -191.07962) (xy 59.439048 -191.07912) (xy 59.474709 -191.07962) (xy 59.545583 -191.087606)
			(xy 59.615118 -191.103476) (xy 59.682438 -191.127033) (xy 59.746697 -191.157978) (xy 59.807088 -191.195924)
			(xy 59.86285 -191.240393) (xy 59.913283 -191.290826) (xy 59.957752 -191.346588) (xy 59.995698 -191.406979)
			(xy 60.026643 -191.471238) (xy 60.0502 -191.538558) (xy 60.06607 -191.608093) (xy 60.074056 -191.678967)
			(xy 60.074056 -191.750289) (xy 61.335912 -191.750289) (xy 61.335912 -191.678967) (xy 61.343898 -191.608093)
			(xy 61.359768 -191.538558) (xy 61.383325 -191.471238) (xy 61.41427 -191.406979) (xy 61.452216 -191.346588)
			(xy 61.496685 -191.290826) (xy 61.547118 -191.240393) (xy 61.60288 -191.195924) (xy 61.663271 -191.157978)
			(xy 61.72753 -191.127033) (xy 61.79485 -191.103476) (xy 61.864385 -191.087606) (xy 61.935259 -191.07962)
			(xy 61.97092 -191.07912) (xy 62.006581 -191.07962) (xy 62.077455 -191.087606) (xy 62.14699 -191.103476)
			(xy 62.21431 -191.127033) (xy 62.278569 -191.157978) (xy 62.33896 -191.195924) (xy 62.394722 -191.240393)
			(xy 62.445155 -191.290826) (xy 62.489624 -191.346588) (xy 62.52757 -191.406979) (xy 62.558515 -191.471238)
			(xy 62.582072 -191.538558) (xy 62.597942 -191.608093) (xy 62.605928 -191.678967) (xy 62.605928 -191.750289)
			(xy 64.140326 -191.750289) (xy 64.140326 -191.678967) (xy 64.148312 -191.608093) (xy 64.164182 -191.538558)
			(xy 64.187739 -191.471238) (xy 64.218684 -191.406979) (xy 64.25663 -191.346588) (xy 64.301099 -191.290826)
			(xy 64.351532 -191.240393) (xy 64.407294 -191.195924) (xy 64.467685 -191.157978) (xy 64.531944 -191.127033)
			(xy 64.599264 -191.103476) (xy 64.668799 -191.087606) (xy 64.739673 -191.07962) (xy 64.775334 -191.07912)
			(xy 64.810995 -191.07962) (xy 64.881869 -191.087606) (xy 64.951404 -191.103476) (xy 65.018724 -191.127033)
			(xy 65.082983 -191.157978) (xy 65.143374 -191.195924) (xy 65.199136 -191.240393) (xy 65.242329 -191.283586)
			(xy 83.761054 -191.283586) (xy 83.761054 -191.22365) (xy 83.768877 -191.164228) (xy 83.78439 -191.106335)
			(xy 83.807326 -191.050962) (xy 83.837293 -190.999056) (xy 83.87378 -190.951506) (xy 83.91616 -190.909126)
			(xy 83.96371 -190.872639) (xy 84.015616 -190.842672) (xy 84.070989 -190.819736) (xy 84.128882 -190.804223)
			(xy 84.188304 -190.7964) (xy 84.218272 -190.79591) (xy 84.24824 -190.7964) (xy 84.307662 -190.804223)
			(xy 84.365555 -190.819736) (xy 84.420928 -190.842672) (xy 84.472834 -190.872639) (xy 84.520384 -190.909126)
			(xy 84.562764 -190.951506) (xy 84.599251 -190.999056) (xy 84.629218 -191.050962) (xy 84.652154 -191.106335)
			(xy 84.667667 -191.164228) (xy 84.67549 -191.22365) (xy 84.67549 -191.256154) (xy 85.65183 -191.256154)
			(xy 85.65183 -191.196218) (xy 85.659653 -191.136796) (xy 85.675166 -191.078903) (xy 85.698102 -191.02353)
			(xy 85.728069 -190.971624) (xy 85.764556 -190.924074) (xy 85.806936 -190.881694) (xy 85.854486 -190.845207)
			(xy 85.906392 -190.81524) (xy 85.961765 -190.792304) (xy 86.019658 -190.776791) (xy 86.07908 -190.768968)
			(xy 86.109048 -190.768478) (xy 86.139016 -190.768968) (xy 86.198438 -190.776791) (xy 86.256331 -190.792304)
			(xy 86.311704 -190.81524) (xy 86.36361 -190.845207) (xy 86.41116 -190.881694) (xy 86.45354 -190.924074)
			(xy 86.490027 -190.971624) (xy 86.500321 -190.989454) (xy 86.946468 -190.989454) (xy 86.946468 -190.929518)
			(xy 86.954291 -190.870096) (xy 86.969804 -190.812203) (xy 86.99274 -190.75683) (xy 87.022707 -190.704924)
			(xy 87.059194 -190.657374) (xy 87.101574 -190.614994) (xy 87.149124 -190.578507) (xy 87.20103 -190.54854)
			(xy 87.256403 -190.525604) (xy 87.314296 -190.510091) (xy 87.373718 -190.502268) (xy 87.403686 -190.501778)
			(xy 87.433654 -190.502268) (xy 87.493076 -190.510091) (xy 87.550969 -190.525604) (xy 87.606342 -190.54854)
			(xy 87.658248 -190.578507) (xy 87.705798 -190.614994) (xy 87.748178 -190.657374) (xy 87.784665 -190.704924)
			(xy 87.814632 -190.75683) (xy 87.837568 -190.812203) (xy 87.853081 -190.870096) (xy 87.860904 -190.929518)
			(xy 87.860904 -190.989454) (xy 87.853081 -191.048876) (xy 87.837568 -191.106769) (xy 87.814632 -191.162142)
			(xy 87.784665 -191.214048) (xy 87.767168 -191.23685) (xy 91.63734 -191.23685) (xy 91.63734 -191.176914)
			(xy 91.645163 -191.117492) (xy 91.660676 -191.059599) (xy 91.683612 -191.004226) (xy 91.713579 -190.95232)
			(xy 91.750066 -190.90477) (xy 91.792446 -190.86239) (xy 91.839996 -190.825903) (xy 91.891902 -190.795936)
			(xy 91.947275 -190.773) (xy 92.005168 -190.757487) (xy 92.06459 -190.749664) (xy 92.094558 -190.749174)
			(xy 92.124526 -190.749664) (xy 92.183948 -190.757487) (xy 92.241841 -190.773) (xy 92.297214 -190.795936)
			(xy 92.34912 -190.825903) (xy 92.39667 -190.86239) (xy 92.43905 -190.90477) (xy 92.475537 -190.95232)
			(xy 92.505504 -191.004226) (xy 92.52844 -191.059599) (xy 92.543953 -191.117492) (xy 92.551776 -191.176914)
			(xy 92.551776 -191.23685) (xy 92.543953 -191.296272) (xy 92.52844 -191.354165) (xy 92.505504 -191.409538)
			(xy 92.475537 -191.461444) (xy 92.43905 -191.508994) (xy 92.39667 -191.551374) (xy 92.34912 -191.587861)
			(xy 92.297214 -191.617828) (xy 92.241841 -191.640764) (xy 92.183948 -191.656277) (xy 92.124526 -191.6641)
			(xy 92.06459 -191.6641) (xy 92.005168 -191.656277) (xy 91.947275 -191.640764) (xy 91.891902 -191.617828)
			(xy 91.839996 -191.587861) (xy 91.792446 -191.551374) (xy 91.750066 -191.508994) (xy 91.713579 -191.461444)
			(xy 91.683612 -191.409538) (xy 91.660676 -191.354165) (xy 91.645163 -191.296272) (xy 91.63734 -191.23685)
			(xy 87.767168 -191.23685) (xy 87.748178 -191.261598) (xy 87.705798 -191.303978) (xy 87.658248 -191.340465)
			(xy 87.606342 -191.370432) (xy 87.550969 -191.393368) (xy 87.493076 -191.408881) (xy 87.433654 -191.416704)
			(xy 87.373718 -191.416704) (xy 87.314296 -191.408881) (xy 87.256403 -191.393368) (xy 87.20103 -191.370432)
			(xy 87.149124 -191.340465) (xy 87.101574 -191.303978) (xy 87.059194 -191.261598) (xy 87.022707 -191.214048)
			(xy 86.99274 -191.162142) (xy 86.969804 -191.106769) (xy 86.954291 -191.048876) (xy 86.946468 -190.989454)
			(xy 86.500321 -190.989454) (xy 86.519994 -191.02353) (xy 86.54293 -191.078903) (xy 86.558443 -191.136796)
			(xy 86.566266 -191.196218) (xy 86.566266 -191.256154) (xy 86.558443 -191.315576) (xy 86.54293 -191.373469)
			(xy 86.519994 -191.428842) (xy 86.490027 -191.480748) (xy 86.45354 -191.528298) (xy 86.41116 -191.570678)
			(xy 86.36361 -191.607165) (xy 86.311704 -191.637132) (xy 86.256331 -191.660068) (xy 86.198438 -191.675581)
			(xy 86.139016 -191.683404) (xy 86.07908 -191.683404) (xy 86.019658 -191.675581) (xy 85.961765 -191.660068)
			(xy 85.906392 -191.637132) (xy 85.854486 -191.607165) (xy 85.806936 -191.570678) (xy 85.764556 -191.528298)
			(xy 85.728069 -191.480748) (xy 85.698102 -191.428842) (xy 85.675166 -191.373469) (xy 85.659653 -191.315576)
			(xy 85.65183 -191.256154) (xy 84.67549 -191.256154) (xy 84.67549 -191.283586) (xy 84.667667 -191.343008)
			(xy 84.652154 -191.400901) (xy 84.629218 -191.456274) (xy 84.599251 -191.50818) (xy 84.562764 -191.55573)
			(xy 84.520384 -191.59811) (xy 84.472834 -191.634597) (xy 84.420928 -191.664564) (xy 84.365555 -191.6875)
			(xy 84.307662 -191.703013) (xy 84.24824 -191.710836) (xy 84.188304 -191.710836) (xy 84.128882 -191.703013)
			(xy 84.070989 -191.6875) (xy 84.015616 -191.664564) (xy 83.96371 -191.634597) (xy 83.91616 -191.59811)
			(xy 83.87378 -191.55573) (xy 83.837293 -191.50818) (xy 83.807326 -191.456274) (xy 83.78439 -191.400901)
			(xy 83.768877 -191.343008) (xy 83.761054 -191.283586) (xy 65.242329 -191.283586) (xy 65.249569 -191.290826)
			(xy 65.294038 -191.346588) (xy 65.331984 -191.406979) (xy 65.362929 -191.471238) (xy 65.386486 -191.538558)
			(xy 65.402356 -191.608093) (xy 65.410342 -191.678967) (xy 65.410342 -191.73596) (xy 95.212898 -191.73596)
			(xy 95.212898 -191.676024) (xy 95.220721 -191.616602) (xy 95.236234 -191.558709) (xy 95.25917 -191.503336)
			(xy 95.289137 -191.45143) (xy 95.325624 -191.40388) (xy 95.368004 -191.3615) (xy 95.415554 -191.325013)
			(xy 95.46746 -191.295046) (xy 95.522833 -191.27211) (xy 95.580726 -191.256597) (xy 95.640148 -191.248774)
			(xy 95.670116 -191.248284) (xy 95.700084 -191.248774) (xy 95.759506 -191.256597) (xy 95.817399 -191.27211)
			(xy 95.872772 -191.295046) (xy 95.924678 -191.325013) (xy 95.972228 -191.3615) (xy 96.014608 -191.40388)
			(xy 96.051095 -191.45143) (xy 96.081062 -191.503336) (xy 96.103998 -191.558709) (xy 96.119511 -191.616602)
			(xy 96.127334 -191.676024) (xy 96.127334 -191.73596) (xy 96.119511 -191.795382) (xy 96.103998 -191.853275)
			(xy 96.081062 -191.908648) (xy 96.051095 -191.960554) (xy 96.014608 -192.008104) (xy 95.972228 -192.050484)
			(xy 95.924678 -192.086971) (xy 95.872772 -192.116938) (xy 95.817399 -192.139874) (xy 95.759506 -192.155387)
			(xy 95.700084 -192.16321) (xy 95.640148 -192.16321) (xy 95.580726 -192.155387) (xy 95.522833 -192.139874)
			(xy 95.46746 -192.116938) (xy 95.415554 -192.086971) (xy 95.368004 -192.050484) (xy 95.325624 -192.008104)
			(xy 95.289137 -191.960554) (xy 95.25917 -191.908648) (xy 95.236234 -191.853275) (xy 95.220721 -191.795382)
			(xy 95.212898 -191.73596) (xy 65.410342 -191.73596) (xy 65.410342 -191.750289) (xy 65.402356 -191.821163)
			(xy 65.386486 -191.890698) (xy 65.362929 -191.958018) (xy 65.331984 -192.022277) (xy 65.294038 -192.082668)
			(xy 65.249569 -192.13843) (xy 65.199136 -192.188863) (xy 65.143374 -192.233332) (xy 65.082983 -192.271278)
			(xy 65.018724 -192.302223) (xy 64.951404 -192.32578) (xy 64.881869 -192.34165) (xy 64.810995 -192.349636)
			(xy 64.739673 -192.349636) (xy 64.668799 -192.34165) (xy 64.599264 -192.32578) (xy 64.531944 -192.302223)
			(xy 64.467685 -192.271278) (xy 64.407294 -192.233332) (xy 64.351532 -192.188863) (xy 64.301099 -192.13843)
			(xy 64.25663 -192.082668) (xy 64.218684 -192.022277) (xy 64.187739 -191.958018) (xy 64.164182 -191.890698)
			(xy 64.148312 -191.821163) (xy 64.140326 -191.750289) (xy 62.605928 -191.750289) (xy 62.597942 -191.821163)
			(xy 62.582072 -191.890698) (xy 62.558515 -191.958018) (xy 62.52757 -192.022277) (xy 62.489624 -192.082668)
			(xy 62.445155 -192.13843) (xy 62.394722 -192.188863) (xy 62.33896 -192.233332) (xy 62.278569 -192.271278)
			(xy 62.21431 -192.302223) (xy 62.14699 -192.32578) (xy 62.077455 -192.34165) (xy 62.006581 -192.349636)
			(xy 61.935259 -192.349636) (xy 61.864385 -192.34165) (xy 61.79485 -192.32578) (xy 61.72753 -192.302223)
			(xy 61.663271 -192.271278) (xy 61.60288 -192.233332) (xy 61.547118 -192.188863) (xy 61.496685 -192.13843)
			(xy 61.452216 -192.082668) (xy 61.41427 -192.022277) (xy 61.383325 -191.958018) (xy 61.359768 -191.890698)
			(xy 61.343898 -191.821163) (xy 61.335912 -191.750289) (xy 60.074056 -191.750289) (xy 60.06607 -191.821163)
			(xy 60.0502 -191.890698) (xy 60.026643 -191.958018) (xy 59.995698 -192.022277) (xy 59.957752 -192.082668)
			(xy 59.913283 -192.13843) (xy 59.86285 -192.188863) (xy 59.807088 -192.233332) (xy 59.746697 -192.271278)
			(xy 59.682438 -192.302223) (xy 59.615118 -192.32578) (xy 59.545583 -192.34165) (xy 59.474709 -192.349636)
			(xy 59.403387 -192.349636) (xy 59.332513 -192.34165) (xy 59.262978 -192.32578) (xy 59.195658 -192.302223)
			(xy 59.131399 -192.271278) (xy 59.071008 -192.233332) (xy 59.015246 -192.188863) (xy 58.964813 -192.13843)
			(xy 58.920344 -192.082668) (xy 58.882398 -192.022277) (xy 58.851453 -191.958018) (xy 58.827896 -191.890698)
			(xy 58.812026 -191.821163) (xy 58.80404 -191.750289) (xy 45.51426 -191.750289) (xy 45.51426 -192.567048)
			(xy 82.733878 -192.567048) (xy 82.733878 -192.507112) (xy 82.741701 -192.44769) (xy 82.757214 -192.389797)
			(xy 82.78015 -192.334424) (xy 82.810117 -192.282518) (xy 82.846604 -192.234968) (xy 82.888984 -192.192588)
			(xy 82.936534 -192.156101) (xy 82.98844 -192.126134) (xy 83.043813 -192.103198) (xy 83.101706 -192.087685)
			(xy 83.161128 -192.079862) (xy 83.191096 -192.079372) (xy 83.221064 -192.079862) (xy 83.280486 -192.087685)
			(xy 83.338379 -192.103198) (xy 83.393752 -192.126134) (xy 83.445658 -192.156101) (xy 83.493208 -192.192588)
			(xy 83.535588 -192.234968) (xy 83.572075 -192.282518) (xy 83.602042 -192.334424) (xy 83.624978 -192.389797)
			(xy 83.640491 -192.44769) (xy 83.648314 -192.507112) (xy 83.648314 -192.567048) (xy 83.640491 -192.62647)
			(xy 83.624978 -192.684363) (xy 83.613812 -192.71132) (xy 84.381322 -192.71132) (xy 84.381322 -192.651384)
			(xy 84.389145 -192.591962) (xy 84.404658 -192.534069) (xy 84.427594 -192.478696) (xy 84.457561 -192.42679)
			(xy 84.494048 -192.37924) (xy 84.536428 -192.33686) (xy 84.583978 -192.300373) (xy 84.635884 -192.270406)
			(xy 84.691257 -192.24747) (xy 84.74915 -192.231957) (xy 84.808572 -192.224134) (xy 84.83854 -192.223644)
			(xy 84.868508 -192.224134) (xy 84.92793 -192.231957) (xy 84.985823 -192.24747) (xy 85.041196 -192.270406)
			(xy 85.093102 -192.300373) (xy 85.140652 -192.33686) (xy 85.183032 -192.37924) (xy 85.219519 -192.42679)
			(xy 85.249486 -192.478696) (xy 85.272422 -192.534069) (xy 85.287935 -192.591962) (xy 85.295758 -192.651384)
			(xy 85.295758 -192.71132) (xy 85.287935 -192.770742) (xy 85.272422 -192.828635) (xy 85.249486 -192.884008)
			(xy 85.219519 -192.935914) (xy 85.183032 -192.983464) (xy 85.140652 -193.025844) (xy 85.093102 -193.062331)
			(xy 85.041196 -193.092298) (xy 84.985823 -193.115234) (xy 84.92793 -193.130747) (xy 84.868508 -193.13857)
			(xy 84.808572 -193.13857) (xy 84.74915 -193.130747) (xy 84.691257 -193.115234) (xy 84.635884 -193.092298)
			(xy 84.583978 -193.062331) (xy 84.536428 -193.025844) (xy 84.494048 -192.983464) (xy 84.457561 -192.935914)
			(xy 84.427594 -192.884008) (xy 84.404658 -192.828635) (xy 84.389145 -192.770742) (xy 84.381322 -192.71132)
			(xy 83.613812 -192.71132) (xy 83.602042 -192.739736) (xy 83.572075 -192.791642) (xy 83.535588 -192.839192)
			(xy 83.493208 -192.881572) (xy 83.445658 -192.918059) (xy 83.393752 -192.948026) (xy 83.338379 -192.970962)
			(xy 83.280486 -192.986475) (xy 83.221064 -192.994298) (xy 83.161128 -192.994298) (xy 83.101706 -192.986475)
			(xy 83.043813 -192.970962) (xy 82.98844 -192.948026) (xy 82.936534 -192.918059) (xy 82.888984 -192.881572)
			(xy 82.846604 -192.839192) (xy 82.810117 -192.791642) (xy 82.78015 -192.739736) (xy 82.757214 -192.684363)
			(xy 82.741701 -192.62647) (xy 82.733878 -192.567048) (xy 45.51426 -192.567048) (xy 45.51426 -193.713201)
			(xy 58.80404 -193.713201) (xy 58.80404 -193.641879) (xy 58.812026 -193.571005) (xy 58.827896 -193.50147)
			(xy 58.851453 -193.43415) (xy 58.882398 -193.369891) (xy 58.920344 -193.3095) (xy 58.964813 -193.253738)
			(xy 59.015246 -193.203305) (xy 59.071008 -193.158836) (xy 59.131399 -193.12089) (xy 59.195658 -193.089945)
			(xy 59.262978 -193.066388) (xy 59.332513 -193.050518) (xy 59.403387 -193.042532) (xy 59.439048 -193.042032)
			(xy 59.474709 -193.042532) (xy 59.545583 -193.050518) (xy 59.615118 -193.066388) (xy 59.682438 -193.089945)
			(xy 59.746697 -193.12089) (xy 59.807088 -193.158836) (xy 59.86285 -193.203305) (xy 59.913283 -193.253738)
			(xy 59.957752 -193.3095) (xy 59.995698 -193.369891) (xy 60.026643 -193.43415) (xy 60.0502 -193.50147)
			(xy 60.06607 -193.571005) (xy 60.074056 -193.641879) (xy 60.074056 -193.713201) (xy 61.335912 -193.713201)
			(xy 61.335912 -193.641879) (xy 61.343898 -193.571005) (xy 61.359768 -193.50147) (xy 61.383325 -193.43415)
			(xy 61.41427 -193.369891) (xy 61.452216 -193.3095) (xy 61.496685 -193.253738) (xy 61.547118 -193.203305)
			(xy 61.60288 -193.158836) (xy 61.663271 -193.12089) (xy 61.72753 -193.089945) (xy 61.79485 -193.066388)
			(xy 61.864385 -193.050518) (xy 61.935259 -193.042532) (xy 61.97092 -193.042032) (xy 62.006581 -193.042532)
			(xy 62.077455 -193.050518) (xy 62.14699 -193.066388) (xy 62.21431 -193.089945) (xy 62.278569 -193.12089)
			(xy 62.33896 -193.158836) (xy 62.394722 -193.203305) (xy 62.445155 -193.253738) (xy 62.489624 -193.3095)
			(xy 62.52757 -193.369891) (xy 62.558515 -193.43415) (xy 62.582072 -193.50147) (xy 62.597942 -193.571005)
			(xy 62.605928 -193.641879) (xy 62.605928 -193.713201) (xy 64.140326 -193.713201) (xy 64.140326 -193.641879)
			(xy 64.148312 -193.571005) (xy 64.164182 -193.50147) (xy 64.187739 -193.43415) (xy 64.218684 -193.369891)
			(xy 64.25663 -193.3095) (xy 64.301099 -193.253738) (xy 64.351532 -193.203305) (xy 64.407294 -193.158836)
			(xy 64.467685 -193.12089) (xy 64.531944 -193.089945) (xy 64.599264 -193.066388) (xy 64.668799 -193.050518)
			(xy 64.739673 -193.042532) (xy 64.775334 -193.042032) (xy 64.810995 -193.042532) (xy 64.881869 -193.050518)
			(xy 64.951404 -193.066388) (xy 65.018724 -193.089945) (xy 65.082983 -193.12089) (xy 65.143374 -193.158836)
			(xy 65.199136 -193.203305) (xy 65.249569 -193.253738) (xy 65.294038 -193.3095) (xy 65.331984 -193.369891)
			(xy 65.362929 -193.43415) (xy 65.386486 -193.50147) (xy 65.402356 -193.571005) (xy 65.410342 -193.641879)
			(xy 65.410342 -193.713201) (xy 65.405746 -193.75399) (xy 83.194126 -193.75399) (xy 83.194126 -193.694054)
			(xy 83.201949 -193.634632) (xy 83.217462 -193.576739) (xy 83.240398 -193.521366) (xy 83.270365 -193.46946)
			(xy 83.306852 -193.42191) (xy 83.349232 -193.37953) (xy 83.396782 -193.343043) (xy 83.448688 -193.313076)
			(xy 83.504061 -193.29014) (xy 83.561954 -193.274627) (xy 83.621376 -193.266804) (xy 83.651344 -193.266314)
			(xy 83.681312 -193.266804) (xy 83.740734 -193.274627) (xy 83.798627 -193.29014) (xy 83.854 -193.313076)
			(xy 83.905906 -193.343043) (xy 83.953456 -193.37953) (xy 83.995836 -193.42191) (xy 84.032323 -193.46946)
			(xy 84.06229 -193.521366) (xy 84.085226 -193.576739) (xy 84.100739 -193.634632) (xy 84.108562 -193.694054)
			(xy 84.108562 -193.75399) (xy 84.100739 -193.813412) (xy 84.085226 -193.871305) (xy 84.06229 -193.926678)
			(xy 84.032323 -193.978584) (xy 83.995836 -194.026134) (xy 83.953456 -194.068514) (xy 83.905906 -194.105001)
			(xy 83.854 -194.134968) (xy 83.798627 -194.157904) (xy 83.740734 -194.173417) (xy 83.681312 -194.18124)
			(xy 83.621376 -194.18124) (xy 83.561954 -194.173417) (xy 83.504061 -194.157904) (xy 83.448688 -194.134968)
			(xy 83.396782 -194.105001) (xy 83.349232 -194.068514) (xy 83.306852 -194.026134) (xy 83.270365 -193.978584)
			(xy 83.240398 -193.926678) (xy 83.217462 -193.871305) (xy 83.201949 -193.813412) (xy 83.194126 -193.75399)
			(xy 65.405746 -193.75399) (xy 65.402356 -193.784075) (xy 65.386486 -193.85361) (xy 65.362929 -193.92093)
			(xy 65.331984 -193.985189) (xy 65.294038 -194.04558) (xy 65.249569 -194.101342) (xy 65.199136 -194.151775)
			(xy 65.143374 -194.196244) (xy 65.082983 -194.23419) (xy 65.018724 -194.265135) (xy 64.951404 -194.288692)
			(xy 64.881869 -194.304562) (xy 64.810995 -194.312548) (xy 64.739673 -194.312548) (xy 64.668799 -194.304562)
			(xy 64.599264 -194.288692) (xy 64.531944 -194.265135) (xy 64.467685 -194.23419) (xy 64.407294 -194.196244)
			(xy 64.351532 -194.151775) (xy 64.301099 -194.101342) (xy 64.25663 -194.04558) (xy 64.218684 -193.985189)
			(xy 64.187739 -193.92093) (xy 64.164182 -193.85361) (xy 64.148312 -193.784075) (xy 64.140326 -193.713201)
			(xy 62.605928 -193.713201) (xy 62.597942 -193.784075) (xy 62.582072 -193.85361) (xy 62.558515 -193.92093)
			(xy 62.52757 -193.985189) (xy 62.489624 -194.04558) (xy 62.445155 -194.101342) (xy 62.394722 -194.151775)
			(xy 62.33896 -194.196244) (xy 62.278569 -194.23419) (xy 62.21431 -194.265135) (xy 62.14699 -194.288692)
			(xy 62.077455 -194.304562) (xy 62.006581 -194.312548) (xy 61.935259 -194.312548) (xy 61.864385 -194.304562)
			(xy 61.79485 -194.288692) (xy 61.72753 -194.265135) (xy 61.663271 -194.23419) (xy 61.60288 -194.196244)
			(xy 61.547118 -194.151775) (xy 61.496685 -194.101342) (xy 61.452216 -194.04558) (xy 61.41427 -193.985189)
			(xy 61.383325 -193.92093) (xy 61.359768 -193.85361) (xy 61.343898 -193.784075) (xy 61.335912 -193.713201)
			(xy 60.074056 -193.713201) (xy 60.06607 -193.784075) (xy 60.0502 -193.85361) (xy 60.026643 -193.92093)
			(xy 59.995698 -193.985189) (xy 59.957752 -194.04558) (xy 59.913283 -194.101342) (xy 59.86285 -194.151775)
			(xy 59.807088 -194.196244) (xy 59.746697 -194.23419) (xy 59.682438 -194.265135) (xy 59.615118 -194.288692)
			(xy 59.545583 -194.304562) (xy 59.474709 -194.312548) (xy 59.403387 -194.312548) (xy 59.332513 -194.304562)
			(xy 59.262978 -194.288692) (xy 59.195658 -194.265135) (xy 59.131399 -194.23419) (xy 59.071008 -194.196244)
			(xy 59.015246 -194.151775) (xy 58.964813 -194.101342) (xy 58.920344 -194.04558) (xy 58.882398 -193.985189)
			(xy 58.851453 -193.92093) (xy 58.827896 -193.85361) (xy 58.812026 -193.784075) (xy 58.80404 -193.713201)
			(xy 45.51426 -193.713201) (xy 45.51426 -195.856707) (xy 58.80404 -195.856707) (xy 58.80404 -195.785385)
			(xy 58.812026 -195.714511) (xy 58.827896 -195.644976) (xy 58.851453 -195.577656) (xy 58.882398 -195.513397)
			(xy 58.920344 -195.453006) (xy 58.964813 -195.397244) (xy 59.015246 -195.346811) (xy 59.071008 -195.302342)
			(xy 59.131399 -195.264396) (xy 59.195658 -195.233451) (xy 59.262978 -195.209894) (xy 59.332513 -195.194024)
			(xy 59.403387 -195.186038) (xy 59.439048 -195.185538) (xy 59.474709 -195.186038) (xy 59.545583 -195.194024)
			(xy 59.615118 -195.209894) (xy 59.682438 -195.233451) (xy 59.746697 -195.264396) (xy 59.807088 -195.302342)
			(xy 59.86285 -195.346811) (xy 59.913283 -195.397244) (xy 59.957752 -195.453006) (xy 59.995698 -195.513397)
			(xy 60.026643 -195.577656) (xy 60.0502 -195.644976) (xy 60.06607 -195.714511) (xy 60.074056 -195.785385)
			(xy 60.074056 -195.856707) (xy 61.335912 -195.856707) (xy 61.335912 -195.785385) (xy 61.343898 -195.714511)
			(xy 61.359768 -195.644976) (xy 61.383325 -195.577656) (xy 61.41427 -195.513397) (xy 61.452216 -195.453006)
			(xy 61.496685 -195.397244) (xy 61.547118 -195.346811) (xy 61.60288 -195.302342) (xy 61.663271 -195.264396)
			(xy 61.72753 -195.233451) (xy 61.79485 -195.209894) (xy 61.864385 -195.194024) (xy 61.935259 -195.186038)
			(xy 61.97092 -195.185538) (xy 62.006581 -195.186038) (xy 62.077455 -195.194024) (xy 62.14699 -195.209894)
			(xy 62.21431 -195.233451) (xy 62.278569 -195.264396) (xy 62.33896 -195.302342) (xy 62.394722 -195.346811)
			(xy 62.445155 -195.397244) (xy 62.489624 -195.453006) (xy 62.52757 -195.513397) (xy 62.558515 -195.577656)
			(xy 62.582072 -195.644976) (xy 62.597942 -195.714511) (xy 62.605928 -195.785385) (xy 62.605928 -195.856707)
			(xy 64.140326 -195.856707) (xy 64.140326 -195.785385) (xy 64.148312 -195.714511) (xy 64.164182 -195.644976)
			(xy 64.187739 -195.577656) (xy 64.218684 -195.513397) (xy 64.25663 -195.453006) (xy 64.301099 -195.397244)
			(xy 64.351532 -195.346811) (xy 64.407294 -195.302342) (xy 64.467685 -195.264396) (xy 64.531944 -195.233451)
			(xy 64.599264 -195.209894) (xy 64.668799 -195.194024) (xy 64.739673 -195.186038) (xy 64.775334 -195.185538)
			(xy 64.810995 -195.186038) (xy 64.881869 -195.194024) (xy 64.951404 -195.209894) (xy 65.018724 -195.233451)
			(xy 65.082983 -195.264396) (xy 65.143374 -195.302342) (xy 65.199136 -195.346811) (xy 65.249569 -195.397244)
			(xy 65.294038 -195.453006) (xy 65.331984 -195.513397) (xy 65.362929 -195.577656) (xy 65.386486 -195.644976)
			(xy 65.402356 -195.714511) (xy 65.410342 -195.785385) (xy 65.410342 -195.856707) (xy 65.402356 -195.927581)
			(xy 65.386486 -195.997116) (xy 65.362929 -196.064436) (xy 65.331984 -196.128695) (xy 65.294038 -196.189086)
			(xy 65.249569 -196.244848) (xy 65.199136 -196.295281) (xy 65.143374 -196.33975) (xy 65.082983 -196.377696)
			(xy 65.018724 -196.408641) (xy 64.951404 -196.432198) (xy 64.881869 -196.448068) (xy 64.810995 -196.456054)
			(xy 64.739673 -196.456054) (xy 64.668799 -196.448068) (xy 64.599264 -196.432198) (xy 64.531944 -196.408641)
			(xy 64.467685 -196.377696) (xy 64.407294 -196.33975) (xy 64.351532 -196.295281) (xy 64.301099 -196.244848)
			(xy 64.25663 -196.189086) (xy 64.218684 -196.128695) (xy 64.187739 -196.064436) (xy 64.164182 -195.997116)
			(xy 64.148312 -195.927581) (xy 64.140326 -195.856707) (xy 62.605928 -195.856707) (xy 62.597942 -195.927581)
			(xy 62.582072 -195.997116) (xy 62.558515 -196.064436) (xy 62.52757 -196.128695) (xy 62.489624 -196.189086)
			(xy 62.445155 -196.244848) (xy 62.394722 -196.295281) (xy 62.33896 -196.33975) (xy 62.278569 -196.377696)
			(xy 62.21431 -196.408641) (xy 62.14699 -196.432198) (xy 62.077455 -196.448068) (xy 62.006581 -196.456054)
			(xy 61.935259 -196.456054) (xy 61.864385 -196.448068) (xy 61.79485 -196.432198) (xy 61.72753 -196.408641)
			(xy 61.663271 -196.377696) (xy 61.60288 -196.33975) (xy 61.547118 -196.295281) (xy 61.496685 -196.244848)
			(xy 61.452216 -196.189086) (xy 61.41427 -196.128695) (xy 61.383325 -196.064436) (xy 61.359768 -195.997116)
			(xy 61.343898 -195.927581) (xy 61.335912 -195.856707) (xy 60.074056 -195.856707) (xy 60.06607 -195.927581)
			(xy 60.0502 -195.997116) (xy 60.026643 -196.064436) (xy 59.995698 -196.128695) (xy 59.957752 -196.189086)
			(xy 59.913283 -196.244848) (xy 59.86285 -196.295281) (xy 59.807088 -196.33975) (xy 59.746697 -196.377696)
			(xy 59.682438 -196.408641) (xy 59.615118 -196.432198) (xy 59.545583 -196.448068) (xy 59.474709 -196.456054)
			(xy 59.403387 -196.456054) (xy 59.332513 -196.448068) (xy 59.262978 -196.432198) (xy 59.195658 -196.408641)
			(xy 59.131399 -196.377696) (xy 59.071008 -196.33975) (xy 59.015246 -196.295281) (xy 58.964813 -196.244848)
			(xy 58.920344 -196.189086) (xy 58.882398 -196.128695) (xy 58.851453 -196.064436) (xy 58.827896 -195.997116)
			(xy 58.812026 -195.927581) (xy 58.80404 -195.856707) (xy 45.51426 -195.856707) (xy 45.51426 -195.903596)
			(xy 51.402996 -195.903596) (xy 53.055012 -195.903596) (xy 53.055012 -197.555612) (xy 51.402996 -197.555612)
			(xy 51.402996 -195.903596) (xy 45.51426 -195.903596) (xy 45.51426 -197.860411) (xy 86.399122 -197.860411)
			(xy 86.401115 -197.660283) (xy 86.411112 -197.460394) (xy 86.429099 -197.261066) (xy 86.455047 -197.062617)
			(xy 86.488914 -196.865365) (xy 86.530646 -196.669626) (xy 86.580175 -196.475713) (xy 86.637424 -196.283938)
			(xy 86.702299 -196.094606) (xy 86.774698 -195.908022) (xy 86.854504 -195.724483) (xy 86.941589 -195.544285)
			(xy 87.035814 -195.367715) (xy 87.137028 -195.195056) (xy 87.245069 -195.026586) (xy 87.359764 -194.862572)
			(xy 87.48093 -194.703279) (xy 87.608371 -194.548962) (xy 87.741885 -194.399866) (xy 87.881257 -194.256232)
			(xy 88.026264 -194.11829) (xy 88.176675 -193.986259) (xy 88.332247 -193.860352) (xy 88.492732 -193.74077)
			(xy 88.657873 -193.627705) (xy 88.827405 -193.521337) (xy 89.001058 -193.421838) (xy 89.178552 -193.329366)
			(xy 89.359604 -193.24407) (xy 89.543924 -193.166086) (xy 89.731216 -193.095538) (xy 89.921181 -193.032541)
			(xy 90.113514 -192.977195) (xy 90.307908 -192.929588) (xy 90.504051 -192.889797) (xy 90.701628 -192.857885)
			(xy 90.900325 -192.833904) (xy 91.099821 -192.817891) (xy 91.299799 -192.809874) (xy 91.399868 -192.809368)
			(xy 91.499937 -192.809864) (xy 91.699915 -192.817861) (xy 91.899414 -192.833853) (xy 92.098112 -192.857814)
			(xy 92.295693 -192.889706) (xy 92.49184 -192.929477) (xy 92.686239 -192.977064) (xy 92.878578 -193.032391)
			(xy 93.068549 -193.095369) (xy 93.255848 -193.165897) (xy 93.440176 -193.243863) (xy 93.621237 -193.329141)
			(xy 93.79874 -193.421594) (xy 93.95732 -193.512436) (xy 96.110026 -193.512436) (xy 96.110026 -193.4525)
			(xy 96.117849 -193.393078) (xy 96.133362 -193.335185) (xy 96.156298 -193.279812) (xy 96.186265 -193.227906)
			(xy 96.222752 -193.180356) (xy 96.265132 -193.137976) (xy 96.312682 -193.101489) (xy 96.364588 -193.071522)
			(xy 96.419961 -193.048586) (xy 96.477854 -193.033073) (xy 96.537276 -193.02525) (xy 96.567244 -193.02476)
			(xy 96.597212 -193.02525) (xy 96.656634 -193.033073) (xy 96.714527 -193.048586) (xy 96.7699 -193.071522)
			(xy 96.821806 -193.101489) (xy 96.869356 -193.137976) (xy 96.911736 -193.180356) (xy 96.948223 -193.227906)
			(xy 96.97819 -193.279812) (xy 97.001126 -193.335185) (xy 97.016639 -193.393078) (xy 97.024462 -193.4525)
			(xy 97.024462 -193.512436) (xy 97.016639 -193.571858) (xy 97.001126 -193.629751) (xy 96.97819 -193.685124)
			(xy 96.948223 -193.73703) (xy 96.911736 -193.78458) (xy 96.869356 -193.82696) (xy 96.821806 -193.863447)
			(xy 96.7699 -193.893414) (xy 96.714527 -193.91635) (xy 96.656634 -193.931863) (xy 96.597212 -193.939686)
			(xy 96.537276 -193.939686) (xy 96.477854 -193.931863) (xy 96.419961 -193.91635) (xy 96.364588 -193.893414)
			(xy 96.312682 -193.863447) (xy 96.265132 -193.82696) (xy 96.222752 -193.78458) (xy 96.186265 -193.73703)
			(xy 96.156298 -193.685124) (xy 96.133362 -193.629751) (xy 96.117849 -193.571858) (xy 96.110026 -193.512436)
			(xy 93.95732 -193.512436) (xy 93.972403 -193.521076) (xy 94.141946 -193.627426) (xy 94.307099 -193.740475)
			(xy 94.467596 -193.86004) (xy 94.623181 -193.985932) (xy 94.773605 -194.117947) (xy 94.918626 -194.255875)
			(xy 95.058012 -194.399495) (xy 95.191541 -194.548576) (xy 95.318999 -194.702881) (xy 95.44018 -194.862162)
			(xy 95.554892 -195.026163) (xy 95.556268 -195.028308) (xy 96.79735 -195.028308) (xy 96.79735 -194.968372)
			(xy 96.805173 -194.90895) (xy 96.820686 -194.851057) (xy 96.843622 -194.795684) (xy 96.873589 -194.743778)
			(xy 96.910076 -194.696228) (xy 96.952456 -194.653848) (xy 97.000006 -194.617361) (xy 97.051912 -194.587394)
			(xy 97.107285 -194.564458) (xy 97.165178 -194.548945) (xy 97.2246 -194.541122) (xy 97.254568 -194.540632)
			(xy 97.284536 -194.541122) (xy 97.343958 -194.548945) (xy 97.401851 -194.564458) (xy 97.408094 -194.567044)
			(xy 98.927394 -194.567044) (xy 98.927394 -194.507108) (xy 98.935217 -194.447686) (xy 98.95073 -194.389793)
			(xy 98.973666 -194.33442) (xy 99.003633 -194.282514) (xy 99.04012 -194.234964) (xy 99.0825 -194.192584)
			(xy 99.13005 -194.156097) (xy 99.181956 -194.12613) (xy 99.237329 -194.103194) (xy 99.295222 -194.087681)
			(xy 99.354644 -194.079858) (xy 99.384612 -194.079368) (xy 99.41458 -194.079858) (xy 99.474002 -194.087681)
			(xy 99.531895 -194.103194) (xy 99.587268 -194.12613) (xy 99.639174 -194.156097) (xy 99.686724 -194.192584)
			(xy 99.729104 -194.234964) (xy 99.765591 -194.282514) (xy 99.795558 -194.33442) (xy 99.818494 -194.389793)
			(xy 99.834007 -194.447686) (xy 99.84183 -194.507108) (xy 99.84183 -194.567044) (xy 99.834007 -194.626466)
			(xy 99.818494 -194.684359) (xy 99.795558 -194.739732) (xy 99.765591 -194.791638) (xy 99.729104 -194.839188)
			(xy 99.686724 -194.881568) (xy 99.639174 -194.918055) (xy 99.587268 -194.948022) (xy 99.531895 -194.970958)
			(xy 99.474002 -194.986471) (xy 99.41458 -194.994294) (xy 99.354644 -194.994294) (xy 99.295222 -194.986471)
			(xy 99.237329 -194.970958) (xy 99.181956 -194.948022) (xy 99.13005 -194.918055) (xy 99.0825 -194.881568)
			(xy 99.04012 -194.839188) (xy 99.003633 -194.791638) (xy 98.973666 -194.739732) (xy 98.95073 -194.684359)
			(xy 98.935217 -194.626466) (xy 98.927394 -194.567044) (xy 97.408094 -194.567044) (xy 97.457224 -194.587394)
			(xy 97.50913 -194.617361) (xy 97.55668 -194.653848) (xy 97.59906 -194.696228) (xy 97.635547 -194.743778)
			(xy 97.665514 -194.795684) (xy 97.68845 -194.851057) (xy 97.703963 -194.90895) (xy 97.711786 -194.968372)
			(xy 97.711786 -195.028308) (xy 97.703963 -195.08773) (xy 97.68845 -195.145623) (xy 97.665514 -195.200996)
			(xy 97.635547 -195.252902) (xy 97.59906 -195.300452) (xy 97.55668 -195.342832) (xy 97.50913 -195.379319)
			(xy 97.457224 -195.409286) (xy 97.401851 -195.432222) (xy 97.343958 -195.447735) (xy 97.284536 -195.455558)
			(xy 97.2246 -195.455558) (xy 97.165178 -195.447735) (xy 97.107285 -195.432222) (xy 97.051912 -195.409286)
			(xy 97.000006 -195.379319) (xy 96.952456 -195.342832) (xy 96.910076 -195.300452) (xy 96.873589 -195.252902)
			(xy 96.843622 -195.200996) (xy 96.820686 -195.145623) (xy 96.805173 -195.08773) (xy 96.79735 -195.028308)
			(xy 95.556268 -195.028308) (xy 95.66295 -195.194623) (xy 95.764182 -195.367272) (xy 95.858425 -195.543832)
			(xy 95.945528 -195.724022) (xy 96.025353 -195.907552) (xy 96.09777 -196.094129) (xy 96.162665 -196.283454)
			(xy 96.219933 -196.475224) (xy 96.269483 -196.669131) (xy 96.278589 -196.71182) (xy 97.787442 -196.71182)
			(xy 97.787442 -196.651884) (xy 97.795265 -196.592462) (xy 97.810778 -196.534569) (xy 97.833714 -196.479196)
			(xy 97.863681 -196.42729) (xy 97.900168 -196.37974) (xy 97.942548 -196.33736) (xy 97.990098 -196.300873)
			(xy 98.042004 -196.270906) (xy 98.097377 -196.24797) (xy 98.15527 -196.232457) (xy 98.214692 -196.224634)
			(xy 98.24466 -196.224144) (xy 98.274628 -196.224634) (xy 98.33405 -196.232457) (xy 98.391943 -196.24797)
			(xy 98.447316 -196.270906) (xy 98.499222 -196.300873) (xy 98.546772 -196.33736) (xy 98.589152 -196.37974)
			(xy 98.625639 -196.42729) (xy 98.655606 -196.479196) (xy 98.678542 -196.534569) (xy 98.694055 -196.592462)
			(xy 98.701878 -196.651884) (xy 98.701878 -196.71182) (xy 98.694055 -196.771242) (xy 98.678542 -196.829135)
			(xy 98.655606 -196.884508) (xy 98.625639 -196.936414) (xy 98.589152 -196.983964) (xy 98.546772 -197.026344)
			(xy 98.499222 -197.062831) (xy 98.447316 -197.092798) (xy 98.391943 -197.115734) (xy 98.33405 -197.131247)
			(xy 98.274628 -197.13907) (xy 98.214692 -197.13907) (xy 98.15527 -197.131247) (xy 98.097377 -197.115734)
			(xy 98.042004 -197.092798) (xy 97.990098 -197.062831) (xy 97.942548 -197.026344) (xy 97.900168 -196.983964)
			(xy 97.863681 -196.936414) (xy 97.833714 -196.884508) (xy 97.810778 -196.829135) (xy 97.795265 -196.771242)
			(xy 97.787442 -196.71182) (xy 96.278589 -196.71182) (xy 96.311234 -196.864866) (xy 96.345121 -197.062115)
			(xy 96.371089 -197.260561) (xy 96.389096 -197.459888) (xy 96.399114 -197.659775) (xy 96.401127 -197.859903)
			(xy 96.395131 -198.059951) (xy 96.381135 -198.2596) (xy 96.359164 -198.458528) (xy 96.32925 -198.656418)
			(xy 96.291443 -198.852953) (xy 96.245804 -199.047818) (xy 96.192404 -199.240701) (xy 96.13133 -199.431293)
			(xy 96.062679 -199.619288) (xy 95.986561 -199.804387) (xy 95.903099 -199.986292) (xy 95.812426 -200.164711)
			(xy 95.714687 -200.339361) (xy 95.610038 -200.50996) (xy 95.498648 -200.676235) (xy 95.380694 -200.83792)
			(xy 95.256365 -200.994757) (xy 95.125862 -201.146494) (xy 94.989391 -201.292888) (xy 94.847173 -201.433704)
			(xy 94.699435 -201.568718) (xy 94.546413 -201.697713) (xy 94.388353 -201.820482) (xy 94.225507 -201.936829)
			(xy 94.058137 -202.046567) (xy 93.88651 -202.149521) (xy 93.710902 -202.245526) (xy 93.531592 -202.334428)
			(xy 93.34887 -202.416084) (xy 93.163027 -202.490365) (xy 92.97436 -202.557151) (xy 92.783173 -202.616334)
			(xy 92.589771 -202.667821) (xy 92.394464 -202.711529) (xy 92.197564 -202.747388) (xy 91.999387 -202.77534)
			(xy 91.800251 -202.79534) (xy 91.600474 -202.807358) (xy 91.400376 -202.811372) (xy 91.200278 -202.807378)
			(xy 91.000499 -202.795381) (xy 90.801361 -202.775401) (xy 90.603182 -202.747469) (xy 90.406278 -202.71163)
			(xy 90.210967 -202.667942) (xy 90.017559 -202.616475) (xy 89.826366 -202.557311) (xy 89.637693 -202.490544)
			(xy 89.451842 -202.416282) (xy 89.269111 -202.334644) (xy 89.089793 -202.245761) (xy 88.914175 -202.149774)
			(xy 88.742537 -202.046837) (xy 88.575156 -201.937116) (xy 88.412298 -201.820785) (xy 88.254226 -201.698032)
			(xy 88.101191 -201.569053) (xy 87.953439 -201.434055) (xy 87.811206 -201.293252) (xy 87.674721 -201.146872)
			(xy 87.544202 -200.995149) (xy 87.419858 -200.838325) (xy 87.301888 -200.676651) (xy 87.19048 -200.510387)
			(xy 87.085814 -200.339799) (xy 86.988057 -200.16516) (xy 86.897366 -199.986749) (xy 86.813885 -199.804853)
			(xy 86.737749 -199.619762) (xy 86.669079 -199.431773) (xy 86.607986 -199.241188) (xy 86.554566 -199.04831)
			(xy 86.508906 -198.85345) (xy 86.47108 -198.656919) (xy 86.441146 -198.459032) (xy 86.419154 -198.260106)
			(xy 86.405139 -198.060459) (xy 86.399122 -197.860411) (xy 45.51426 -197.860411) (xy 45.51426 -202.249024)
			(xy 41.436696 -206.326736) (xy 64.48728 -206.326736) (xy 64.48728 -206.2668) (xy 64.495103 -206.207378)
			(xy 64.510616 -206.149485) (xy 64.533552 -206.094112) (xy 64.563519 -206.042206) (xy 64.600006 -205.994656)
			(xy 64.642386 -205.952276) (xy 64.689936 -205.915789) (xy 64.741842 -205.885822) (xy 64.797215 -205.862886)
			(xy 64.855108 -205.847373) (xy 64.91453 -205.83955) (xy 64.944498 -205.83906) (xy 64.974466 -205.83955)
			(xy 65.033888 -205.847373) (xy 65.091781 -205.862886) (xy 65.147154 -205.885822) (xy 65.19906 -205.915789)
			(xy 65.24661 -205.952276) (xy 65.28899 -205.994656) (xy 65.325477 -206.042206) (xy 65.355444 -206.094112)
			(xy 65.37838 -206.149485) (xy 65.393893 -206.207378) (xy 65.401716 -206.2668) (xy 65.401716 -206.326736)
			(xy 65.393893 -206.386158) (xy 65.37838 -206.444051) (xy 65.355444 -206.499424) (xy 65.325477 -206.55133)
			(xy 65.28899 -206.59888) (xy 65.24661 -206.64126) (xy 65.19906 -206.677747) (xy 65.147154 -206.707714)
			(xy 65.091781 -206.73065) (xy 65.033888 -206.746163) (xy 64.974466 -206.753986) (xy 64.91453 -206.753986)
			(xy 64.855108 -206.746163) (xy 64.797215 -206.73065) (xy 64.741842 -206.707714) (xy 64.689936 -206.677747)
			(xy 64.642386 -206.64126) (xy 64.600006 -206.59888) (xy 64.563519 -206.55133) (xy 64.533552 -206.499424)
			(xy 64.510616 -206.444051) (xy 64.495103 -206.386158) (xy 64.48728 -206.326736) (xy 41.436696 -206.326736)
			(xy 38.538912 -209.224626) (xy 38.538912 -209.230972) (xy 64.52538 -209.230972) (xy 64.52538 -209.171036)
			(xy 64.533203 -209.111614) (xy 64.548716 -209.053721) (xy 64.571652 -208.998348) (xy 64.601619 -208.946442)
			(xy 64.638106 -208.898892) (xy 64.680486 -208.856512) (xy 64.728036 -208.820025) (xy 64.779942 -208.790058)
			(xy 64.835315 -208.767122) (xy 64.893208 -208.751609) (xy 64.95263 -208.743786) (xy 64.982598 -208.743296)
			(xy 65.012566 -208.743786) (xy 65.071988 -208.751609) (xy 65.129881 -208.767122) (xy 65.185254 -208.790058)
			(xy 65.23716 -208.820025) (xy 65.28471 -208.856512) (xy 65.32709 -208.898892) (xy 65.363577 -208.946442)
			(xy 65.393544 -208.998348) (xy 65.41648 -209.053721) (xy 65.431993 -209.111614) (xy 65.439816 -209.171036)
			(xy 65.439816 -209.230972) (xy 65.431993 -209.290394) (xy 65.41648 -209.348287) (xy 65.393544 -209.40366)
			(xy 65.363577 -209.455566) (xy 65.32709 -209.503116) (xy 65.28471 -209.545496) (xy 65.23716 -209.581983)
			(xy 65.185254 -209.61195) (xy 65.129881 -209.634886) (xy 65.071988 -209.650399) (xy 65.012566 -209.658222)
			(xy 64.95263 -209.658222) (xy 64.893208 -209.650399) (xy 64.835315 -209.634886) (xy 64.779942 -209.61195)
			(xy 64.728036 -209.581983) (xy 64.680486 -209.545496) (xy 64.638106 -209.503116) (xy 64.601619 -209.455566)
			(xy 64.571652 -209.40366) (xy 64.548716 -209.348287) (xy 64.533203 -209.290394) (xy 64.52538 -209.230972)
			(xy 38.538912 -209.230972) (xy 38.538912 -210.149947) (xy 72.999096 -210.149947) (xy 73.001098 -209.949819)
			(xy 73.011106 -209.749931) (xy 73.029103 -209.550604) (xy 73.055061 -209.352156) (xy 73.088938 -209.154906)
			(xy 73.13068 -208.959169) (xy 73.180219 -208.765259) (xy 73.237477 -208.573486) (xy 73.302362 -208.384157)
			(xy 73.37477 -208.197577) (xy 73.454586 -208.014042) (xy 73.54168 -207.833848) (xy 73.635914 -207.657283)
			(xy 73.737137 -207.48463) (xy 73.845187 -207.316165) (xy 73.95989 -207.152157) (xy 74.081064 -206.99287)
			(xy 74.208513 -206.838559) (xy 74.342034 -206.689471) (xy 74.481414 -206.545844) (xy 74.626428 -206.407908)
			(xy 74.776845 -206.275885) (xy 74.932423 -206.149986) (xy 75.092915 -206.030412) (xy 75.258061 -205.917356)
			(xy 75.427599 -205.810997) (xy 75.601257 -205.711506) (xy 75.778756 -205.619043) (xy 75.959812 -205.533756)
			(xy 76.144136 -205.455781) (xy 76.331432 -205.385244) (xy 76.5214 -205.322256) (xy 76.713736 -205.266919)
			(xy 76.908132 -205.219322) (xy 77.104277 -205.179541) (xy 77.301856 -205.147639) (xy 77.500553 -205.123668)
			(xy 77.700051 -205.107666) (xy 77.900029 -205.099659) (xy 78.000098 -205.099158) (xy 78.100167 -205.099659)
			(xy 78.300145 -205.107666) (xy 78.499643 -205.123668) (xy 78.69834 -205.147639) (xy 78.895919 -205.179541)
			(xy 79.092064 -205.219322) (xy 79.28646 -205.266919) (xy 79.478796 -205.322256) (xy 79.668764 -205.385244)
			(xy 79.85606 -205.455781) (xy 80.040384 -205.533756) (xy 80.22144 -205.619043) (xy 80.398939 -205.711506)
			(xy 80.572597 -205.810997) (xy 80.742135 -205.917356) (xy 80.907281 -206.030412) (xy 81.067773 -206.149986)
			(xy 81.223351 -206.275885) (xy 81.373768 -206.407908) (xy 81.518782 -206.545844) (xy 81.658162 -206.689471)
			(xy 81.791683 -206.838559) (xy 81.919132 -206.99287) (xy 82.040306 -207.152157) (xy 82.155009 -207.316165)
			(xy 82.263059 -207.48463) (xy 82.364282 -207.657283) (xy 82.458516 -207.833848) (xy 82.54561 -208.014042)
			(xy 82.625426 -208.197577) (xy 82.697834 -208.384157) (xy 82.762719 -208.573486) (xy 82.819977 -208.765259)
			(xy 82.869516 -208.959169) (xy 82.911258 -209.154906) (xy 82.945135 -209.352156) (xy 82.971093 -209.550604)
			(xy 82.98909 -209.749931) (xy 82.999098 -209.949819) (xy 83.0011 -210.149947) (xy 82.995094 -210.349995)
			(xy 82.981089 -210.549643) (xy 82.959107 -210.74857) (xy 82.929183 -210.946459) (xy 82.891366 -211.142992)
			(xy 82.845717 -211.337854) (xy 82.792307 -211.530734) (xy 82.731223 -211.721323) (xy 82.662563 -211.909315)
			(xy 82.586436 -212.09441) (xy 82.502965 -212.27631) (xy 82.412282 -212.454726) (xy 82.314534 -212.62937)
			(xy 82.209877 -212.799963) (xy 82.098478 -212.966233) (xy 81.980516 -213.127912) (xy 81.85618 -213.284743)
			(xy 81.725668 -213.436473) (xy 81.589191 -213.58286) (xy 81.446965 -213.723669) (xy 81.29922 -213.858676)
			(xy 81.146192 -213.987663) (xy 80.988125 -214.110424) (xy 80.825274 -214.226762) (xy 80.657898 -214.336492)
			(xy 80.486266 -214.439437) (xy 80.310652 -214.535433) (xy 80.131339 -214.624326) (xy 79.948612 -214.705973)
			(xy 79.762765 -214.780245) (xy 79.574095 -214.847021) (xy 79.382905 -214.906195) (xy 79.1895 -214.957672)
			(xy 78.994191 -215.00137) (xy 78.797289 -215.037218) (xy 78.599111 -215.06516) (xy 78.399974 -215.085151)
			(xy 78.200196 -215.097158) (xy 78.000098 -215.101163) (xy 77.8 -215.097158) (xy 77.600222 -215.085151)
			(xy 77.401085 -215.06516) (xy 77.202907 -215.037218) (xy 77.006005 -215.00137) (xy 76.810696 -214.957672)
			(xy 76.617291 -214.906195) (xy 76.426101 -214.847021) (xy 76.237431 -214.780245) (xy 76.051584 -214.705973)
			(xy 75.868857 -214.624326) (xy 75.689544 -214.535433) (xy 75.51393 -214.439437) (xy 75.342298 -214.336492)
			(xy 75.174922 -214.226762) (xy 75.012071 -214.110424) (xy 74.854004 -213.987663) (xy 74.700976 -213.858676)
			(xy 74.553231 -213.723669) (xy 74.411005 -213.58286) (xy 74.274528 -213.436473) (xy 74.144016 -213.284743)
			(xy 74.01968 -213.127912) (xy 73.901718 -212.966233) (xy 73.790319 -212.799963) (xy 73.685662 -212.62937)
			(xy 73.587914 -212.454726) (xy 73.497231 -212.27631) (xy 73.41376 -212.09441) (xy 73.337633 -211.909315)
			(xy 73.268973 -211.721323) (xy 73.207889 -211.530734) (xy 73.154479 -211.337854) (xy 73.10883 -211.142992)
			(xy 73.071013 -210.946459) (xy 73.041089 -210.74857) (xy 73.019107 -210.549643) (xy 73.005102 -210.349995)
			(xy 72.999096 -210.149947) (xy 38.538912 -210.149947) (xy 38.538912 -211.69376) (xy 36.655756 -213.576916)
			(xy 30.15234 -213.576916) (xy 29.755084 -213.974172) (xy 29.755084 -216.659968) (xy 51.342036 -216.659968)
			(xy 52.994052 -216.659968) (xy 52.994052 -217.246047) (xy 63.219576 -217.246047) (xy 63.219576 -217.174725)
			(xy 63.227562 -217.103851) (xy 63.243432 -217.034316) (xy 63.266989 -216.966996) (xy 63.297934 -216.902737)
			(xy 63.33588 -216.842346) (xy 63.380349 -216.786584) (xy 63.430782 -216.736151) (xy 63.486544 -216.691682)
			(xy 63.546935 -216.653736) (xy 63.611194 -216.622791) (xy 63.678514 -216.599234) (xy 63.748049 -216.583364)
			(xy 63.818923 -216.575378) (xy 63.854584 -216.574878) (xy 63.890245 -216.575378) (xy 63.961119 -216.583364)
			(xy 64.030654 -216.599234) (xy 64.097974 -216.622791) (xy 64.162233 -216.653736) (xy 64.222624 -216.691682)
			(xy 64.278386 -216.736151) (xy 64.328819 -216.786584) (xy 64.373288 -216.842346) (xy 64.411234 -216.902737)
			(xy 64.442179 -216.966996) (xy 64.465736 -217.034316) (xy 64.481606 -217.103851) (xy 64.489592 -217.174725)
			(xy 64.489592 -217.246047) (xy 66.211188 -217.246047) (xy 66.211188 -217.174725) (xy 66.219174 -217.103851)
			(xy 66.235044 -217.034316) (xy 66.258601 -216.966996) (xy 66.289546 -216.902737) (xy 66.327492 -216.842346)
			(xy 66.371961 -216.786584) (xy 66.422394 -216.736151) (xy 66.478156 -216.691682) (xy 66.538547 -216.653736)
			(xy 66.602806 -216.622791) (xy 66.670126 -216.599234) (xy 66.739661 -216.583364) (xy 66.810535 -216.575378)
			(xy 66.846196 -216.574878) (xy 66.881857 -216.575378) (xy 66.952731 -216.583364) (xy 67.022266 -216.599234)
			(xy 67.089586 -216.622791) (xy 67.153845 -216.653736) (xy 67.214236 -216.691682) (xy 67.269998 -216.736151)
			(xy 67.320431 -216.786584) (xy 67.3649 -216.842346) (xy 67.402846 -216.902737) (xy 67.433791 -216.966996)
			(xy 67.457348 -217.034316) (xy 67.473218 -217.103851) (xy 67.481204 -217.174725) (xy 67.481204 -217.246047)
			(xy 67.473218 -217.316921) (xy 67.457348 -217.386456) (xy 67.433791 -217.453776) (xy 67.402846 -217.518035)
			(xy 67.3649 -217.578426) (xy 67.320431 -217.634188) (xy 67.269998 -217.684621) (xy 67.214236 -217.72909)
			(xy 67.153845 -217.767036) (xy 67.089586 -217.797981) (xy 67.022266 -217.821538) (xy 66.952731 -217.837408)
			(xy 66.881857 -217.845394) (xy 66.810535 -217.845394) (xy 66.739661 -217.837408) (xy 66.670126 -217.821538)
			(xy 66.602806 -217.797981) (xy 66.538547 -217.767036) (xy 66.478156 -217.72909) (xy 66.422394 -217.684621)
			(xy 66.371961 -217.634188) (xy 66.327492 -217.578426) (xy 66.289546 -217.518035) (xy 66.258601 -217.453776)
			(xy 66.235044 -217.386456) (xy 66.219174 -217.316921) (xy 66.211188 -217.246047) (xy 64.489592 -217.246047)
			(xy 64.481606 -217.316921) (xy 64.465736 -217.386456) (xy 64.442179 -217.453776) (xy 64.411234 -217.518035)
			(xy 64.373288 -217.578426) (xy 64.328819 -217.634188) (xy 64.278386 -217.684621) (xy 64.222624 -217.72909)
			(xy 64.162233 -217.767036) (xy 64.097974 -217.797981) (xy 64.030654 -217.821538) (xy 63.961119 -217.837408)
			(xy 63.890245 -217.845394) (xy 63.818923 -217.845394) (xy 63.748049 -217.837408) (xy 63.678514 -217.821538)
			(xy 63.611194 -217.797981) (xy 63.546935 -217.767036) (xy 63.486544 -217.72909) (xy 63.430782 -217.684621)
			(xy 63.380349 -217.634188) (xy 63.33588 -217.578426) (xy 63.297934 -217.518035) (xy 63.266989 -217.453776)
			(xy 63.243432 -217.386456) (xy 63.227562 -217.316921) (xy 63.219576 -217.246047) (xy 52.994052 -217.246047)
			(xy 52.994052 -218.311984) (xy 51.342036 -218.311984) (xy 51.342036 -216.659968) (xy 29.755084 -216.659968)
			(xy 29.755084 -219.208959) (xy 63.219576 -219.208959) (xy 63.219576 -219.137637) (xy 63.227562 -219.066763)
			(xy 63.243432 -218.997228) (xy 63.266989 -218.929908) (xy 63.297934 -218.865649) (xy 63.33588 -218.805258)
			(xy 63.380349 -218.749496) (xy 63.430782 -218.699063) (xy 63.486544 -218.654594) (xy 63.546935 -218.616648)
			(xy 63.611194 -218.585703) (xy 63.678514 -218.562146) (xy 63.748049 -218.546276) (xy 63.818923 -218.53829)
			(xy 63.854584 -218.53779) (xy 63.890245 -218.53829) (xy 63.961119 -218.546276) (xy 64.030654 -218.562146)
			(xy 64.097974 -218.585703) (xy 64.162233 -218.616648) (xy 64.222624 -218.654594) (xy 64.278386 -218.699063)
			(xy 64.328819 -218.749496) (xy 64.373288 -218.805258) (xy 64.411234 -218.865649) (xy 64.442179 -218.929908)
			(xy 64.465736 -218.997228) (xy 64.481606 -219.066763) (xy 64.489592 -219.137637) (xy 64.489592 -219.208959)
			(xy 66.211188 -219.208959) (xy 66.211188 -219.137637) (xy 66.219174 -219.066763) (xy 66.235044 -218.997228)
			(xy 66.258601 -218.929908) (xy 66.289546 -218.865649) (xy 66.327492 -218.805258) (xy 66.371961 -218.749496)
			(xy 66.422394 -218.699063) (xy 66.478156 -218.654594) (xy 66.538547 -218.616648) (xy 66.602806 -218.585703)
			(xy 66.670126 -218.562146) (xy 66.739661 -218.546276) (xy 66.810535 -218.53829) (xy 66.846196 -218.53779)
			(xy 66.881857 -218.53829) (xy 66.952731 -218.546276) (xy 67.022266 -218.562146) (xy 67.089586 -218.585703)
			(xy 67.153845 -218.616648) (xy 67.214236 -218.654594) (xy 67.269998 -218.699063) (xy 67.320431 -218.749496)
			(xy 67.3649 -218.805258) (xy 67.402846 -218.865649) (xy 67.433791 -218.929908) (xy 67.457348 -218.997228)
			(xy 67.473218 -219.066763) (xy 67.481204 -219.137637) (xy 67.481204 -219.208959) (xy 67.473218 -219.279833)
			(xy 67.457348 -219.349368) (xy 67.433791 -219.416688) (xy 67.402846 -219.480947) (xy 67.3649 -219.541338)
			(xy 67.320431 -219.5971) (xy 67.269998 -219.647533) (xy 67.214236 -219.692002) (xy 67.153845 -219.729948)
			(xy 67.089586 -219.760893) (xy 67.022266 -219.78445) (xy 66.952731 -219.80032) (xy 66.881857 -219.808306)
			(xy 66.810535 -219.808306) (xy 66.739661 -219.80032) (xy 66.670126 -219.78445) (xy 66.602806 -219.760893)
			(xy 66.538547 -219.729948) (xy 66.478156 -219.692002) (xy 66.422394 -219.647533) (xy 66.371961 -219.5971)
			(xy 66.327492 -219.541338) (xy 66.289546 -219.480947) (xy 66.258601 -219.416688) (xy 66.235044 -219.349368)
			(xy 66.219174 -219.279833) (xy 66.211188 -219.208959) (xy 64.489592 -219.208959) (xy 64.481606 -219.279833)
			(xy 64.465736 -219.349368) (xy 64.442179 -219.416688) (xy 64.411234 -219.480947) (xy 64.373288 -219.541338)
			(xy 64.328819 -219.5971) (xy 64.278386 -219.647533) (xy 64.222624 -219.692002) (xy 64.162233 -219.729948)
			(xy 64.097974 -219.760893) (xy 64.030654 -219.78445) (xy 63.961119 -219.80032) (xy 63.890245 -219.808306)
			(xy 63.818923 -219.808306) (xy 63.748049 -219.80032) (xy 63.678514 -219.78445) (xy 63.611194 -219.760893)
			(xy 63.546935 -219.729948) (xy 63.486544 -219.692002) (xy 63.430782 -219.647533) (xy 63.380349 -219.5971)
			(xy 63.33588 -219.541338) (xy 63.297934 -219.480947) (xy 63.266989 -219.416688) (xy 63.243432 -219.349368)
			(xy 63.227562 -219.279833) (xy 63.219576 -219.208959) (xy 29.755084 -219.208959) (xy 29.755084 -221.352465)
			(xy 63.219576 -221.352465) (xy 63.219576 -221.281143) (xy 63.227562 -221.210269) (xy 63.243432 -221.140734)
			(xy 63.266989 -221.073414) (xy 63.297934 -221.009155) (xy 63.33588 -220.948764) (xy 63.380349 -220.893002)
			(xy 63.430782 -220.842569) (xy 63.486544 -220.7981) (xy 63.546935 -220.760154) (xy 63.611194 -220.729209)
			(xy 63.678514 -220.705652) (xy 63.748049 -220.689782) (xy 63.818923 -220.681796) (xy 63.854584 -220.681296)
			(xy 63.890245 -220.681796) (xy 63.961119 -220.689782) (xy 64.030654 -220.705652) (xy 64.097974 -220.729209)
			(xy 64.162233 -220.760154) (xy 64.222624 -220.7981) (xy 64.278386 -220.842569) (xy 64.328819 -220.893002)
			(xy 64.373288 -220.948764) (xy 64.411234 -221.009155) (xy 64.442179 -221.073414) (xy 64.465736 -221.140734)
			(xy 64.481606 -221.210269) (xy 64.489592 -221.281143) (xy 64.489592 -221.352465) (xy 66.211188 -221.352465)
			(xy 66.211188 -221.281143) (xy 66.219174 -221.210269) (xy 66.235044 -221.140734) (xy 66.258601 -221.073414)
			(xy 66.289546 -221.009155) (xy 66.327492 -220.948764) (xy 66.371961 -220.893002) (xy 66.422394 -220.842569)
			(xy 66.478156 -220.7981) (xy 66.538547 -220.760154) (xy 66.602806 -220.729209) (xy 66.670126 -220.705652)
			(xy 66.739661 -220.689782) (xy 66.810535 -220.681796) (xy 66.846196 -220.681296) (xy 66.881857 -220.681796)
			(xy 66.952731 -220.689782) (xy 67.022266 -220.705652) (xy 67.089586 -220.729209) (xy 67.153845 -220.760154)
			(xy 67.214236 -220.7981) (xy 67.269998 -220.842569) (xy 67.320431 -220.893002) (xy 67.3649 -220.948764)
			(xy 67.402846 -221.009155) (xy 67.433791 -221.073414) (xy 67.457348 -221.140734) (xy 67.473218 -221.210269)
			(xy 67.481204 -221.281143) (xy 67.481204 -221.352465) (xy 67.473218 -221.423339) (xy 67.457348 -221.492874)
			(xy 67.433791 -221.560194) (xy 67.402846 -221.624453) (xy 67.3649 -221.684844) (xy 67.320431 -221.740606)
			(xy 67.269998 -221.791039) (xy 67.214236 -221.835508) (xy 67.153845 -221.873454) (xy 67.089586 -221.904399)
			(xy 67.022266 -221.927956) (xy 66.952731 -221.943826) (xy 66.881857 -221.951812) (xy 66.810535 -221.951812)
			(xy 66.739661 -221.943826) (xy 66.670126 -221.927956) (xy 66.602806 -221.904399) (xy 66.538547 -221.873454)
			(xy 66.478156 -221.835508) (xy 66.422394 -221.791039) (xy 66.371961 -221.740606) (xy 66.327492 -221.684844)
			(xy 66.289546 -221.624453) (xy 66.258601 -221.560194) (xy 66.235044 -221.492874) (xy 66.219174 -221.423339)
			(xy 66.211188 -221.352465) (xy 64.489592 -221.352465) (xy 64.481606 -221.423339) (xy 64.465736 -221.492874)
			(xy 64.442179 -221.560194) (xy 64.411234 -221.624453) (xy 64.373288 -221.684844) (xy 64.328819 -221.740606)
			(xy 64.278386 -221.791039) (xy 64.222624 -221.835508) (xy 64.162233 -221.873454) (xy 64.097974 -221.904399)
			(xy 64.030654 -221.927956) (xy 63.961119 -221.943826) (xy 63.890245 -221.951812) (xy 63.818923 -221.951812)
			(xy 63.748049 -221.943826) (xy 63.678514 -221.927956) (xy 63.611194 -221.904399) (xy 63.546935 -221.873454)
			(xy 63.486544 -221.835508) (xy 63.430782 -221.791039) (xy 63.380349 -221.740606) (xy 63.33588 -221.684844)
			(xy 63.297934 -221.624453) (xy 63.266989 -221.560194) (xy 63.243432 -221.492874) (xy 63.227562 -221.423339)
			(xy 63.219576 -221.352465) (xy 29.755084 -221.352465) (xy 29.755084 -229.131047) (xy 39.818567 -229.131047)
			(xy 39.824576 -229.015126) (xy 39.838567 -228.899897) (xy 39.860475 -228.785907) (xy 39.890195 -228.6737)
			(xy 39.927585 -228.563811) (xy 39.972468 -228.456764) (xy 40.024629 -228.353068) (xy 40.08382 -228.253218)
			(xy 40.149759 -228.157689) (xy 40.222131 -228.066938) (xy 40.300592 -227.981395) (xy 40.384767 -227.901469)
			(xy 40.474256 -227.827542) (xy 40.568632 -227.759964) (xy 40.667446 -227.699058) (xy 40.770226 -227.645115)
			(xy 40.876483 -227.598391) (xy 40.98571 -227.55911) (xy 41.097387 -227.527458) (xy 41.210982 -227.503585)
			(xy 41.325953 -227.487607) (xy 41.441752 -227.479599) (xy 41.49979 -227.479098) (xy 41.557828 -227.479599)
			(xy 41.673627 -227.487607) (xy 41.788598 -227.503585) (xy 41.902193 -227.527458) (xy 42.01387 -227.55911)
			(xy 42.123097 -227.598391) (xy 42.229354 -227.645115) (xy 42.332134 -227.699058) (xy 42.430948 -227.759964)
			(xy 42.474432 -227.791101) (xy 63.647829 -227.791101) (xy 63.653878 -227.715531) (xy 63.667925 -227.641033)
			(xy 63.689811 -227.56845) (xy 63.719288 -227.498604) (xy 63.756023 -227.432287) (xy 63.799598 -227.370251)
			(xy 63.84952 -227.313198) (xy 63.905224 -227.261774) (xy 63.966079 -227.216563) (xy 64.031394 -227.178076)
			(xy 64.10043 -227.14675) (xy 64.172405 -227.12294) (xy 64.246503 -227.106915) (xy 64.321884 -227.098856)
			(xy 64.35979 -227.098352) (xy 64.397696 -227.098856) (xy 64.473077 -227.106915) (xy 64.547175 -227.12294)
			(xy 64.61915 -227.14675) (xy 64.688186 -227.178076) (xy 64.753501 -227.216563) (xy 64.814356 -227.261774)
			(xy 64.87006 -227.313198) (xy 64.919982 -227.370251) (xy 64.963557 -227.432287) (xy 65.000292 -227.498604)
			(xy 65.029769 -227.56845) (xy 65.051655 -227.641033) (xy 65.065702 -227.715531) (xy 65.071751 -227.791101)
			(xy 66.187829 -227.791101) (xy 66.193878 -227.715531) (xy 66.207925 -227.641033) (xy 66.229811 -227.56845)
			(xy 66.259288 -227.498604) (xy 66.296023 -227.432287) (xy 66.339598 -227.370251) (xy 66.38952 -227.313198)
			(xy 66.445224 -227.261774) (xy 66.506079 -227.216563) (xy 66.571394 -227.178076) (xy 66.64043 -227.14675)
			(xy 66.712405 -227.12294) (xy 66.786503 -227.106915) (xy 66.861884 -227.098856) (xy 66.89979 -227.098352)
			(xy 66.937696 -227.098856) (xy 67.013077 -227.106915) (xy 67.087175 -227.12294) (xy 67.15915 -227.14675)
			(xy 67.228186 -227.178076) (xy 67.293501 -227.216563) (xy 67.354356 -227.261774) (xy 67.41006 -227.313198)
			(xy 67.459982 -227.370251) (xy 67.503557 -227.432287) (xy 67.540292 -227.498604) (xy 67.569769 -227.56845)
			(xy 67.591655 -227.641033) (xy 67.605702 -227.715531) (xy 67.611751 -227.791101) (xy 68.727829 -227.791101)
			(xy 68.733878 -227.715531) (xy 68.747925 -227.641033) (xy 68.769811 -227.56845) (xy 68.799288 -227.498604)
			(xy 68.836023 -227.432287) (xy 68.879598 -227.370251) (xy 68.92952 -227.313198) (xy 68.985224 -227.261774)
			(xy 69.046079 -227.216563) (xy 69.111394 -227.178076) (xy 69.18043 -227.14675) (xy 69.252405 -227.12294)
			(xy 69.326503 -227.106915) (xy 69.401884 -227.098856) (xy 69.43979 -227.098352) (xy 69.477696 -227.098856)
			(xy 69.553077 -227.106915) (xy 69.627175 -227.12294) (xy 69.69915 -227.14675) (xy 69.768186 -227.178076)
			(xy 69.833501 -227.216563) (xy 69.894356 -227.261774) (xy 69.95006 -227.313198) (xy 69.999982 -227.370251)
			(xy 70.043557 -227.432287) (xy 70.080292 -227.498604) (xy 70.109769 -227.56845) (xy 70.131655 -227.641033)
			(xy 70.145702 -227.715531) (xy 70.151751 -227.791101) (xy 71.267829 -227.791101) (xy 71.273878 -227.715531)
			(xy 71.287925 -227.641033) (xy 71.309811 -227.56845) (xy 71.339288 -227.498604) (xy 71.376023 -227.432287)
			(xy 71.419598 -227.370251) (xy 71.46952 -227.313198) (xy 71.525224 -227.261774) (xy 71.586079 -227.216563)
			(xy 71.651394 -227.178076) (xy 71.72043 -227.14675) (xy 71.792405 -227.12294) (xy 71.866503 -227.106915)
			(xy 71.941884 -227.098856) (xy 71.97979 -227.098352) (xy 72.017696 -227.098856) (xy 72.093077 -227.106915)
			(xy 72.167175 -227.12294) (xy 72.23915 -227.14675) (xy 72.308186 -227.178076) (xy 72.373501 -227.216563)
			(xy 72.434356 -227.261774) (xy 72.49006 -227.313198) (xy 72.539982 -227.370251) (xy 72.583557 -227.432287)
			(xy 72.620292 -227.498604) (xy 72.649769 -227.56845) (xy 72.671655 -227.641033) (xy 72.685702 -227.715531)
			(xy 72.691751 -227.791101) (xy 73.807829 -227.791101) (xy 73.813878 -227.715531) (xy 73.827925 -227.641033)
			(xy 73.849811 -227.56845) (xy 73.879288 -227.498604) (xy 73.916023 -227.432287) (xy 73.959598 -227.370251)
			(xy 74.00952 -227.313198) (xy 74.065224 -227.261774) (xy 74.126079 -227.216563) (xy 74.191394 -227.178076)
			(xy 74.26043 -227.14675) (xy 74.332405 -227.12294) (xy 74.406503 -227.106915) (xy 74.481884 -227.098856)
			(xy 74.51979 -227.098352) (xy 74.557696 -227.098856) (xy 74.633077 -227.106915) (xy 74.707175 -227.12294)
			(xy 74.77915 -227.14675) (xy 74.848186 -227.178076) (xy 74.913501 -227.216563) (xy 74.974356 -227.261774)
			(xy 75.03006 -227.313198) (xy 75.079982 -227.370251) (xy 75.123557 -227.432287) (xy 75.160292 -227.498604)
			(xy 75.189769 -227.56845) (xy 75.211655 -227.641033) (xy 75.225702 -227.715531) (xy 75.231751 -227.791101)
			(xy 76.347829 -227.791101) (xy 76.353878 -227.715531) (xy 76.367925 -227.641033) (xy 76.389811 -227.56845)
			(xy 76.419288 -227.498604) (xy 76.456023 -227.432287) (xy 76.499598 -227.370251) (xy 76.54952 -227.313198)
			(xy 76.605224 -227.261774) (xy 76.666079 -227.216563) (xy 76.731394 -227.178076) (xy 76.80043 -227.14675)
			(xy 76.872405 -227.12294) (xy 76.946503 -227.106915) (xy 77.021884 -227.098856) (xy 77.05979 -227.098352)
			(xy 77.097696 -227.098856) (xy 77.173077 -227.106915) (xy 77.247175 -227.12294) (xy 77.31915 -227.14675)
			(xy 77.388186 -227.178076) (xy 77.453501 -227.216563) (xy 77.514356 -227.261774) (xy 77.57006 -227.313198)
			(xy 77.619982 -227.370251) (xy 77.663557 -227.432287) (xy 77.700292 -227.498604) (xy 77.729769 -227.56845)
			(xy 77.751655 -227.641033) (xy 77.765702 -227.715531) (xy 77.771751 -227.791101) (xy 78.887829 -227.791101)
			(xy 78.893878 -227.715531) (xy 78.907925 -227.641033) (xy 78.929811 -227.56845) (xy 78.959288 -227.498604)
			(xy 78.996023 -227.432287) (xy 79.039598 -227.370251) (xy 79.08952 -227.313198) (xy 79.145224 -227.261774)
			(xy 79.206079 -227.216563) (xy 79.271394 -227.178076) (xy 79.34043 -227.14675) (xy 79.412405 -227.12294)
			(xy 79.486503 -227.106915) (xy 79.561884 -227.098856) (xy 79.59979 -227.098352) (xy 79.637696 -227.098856)
			(xy 79.713077 -227.106915) (xy 79.787175 -227.12294) (xy 79.85915 -227.14675) (xy 79.928186 -227.178076)
			(xy 79.993501 -227.216563) (xy 80.054356 -227.261774) (xy 80.11006 -227.313198) (xy 80.159982 -227.370251)
			(xy 80.203557 -227.432287) (xy 80.240292 -227.498604) (xy 80.269769 -227.56845) (xy 80.291655 -227.641033)
			(xy 80.305702 -227.715531) (xy 80.311751 -227.791101) (xy 81.427829 -227.791101) (xy 81.433878 -227.715531)
			(xy 81.447925 -227.641033) (xy 81.469811 -227.56845) (xy 81.499288 -227.498604) (xy 81.536023 -227.432287)
			(xy 81.579598 -227.370251) (xy 81.62952 -227.313198) (xy 81.685224 -227.261774) (xy 81.746079 -227.216563)
			(xy 81.811394 -227.178076) (xy 81.88043 -227.14675) (xy 81.952405 -227.12294) (xy 82.026503 -227.106915)
			(xy 82.101884 -227.098856) (xy 82.13979 -227.098352) (xy 82.177696 -227.098856) (xy 82.253077 -227.106915)
			(xy 82.327175 -227.12294) (xy 82.39915 -227.14675) (xy 82.468186 -227.178076) (xy 82.533501 -227.216563)
			(xy 82.559813 -227.236111) (xy 86.197949 -227.236111) (xy 86.203998 -227.160541) (xy 86.218045 -227.086043)
			(xy 86.239931 -227.01346) (xy 86.269408 -226.943614) (xy 86.306143 -226.877297) (xy 86.349718 -226.815261)
			(xy 86.39964 -226.758208) (xy 86.455344 -226.706784) (xy 86.516199 -226.661573) (xy 86.581514 -226.623086)
			(xy 86.65055 -226.59176) (xy 86.722525 -226.56795) (xy 86.796623 -226.551925) (xy 86.872004 -226.543866)
			(xy 86.90991 -226.543362) (xy 86.947816 -226.543866) (xy 87.023197 -226.551925) (xy 87.097295 -226.56795)
			(xy 87.16927 -226.59176) (xy 87.238306 -226.623086) (xy 87.303621 -226.661573) (xy 87.364476 -226.706784)
			(xy 87.42018 -226.758208) (xy 87.470102 -226.815261) (xy 87.513677 -226.877297) (xy 87.550412 -226.943614)
			(xy 87.579889 -227.01346) (xy 87.601775 -227.086043) (xy 87.615822 -227.160541) (xy 87.621871 -227.236111)
			(xy 88.737949 -227.236111) (xy 88.743998 -227.160541) (xy 88.758045 -227.086043) (xy 88.779931 -227.01346)
			(xy 88.809408 -226.943614) (xy 88.846143 -226.877297) (xy 88.889718 -226.815261) (xy 88.93964 -226.758208)
			(xy 88.995344 -226.706784) (xy 89.056199 -226.661573) (xy 89.121514 -226.623086) (xy 89.19055 -226.59176)
			(xy 89.262525 -226.56795) (xy 89.336623 -226.551925) (xy 89.412004 -226.543866) (xy 89.44991 -226.543362)
			(xy 89.487816 -226.543866) (xy 89.563197 -226.551925) (xy 89.637295 -226.56795) (xy 89.70927 -226.59176)
			(xy 89.778306 -226.623086) (xy 89.843621 -226.661573) (xy 89.904476 -226.706784) (xy 89.96018 -226.758208)
			(xy 90.010102 -226.815261) (xy 90.053677 -226.877297) (xy 90.090412 -226.943614) (xy 90.119889 -227.01346)
			(xy 90.141775 -227.086043) (xy 90.155822 -227.160541) (xy 90.161871 -227.236111) (xy 91.277949 -227.236111)
			(xy 91.283998 -227.160541) (xy 91.298045 -227.086043) (xy 91.319931 -227.01346) (xy 91.349408 -226.943614)
			(xy 91.386143 -226.877297) (xy 91.429718 -226.815261) (xy 91.47964 -226.758208) (xy 91.535344 -226.706784)
			(xy 91.596199 -226.661573) (xy 91.661514 -226.623086) (xy 91.73055 -226.59176) (xy 91.802525 -226.56795)
			(xy 91.876623 -226.551925) (xy 91.952004 -226.543866) (xy 91.98991 -226.543362) (xy 92.027816 -226.543866)
			(xy 92.103197 -226.551925) (xy 92.177295 -226.56795) (xy 92.24927 -226.59176) (xy 92.318306 -226.623086)
			(xy 92.383621 -226.661573) (xy 92.444476 -226.706784) (xy 92.50018 -226.758208) (xy 92.550102 -226.815261)
			(xy 92.593677 -226.877297) (xy 92.630412 -226.943614) (xy 92.659889 -227.01346) (xy 92.681775 -227.086043)
			(xy 92.695822 -227.160541) (xy 92.701871 -227.236111) (xy 92.699852 -227.311895) (xy 92.68979 -227.387035)
			(xy 92.671798 -227.46068) (xy 92.64608 -227.531996) (xy 92.612928 -227.600173) (xy 92.572716 -227.664441)
			(xy 92.525901 -227.72407) (xy 92.473013 -227.778386) (xy 92.414651 -227.826772) (xy 92.351476 -227.86868)
			(xy 92.284205 -227.903636) (xy 92.2136 -227.931243) (xy 92.140459 -227.951189) (xy 92.065614 -227.963248)
			(xy 91.98991 -227.967283) (xy 91.914206 -227.963248) (xy 91.839361 -227.951189) (xy 91.76622 -227.931243)
			(xy 91.695615 -227.903636) (xy 91.628344 -227.86868) (xy 91.565169 -227.826772) (xy 91.506807 -227.778386)
			(xy 91.453919 -227.72407) (xy 91.407104 -227.664441) (xy 91.366892 -227.600173) (xy 91.33374 -227.531996)
			(xy 91.308022 -227.46068) (xy 91.29003 -227.387035) (xy 91.279968 -227.311895) (xy 91.277949 -227.236111)
			(xy 90.161871 -227.236111) (xy 90.159852 -227.311895) (xy 90.14979 -227.387035) (xy 90.131798 -227.46068)
			(xy 90.10608 -227.531996) (xy 90.072928 -227.600173) (xy 90.032716 -227.664441) (xy 89.985901 -227.72407)
			(xy 89.933013 -227.778386) (xy 89.874651 -227.826772) (xy 89.811476 -227.86868) (xy 89.744205 -227.903636)
			(xy 89.6736 -227.931243) (xy 89.600459 -227.951189) (xy 89.525614 -227.963248) (xy 89.44991 -227.967283)
			(xy 89.374206 -227.963248) (xy 89.299361 -227.951189) (xy 89.22622 -227.931243) (xy 89.155615 -227.903636)
			(xy 89.088344 -227.86868) (xy 89.025169 -227.826772) (xy 88.966807 -227.778386) (xy 88.913919 -227.72407)
			(xy 88.867104 -227.664441) (xy 88.826892 -227.600173) (xy 88.79374 -227.531996) (xy 88.768022 -227.46068)
			(xy 88.75003 -227.387035) (xy 88.739968 -227.311895) (xy 88.737949 -227.236111) (xy 87.621871 -227.236111)
			(xy 87.619852 -227.311895) (xy 87.60979 -227.387035) (xy 87.591798 -227.46068) (xy 87.56608 -227.531996)
			(xy 87.532928 -227.600173) (xy 87.492716 -227.664441) (xy 87.445901 -227.72407) (xy 87.393013 -227.778386)
			(xy 87.334651 -227.826772) (xy 87.271476 -227.86868) (xy 87.204205 -227.903636) (xy 87.1336 -227.931243)
			(xy 87.060459 -227.951189) (xy 86.985614 -227.963248) (xy 86.90991 -227.967283) (xy 86.834206 -227.963248)
			(xy 86.759361 -227.951189) (xy 86.68622 -227.931243) (xy 86.615615 -227.903636) (xy 86.548344 -227.86868)
			(xy 86.485169 -227.826772) (xy 86.426807 -227.778386) (xy 86.373919 -227.72407) (xy 86.327104 -227.664441)
			(xy 86.286892 -227.600173) (xy 86.25374 -227.531996) (xy 86.228022 -227.46068) (xy 86.21003 -227.387035)
			(xy 86.199968 -227.311895) (xy 86.197949 -227.236111) (xy 82.559813 -227.236111) (xy 82.594356 -227.261774)
			(xy 82.65006 -227.313198) (xy 82.699982 -227.370251) (xy 82.743557 -227.432287) (xy 82.780292 -227.498604)
			(xy 82.809769 -227.56845) (xy 82.831655 -227.641033) (xy 82.845702 -227.715531) (xy 82.851751 -227.791101)
			(xy 82.849732 -227.866885) (xy 82.83967 -227.942025) (xy 82.821678 -228.01567) (xy 82.79596 -228.086986)
			(xy 82.762808 -228.155163) (xy 82.722596 -228.219431) (xy 82.675781 -228.27906) (xy 82.622893 -228.333376)
			(xy 82.564531 -228.381762) (xy 82.501356 -228.42367) (xy 82.434085 -228.458626) (xy 82.36348 -228.486233)
			(xy 82.290588 -228.506111) (xy 84.927949 -228.506111) (xy 84.933998 -228.430541) (xy 84.948045 -228.356043)
			(xy 84.969931 -228.28346) (xy 84.999408 -228.213614) (xy 85.036143 -228.147297) (xy 85.079718 -228.085261)
			(xy 85.12964 -228.028208) (xy 85.185344 -227.976784) (xy 85.246199 -227.931573) (xy 85.311514 -227.893086)
			(xy 85.38055 -227.86176) (xy 85.452525 -227.83795) (xy 85.526623 -227.821925) (xy 85.602004 -227.813866)
			(xy 85.63991 -227.813362) (xy 85.677816 -227.813866) (xy 85.753197 -227.821925) (xy 85.827295 -227.83795)
			(xy 85.89927 -227.86176) (xy 85.968306 -227.893086) (xy 86.033621 -227.931573) (xy 86.094476 -227.976784)
			(xy 86.15018 -228.028208) (xy 86.200102 -228.085261) (xy 86.243677 -228.147297) (xy 86.280412 -228.213614)
			(xy 86.309889 -228.28346) (xy 86.331775 -228.356043) (xy 86.345822 -228.430541) (xy 86.351871 -228.506111)
			(xy 87.467949 -228.506111) (xy 87.473998 -228.430541) (xy 87.488045 -228.356043) (xy 87.509931 -228.28346)
			(xy 87.539408 -228.213614) (xy 87.576143 -228.147297) (xy 87.619718 -228.085261) (xy 87.66964 -228.028208)
			(xy 87.725344 -227.976784) (xy 87.786199 -227.931573) (xy 87.851514 -227.893086) (xy 87.92055 -227.86176)
			(xy 87.992525 -227.83795) (xy 88.066623 -227.821925) (xy 88.142004 -227.813866) (xy 88.17991 -227.813362)
			(xy 88.217816 -227.813866) (xy 88.293197 -227.821925) (xy 88.367295 -227.83795) (xy 88.43927 -227.86176)
			(xy 88.508306 -227.893086) (xy 88.573621 -227.931573) (xy 88.634476 -227.976784) (xy 88.69018 -228.028208)
			(xy 88.740102 -228.085261) (xy 88.783677 -228.147297) (xy 88.820412 -228.213614) (xy 88.849889 -228.28346)
			(xy 88.871775 -228.356043) (xy 88.885822 -228.430541) (xy 88.891871 -228.506111) (xy 90.007949 -228.506111)
			(xy 90.013998 -228.430541) (xy 90.028045 -228.356043) (xy 90.049931 -228.28346) (xy 90.079408 -228.213614)
			(xy 90.116143 -228.147297) (xy 90.159718 -228.085261) (xy 90.20964 -228.028208) (xy 90.265344 -227.976784)
			(xy 90.326199 -227.931573) (xy 90.391514 -227.893086) (xy 90.46055 -227.86176) (xy 90.532525 -227.83795)
			(xy 90.606623 -227.821925) (xy 90.682004 -227.813866) (xy 90.71991 -227.813362) (xy 90.757816 -227.813866)
			(xy 90.833197 -227.821925) (xy 90.907295 -227.83795) (xy 90.97927 -227.86176) (xy 91.048306 -227.893086)
			(xy 91.113621 -227.931573) (xy 91.174476 -227.976784) (xy 91.23018 -228.028208) (xy 91.280102 -228.085261)
			(xy 91.323677 -228.147297) (xy 91.360412 -228.213614) (xy 91.389889 -228.28346) (xy 91.411775 -228.356043)
			(xy 91.425822 -228.430541) (xy 91.431871 -228.506111) (xy 91.429852 -228.581895) (xy 91.41979 -228.657035)
			(xy 91.401798 -228.73068) (xy 91.37608 -228.801996) (xy 91.342928 -228.870173) (xy 91.302716 -228.934441)
			(xy 91.255901 -228.99407) (xy 91.203013 -229.048386) (xy 91.144651 -229.096772) (xy 91.081476 -229.13868)
			(xy 91.014205 -229.173636) (xy 90.9436 -229.201243) (xy 90.870459 -229.221189) (xy 90.795614 -229.233248)
			(xy 90.71991 -229.237283) (xy 90.644206 -229.233248) (xy 90.569361 -229.221189) (xy 90.49622 -229.201243)
			(xy 90.425615 -229.173636) (xy 90.358344 -229.13868) (xy 90.295169 -229.096772) (xy 90.236807 -229.048386)
			(xy 90.183919 -228.99407) (xy 90.137104 -228.934441) (xy 90.096892 -228.870173) (xy 90.06374 -228.801996)
			(xy 90.038022 -228.73068) (xy 90.02003 -228.657035) (xy 90.009968 -228.581895) (xy 90.007949 -228.506111)
			(xy 88.891871 -228.506111) (xy 88.889852 -228.581895) (xy 88.87979 -228.657035) (xy 88.861798 -228.73068)
			(xy 88.83608 -228.801996) (xy 88.802928 -228.870173) (xy 88.762716 -228.934441) (xy 88.715901 -228.99407)
			(xy 88.663013 -229.048386) (xy 88.604651 -229.096772) (xy 88.541476 -229.13868) (xy 88.474205 -229.173636)
			(xy 88.4036 -229.201243) (xy 88.330459 -229.221189) (xy 88.255614 -229.233248) (xy 88.17991 -229.237283)
			(xy 88.104206 -229.233248) (xy 88.029361 -229.221189) (xy 87.95622 -229.201243) (xy 87.885615 -229.173636)
			(xy 87.818344 -229.13868) (xy 87.755169 -229.096772) (xy 87.696807 -229.048386) (xy 87.643919 -228.99407)
			(xy 87.597104 -228.934441) (xy 87.556892 -228.870173) (xy 87.52374 -228.801996) (xy 87.498022 -228.73068)
			(xy 87.48003 -228.657035) (xy 87.469968 -228.581895) (xy 87.467949 -228.506111) (xy 86.351871 -228.506111)
			(xy 86.349852 -228.581895) (xy 86.33979 -228.657035) (xy 86.321798 -228.73068) (xy 86.29608 -228.801996)
			(xy 86.262928 -228.870173) (xy 86.222716 -228.934441) (xy 86.175901 -228.99407) (xy 86.123013 -229.048386)
			(xy 86.064651 -229.096772) (xy 86.001476 -229.13868) (xy 85.934205 -229.173636) (xy 85.8636 -229.201243)
			(xy 85.790459 -229.221189) (xy 85.715614 -229.233248) (xy 85.63991 -229.237283) (xy 85.564206 -229.233248)
			(xy 85.489361 -229.221189) (xy 85.41622 -229.201243) (xy 85.345615 -229.173636) (xy 85.278344 -229.13868)
			(xy 85.215169 -229.096772) (xy 85.156807 -229.048386) (xy 85.103919 -228.99407) (xy 85.057104 -228.934441)
			(xy 85.016892 -228.870173) (xy 84.98374 -228.801996) (xy 84.958022 -228.73068) (xy 84.94003 -228.657035)
			(xy 84.929968 -228.581895) (xy 84.927949 -228.506111) (xy 82.290588 -228.506111) (xy 82.290339 -228.506179)
			(xy 82.215494 -228.518238) (xy 82.13979 -228.522273) (xy 82.064086 -228.518238) (xy 81.989241 -228.506179)
			(xy 81.9161 -228.486233) (xy 81.845495 -228.458626) (xy 81.778224 -228.42367) (xy 81.715049 -228.381762)
			(xy 81.656687 -228.333376) (xy 81.603799 -228.27906) (xy 81.556984 -228.219431) (xy 81.516772 -228.155163)
			(xy 81.48362 -228.086986) (xy 81.457902 -228.01567) (xy 81.43991 -227.942025) (xy 81.429848 -227.866885)
			(xy 81.427829 -227.791101) (xy 80.311751 -227.791101) (xy 80.309732 -227.866885) (xy 80.29967 -227.942025)
			(xy 80.281678 -228.01567) (xy 80.25596 -228.086986) (xy 80.222808 -228.155163) (xy 80.182596 -228.219431)
			(xy 80.135781 -228.27906) (xy 80.082893 -228.333376) (xy 80.024531 -228.381762) (xy 79.961356 -228.42367)
			(xy 79.894085 -228.458626) (xy 79.82348 -228.486233) (xy 79.750339 -228.506179) (xy 79.675494 -228.518238)
			(xy 79.59979 -228.522273) (xy 79.524086 -228.518238) (xy 79.449241 -228.506179) (xy 79.3761 -228.486233)
			(xy 79.305495 -228.458626) (xy 79.238224 -228.42367) (xy 79.175049 -228.381762) (xy 79.116687 -228.333376)
			(xy 79.063799 -228.27906) (xy 79.016984 -228.219431) (xy 78.976772 -228.155163) (xy 78.94362 -228.086986)
			(xy 78.917902 -228.01567) (xy 78.89991 -227.942025) (xy 78.889848 -227.866885) (xy 78.887829 -227.791101)
			(xy 77.771751 -227.791101) (xy 77.769732 -227.866885) (xy 77.75967 -227.942025) (xy 77.741678 -228.01567)
			(xy 77.71596 -228.086986) (xy 77.682808 -228.155163) (xy 77.642596 -228.219431) (xy 77.595781 -228.27906)
			(xy 77.542893 -228.333376) (xy 77.484531 -228.381762) (xy 77.421356 -228.42367) (xy 77.354085 -228.458626)
			(xy 77.28348 -228.486233) (xy 77.210339 -228.506179) (xy 77.135494 -228.518238) (xy 77.05979 -228.522273)
			(xy 76.984086 -228.518238) (xy 76.909241 -228.506179) (xy 76.8361 -228.486233) (xy 76.765495 -228.458626)
			(xy 76.698224 -228.42367) (xy 76.635049 -228.381762) (xy 76.576687 -228.333376) (xy 76.523799 -228.27906)
			(xy 76.476984 -228.219431) (xy 76.436772 -228.155163) (xy 76.40362 -228.086986) (xy 76.377902 -228.01567)
			(xy 76.35991 -227.942025) (xy 76.349848 -227.866885) (xy 76.347829 -227.791101) (xy 75.231751 -227.791101)
			(xy 75.229732 -227.866885) (xy 75.21967 -227.942025) (xy 75.201678 -228.01567) (xy 75.17596 -228.086986)
			(xy 75.142808 -228.155163) (xy 75.102596 -228.219431) (xy 75.055781 -228.27906) (xy 75.002893 -228.333376)
			(xy 74.944531 -228.381762) (xy 74.881356 -228.42367) (xy 74.814085 -228.458626) (xy 74.74348 -228.486233)
			(xy 74.670339 -228.506179) (xy 74.595494 -228.518238) (xy 74.51979 -228.522273) (xy 74.444086 -228.518238)
			(xy 74.369241 -228.506179) (xy 74.2961 -228.486233) (xy 74.225495 -228.458626) (xy 74.158224 -228.42367)
			(xy 74.095049 -228.381762) (xy 74.036687 -228.333376) (xy 73.983799 -228.27906) (xy 73.936984 -228.219431)
			(xy 73.896772 -228.155163) (xy 73.86362 -228.086986) (xy 73.837902 -228.01567) (xy 73.81991 -227.942025)
			(xy 73.809848 -227.866885) (xy 73.807829 -227.791101) (xy 72.691751 -227.791101) (xy 72.689732 -227.866885)
			(xy 72.67967 -227.942025) (xy 72.661678 -228.01567) (xy 72.63596 -228.086986) (xy 72.602808 -228.155163)
			(xy 72.562596 -228.219431) (xy 72.515781 -228.27906) (xy 72.462893 -228.333376) (xy 72.404531 -228.381762)
			(xy 72.341356 -228.42367) (xy 72.274085 -228.458626) (xy 72.20348 -228.486233) (xy 72.130339 -228.506179)
			(xy 72.055494 -228.518238) (xy 71.97979 -228.522273) (xy 71.904086 -228.518238) (xy 71.829241 -228.506179)
			(xy 71.7561 -228.486233) (xy 71.685495 -228.458626) (xy 71.618224 -228.42367) (xy 71.555049 -228.381762)
			(xy 71.496687 -228.333376) (xy 71.443799 -228.27906) (xy 71.396984 -228.219431) (xy 71.356772 -228.155163)
			(xy 71.32362 -228.086986) (xy 71.297902 -228.01567) (xy 71.27991 -227.942025) (xy 71.269848 -227.866885)
			(xy 71.267829 -227.791101) (xy 70.151751 -227.791101) (xy 70.149732 -227.866885) (xy 70.13967 -227.942025)
			(xy 70.121678 -228.01567) (xy 70.09596 -228.086986) (xy 70.062808 -228.155163) (xy 70.022596 -228.219431)
			(xy 69.975781 -228.27906) (xy 69.922893 -228.333376) (xy 69.864531 -228.381762) (xy 69.801356 -228.42367)
			(xy 69.734085 -228.458626) (xy 69.66348 -228.486233) (xy 69.590339 -228.506179) (xy 69.515494 -228.518238)
			(xy 69.43979 -228.522273) (xy 69.364086 -228.518238) (xy 69.289241 -228.506179) (xy 69.2161 -228.486233)
			(xy 69.145495 -228.458626) (xy 69.078224 -228.42367) (xy 69.015049 -228.381762) (xy 68.956687 -228.333376)
			(xy 68.903799 -228.27906) (xy 68.856984 -228.219431) (xy 68.816772 -228.155163) (xy 68.78362 -228.086986)
			(xy 68.757902 -228.01567) (xy 68.73991 -227.942025) (xy 68.729848 -227.866885) (xy 68.727829 -227.791101)
			(xy 67.611751 -227.791101) (xy 67.609732 -227.866885) (xy 67.59967 -227.942025) (xy 67.581678 -228.01567)
			(xy 67.55596 -228.086986) (xy 67.522808 -228.155163) (xy 67.482596 -228.219431) (xy 67.435781 -228.27906)
			(xy 67.382893 -228.333376) (xy 67.324531 -228.381762) (xy 67.261356 -228.42367) (xy 67.194085 -228.458626)
			(xy 67.12348 -228.486233) (xy 67.050339 -228.506179) (xy 66.975494 -228.518238) (xy 66.89979 -228.522273)
			(xy 66.824086 -228.518238) (xy 66.749241 -228.506179) (xy 66.6761 -228.486233) (xy 66.605495 -228.458626)
			(xy 66.538224 -228.42367) (xy 66.475049 -228.381762) (xy 66.416687 -228.333376) (xy 66.363799 -228.27906)
			(xy 66.316984 -228.219431) (xy 66.276772 -228.155163) (xy 66.24362 -228.086986) (xy 66.217902 -228.01567)
			(xy 66.19991 -227.942025) (xy 66.189848 -227.866885) (xy 66.187829 -227.791101) (xy 65.071751 -227.791101)
			(xy 65.069732 -227.866885) (xy 65.05967 -227.942025) (xy 65.041678 -228.01567) (xy 65.01596 -228.086986)
			(xy 64.982808 -228.155163) (xy 64.942596 -228.219431) (xy 64.895781 -228.27906) (xy 64.842893 -228.333376)
			(xy 64.784531 -228.381762) (xy 64.721356 -228.42367) (xy 64.654085 -228.458626) (xy 64.58348 -228.486233)
			(xy 64.510339 -228.506179) (xy 64.435494 -228.518238) (xy 64.35979 -228.522273) (xy 64.284086 -228.518238)
			(xy 64.209241 -228.506179) (xy 64.1361 -228.486233) (xy 64.065495 -228.458626) (xy 63.998224 -228.42367)
			(xy 63.935049 -228.381762) (xy 63.876687 -228.333376) (xy 63.823799 -228.27906) (xy 63.776984 -228.219431)
			(xy 63.736772 -228.155163) (xy 63.70362 -228.086986) (xy 63.677902 -228.01567) (xy 63.65991 -227.942025)
			(xy 63.649848 -227.866885) (xy 63.647829 -227.791101) (xy 42.474432 -227.791101) (xy 42.525324 -227.827542)
			(xy 42.614813 -227.901469) (xy 42.698988 -227.981395) (xy 42.777449 -228.066938) (xy 42.849821 -228.157689)
			(xy 42.91576 -228.253218) (xy 42.974951 -228.353068) (xy 43.027112 -228.456764) (xy 43.071995 -228.563811)
			(xy 43.109385 -228.6737) (xy 43.139105 -228.785907) (xy 43.161013 -228.899897) (xy 43.175004 -229.015126)
			(xy 43.181013 -229.131047) (xy 43.179009 -229.247105) (xy 43.169003 -229.362749) (xy 43.151043 -229.477427)
			(xy 43.125213 -229.590593) (xy 43.091638 -229.701707) (xy 43.06342 -229.776111) (xy 86.197949 -229.776111)
			(xy 86.203998 -229.700541) (xy 86.218045 -229.626043) (xy 86.239931 -229.55346) (xy 86.269408 -229.483614)
			(xy 86.306143 -229.417297) (xy 86.349718 -229.355261) (xy 86.39964 -229.298208) (xy 86.455344 -229.246784)
			(xy 86.516199 -229.201573) (xy 86.581514 -229.163086) (xy 86.65055 -229.13176) (xy 86.722525 -229.10795)
			(xy 86.796623 -229.091925) (xy 86.872004 -229.083866) (xy 86.90991 -229.083362) (xy 86.947816 -229.083866)
			(xy 87.023197 -229.091925) (xy 87.097295 -229.10795) (xy 87.16927 -229.13176) (xy 87.238306 -229.163086)
			(xy 87.303621 -229.201573) (xy 87.364476 -229.246784) (xy 87.42018 -229.298208) (xy 87.470102 -229.355261)
			(xy 87.513677 -229.417297) (xy 87.550412 -229.483614) (xy 87.579889 -229.55346) (xy 87.601775 -229.626043)
			(xy 87.615822 -229.700541) (xy 87.621871 -229.776111) (xy 88.737949 -229.776111) (xy 88.743998 -229.700541)
			(xy 88.758045 -229.626043) (xy 88.779931 -229.55346) (xy 88.809408 -229.483614) (xy 88.846143 -229.417297)
			(xy 88.889718 -229.355261) (xy 88.93964 -229.298208) (xy 88.995344 -229.246784) (xy 89.056199 -229.201573)
			(xy 89.121514 -229.163086) (xy 89.19055 -229.13176) (xy 89.262525 -229.10795) (xy 89.336623 -229.091925)
			(xy 89.412004 -229.083866) (xy 89.44991 -229.083362) (xy 89.487816 -229.083866) (xy 89.563197 -229.091925)
			(xy 89.637295 -229.10795) (xy 89.70927 -229.13176) (xy 89.778306 -229.163086) (xy 89.843621 -229.201573)
			(xy 89.904476 -229.246784) (xy 89.96018 -229.298208) (xy 90.010102 -229.355261) (xy 90.053677 -229.417297)
			(xy 90.090412 -229.483614) (xy 90.119889 -229.55346) (xy 90.141775 -229.626043) (xy 90.155822 -229.700541)
			(xy 90.161871 -229.776111) (xy 91.277949 -229.776111) (xy 91.283998 -229.700541) (xy 91.298045 -229.626043)
			(xy 91.319931 -229.55346) (xy 91.349408 -229.483614) (xy 91.386143 -229.417297) (xy 91.429718 -229.355261)
			(xy 91.47964 -229.298208) (xy 91.535344 -229.246784) (xy 91.596199 -229.201573) (xy 91.661514 -229.163086)
			(xy 91.73055 -229.13176) (xy 91.802525 -229.10795) (xy 91.876623 -229.091925) (xy 91.952004 -229.083866)
			(xy 91.98991 -229.083362) (xy 92.027816 -229.083866) (xy 92.103197 -229.091925) (xy 92.177295 -229.10795)
			(xy 92.24927 -229.13176) (xy 92.318306 -229.163086) (xy 92.383621 -229.201573) (xy 92.444476 -229.246784)
			(xy 92.50018 -229.298208) (xy 92.550102 -229.355261) (xy 92.593677 -229.417297) (xy 92.630412 -229.483614)
			(xy 92.659889 -229.55346) (xy 92.681775 -229.626043) (xy 92.695822 -229.700541) (xy 92.701871 -229.776111)
			(xy 92.699852 -229.851895) (xy 92.68979 -229.927035) (xy 92.671798 -230.00068) (xy 92.64608 -230.071996)
			(xy 92.612928 -230.140173) (xy 92.572716 -230.204441) (xy 92.525901 -230.26407) (xy 92.473013 -230.318386)
			(xy 92.414651 -230.366772) (xy 92.351476 -230.40868) (xy 92.284205 -230.443636) (xy 92.2136 -230.471243)
			(xy 92.177855 -230.480991) (xy 93.154757 -230.480991) (xy 93.160779 -230.364808) (xy 93.174802 -230.249317)
			(xy 93.19676 -230.135069) (xy 93.226547 -230.022608) (xy 93.264022 -229.91247) (xy 93.309007 -229.80518)
			(xy 93.361286 -229.701249) (xy 93.420611 -229.601173) (xy 93.486699 -229.505427) (xy 93.559235 -229.41447)
			(xy 93.637874 -229.328734) (xy 93.72224 -229.248627) (xy 93.811932 -229.174531) (xy 93.906522 -229.106801)
			(xy 94.00556 -229.045757) (xy 94.108573 -228.991692) (xy 94.21507 -228.944862) (xy 94.324545 -228.905491)
			(xy 94.436475 -228.873767) (xy 94.550327 -228.849841) (xy 94.665559 -228.833827) (xy 94.781621 -228.8258)
			(xy 94.83979 -228.825298) (xy 94.897959 -228.8258) (xy 95.014021 -228.833827) (xy 95.129253 -228.849841)
			(xy 95.243105 -228.873767) (xy 95.355035 -228.905491) (xy 95.46451 -228.944862) (xy 95.571007 -228.991692)
			(xy 95.67402 -229.045757) (xy 95.773058 -229.106801) (xy 95.867648 -229.174531) (xy 95.95734 -229.248627)
			(xy 96.041706 -229.328734) (xy 96.120345 -229.41447) (xy 96.192881 -229.505427) (xy 96.258969 -229.601173)
			(xy 96.318294 -229.701249) (xy 96.370573 -229.80518) (xy 96.415558 -229.91247) (xy 96.453033 -230.022608)
			(xy 96.48282 -230.135069) (xy 96.504778 -230.249317) (xy 96.518801 -230.364808) (xy 96.524823 -230.480991)
			(xy 96.522815 -230.597313) (xy 96.512786 -230.713219) (xy 96.494785 -230.828156) (xy 96.468897 -230.941579)
			(xy 96.435246 -231.052944) (xy 96.393992 -231.161723) (xy 96.345331 -231.267397) (xy 96.289495 -231.369461)
			(xy 96.226752 -231.46743) (xy 96.157398 -231.560837) (xy 96.081766 -231.649237) (xy 96.000215 -231.732208)
			(xy 95.913134 -231.809355) (xy 95.820938 -231.88031) (xy 95.724066 -231.944736) (xy 95.622981 -232.002325)
			(xy 95.518163 -232.052802) (xy 95.410112 -232.095928) (xy 95.299344 -232.131497) (xy 95.186385 -232.159339)
			(xy 95.071775 -232.179321) (xy 94.95606 -232.191348) (xy 94.83979 -232.195364) (xy 94.72352 -232.191348)
			(xy 94.607805 -232.179321) (xy 94.493195 -232.159339) (xy 94.380236 -232.131497) (xy 94.269468 -232.095928)
			(xy 94.161417 -232.052802) (xy 94.056599 -232.002325) (xy 93.955514 -231.944736) (xy 93.858642 -231.88031)
			(xy 93.766446 -231.809355) (xy 93.679365 -231.732208) (xy 93.597814 -231.649237) (xy 93.522182 -231.560837)
			(xy 93.452828 -231.46743) (xy 93.390085 -231.369461) (xy 93.334249 -231.267397) (xy 93.285588 -231.161723)
			(xy 93.244334 -231.052944) (xy 93.210683 -230.941579) (xy 93.184795 -230.828156) (xy 93.166794 -230.713219)
			(xy 93.156765 -230.597313) (xy 93.154757 -230.480991) (xy 92.177855 -230.480991) (xy 92.140459 -230.491189)
			(xy 92.065614 -230.503248) (xy 91.98991 -230.507283) (xy 91.914206 -230.503248) (xy 91.839361 -230.491189)
			(xy 91.76622 -230.471243) (xy 91.695615 -230.443636) (xy 91.628344 -230.40868) (xy 91.565169 -230.366772)
			(xy 91.506807 -230.318386) (xy 91.453919 -230.26407) (xy 91.407104 -230.204441) (xy 91.366892 -230.140173)
			(xy 91.33374 -230.071996) (xy 91.308022 -230.00068) (xy 91.29003 -229.927035) (xy 91.279968 -229.851895)
			(xy 91.277949 -229.776111) (xy 90.161871 -229.776111) (xy 90.159852 -229.851895) (xy 90.14979 -229.927035)
			(xy 90.131798 -230.00068) (xy 90.10608 -230.071996) (xy 90.072928 -230.140173) (xy 90.032716 -230.204441)
			(xy 89.985901 -230.26407) (xy 89.933013 -230.318386) (xy 89.874651 -230.366772) (xy 89.811476 -230.40868)
			(xy 89.744205 -230.443636) (xy 89.6736 -230.471243) (xy 89.600459 -230.491189) (xy 89.525614 -230.503248)
			(xy 89.44991 -230.507283) (xy 89.374206 -230.503248) (xy 89.299361 -230.491189) (xy 89.22622 -230.471243)
			(xy 89.155615 -230.443636) (xy 89.088344 -230.40868) (xy 89.025169 -230.366772) (xy 88.966807 -230.318386)
			(xy 88.913919 -230.26407) (xy 88.867104 -230.204441) (xy 88.826892 -230.140173) (xy 88.79374 -230.071996)
			(xy 88.768022 -230.00068) (xy 88.75003 -229.927035) (xy 88.739968 -229.851895) (xy 88.737949 -229.776111)
			(xy 87.621871 -229.776111) (xy 87.619852 -229.851895) (xy 87.60979 -229.927035) (xy 87.591798 -230.00068)
			(xy 87.56608 -230.071996) (xy 87.532928 -230.140173) (xy 87.492716 -230.204441) (xy 87.445901 -230.26407)
			(xy 87.393013 -230.318386) (xy 87.334651 -230.366772) (xy 87.271476 -230.40868) (xy 87.204205 -230.443636)
			(xy 87.1336 -230.471243) (xy 87.060459 -230.491189) (xy 86.985614 -230.503248) (xy 86.90991 -230.507283)
			(xy 86.834206 -230.503248) (xy 86.759361 -230.491189) (xy 86.68622 -230.471243) (xy 86.615615 -230.443636)
			(xy 86.548344 -230.40868) (xy 86.485169 -230.366772) (xy 86.426807 -230.318386) (xy 86.373919 -230.26407)
			(xy 86.327104 -230.204441) (xy 86.286892 -230.140173) (xy 86.25374 -230.071996) (xy 86.228022 -230.00068)
			(xy 86.21003 -229.927035) (xy 86.199968 -229.851895) (xy 86.197949 -229.776111) (xy 43.06342 -229.776111)
			(xy 43.050477 -229.81024) (xy 43.001926 -229.915674) (xy 42.946217 -230.017508) (xy 42.883615 -230.115256)
			(xy 42.814419 -230.208451) (xy 42.738957 -230.296651) (xy 42.65759 -230.379434) (xy 42.570706 -230.456407)
			(xy 42.525601 -230.491121) (xy 63.647829 -230.491121) (xy 63.653878 -230.415551) (xy 63.667925 -230.341053)
			(xy 63.689811 -230.26847) (xy 63.719288 -230.198624) (xy 63.756023 -230.132307) (xy 63.799598 -230.070271)
			(xy 63.84952 -230.013218) (xy 63.905224 -229.961794) (xy 63.966079 -229.916583) (xy 64.031394 -229.878096)
			(xy 64.10043 -229.84677) (xy 64.172405 -229.82296) (xy 64.246503 -229.806935) (xy 64.321884 -229.798876)
			(xy 64.35979 -229.798372) (xy 64.397696 -229.798876) (xy 64.473077 -229.806935) (xy 64.547175 -229.82296)
			(xy 64.61915 -229.84677) (xy 64.688186 -229.878096) (xy 64.753501 -229.916583) (xy 64.814356 -229.961794)
			(xy 64.87006 -230.013218) (xy 64.919982 -230.070271) (xy 64.963557 -230.132307) (xy 65.000292 -230.198624)
			(xy 65.029769 -230.26847) (xy 65.051655 -230.341053) (xy 65.065702 -230.415551) (xy 65.071751 -230.491121)
			(xy 66.187829 -230.491121) (xy 66.193878 -230.415551) (xy 66.207925 -230.341053) (xy 66.229811 -230.26847)
			(xy 66.259288 -230.198624) (xy 66.296023 -230.132307) (xy 66.339598 -230.070271) (xy 66.38952 -230.013218)
			(xy 66.445224 -229.961794) (xy 66.506079 -229.916583) (xy 66.571394 -229.878096) (xy 66.64043 -229.84677)
			(xy 66.712405 -229.82296) (xy 66.786503 -229.806935) (xy 66.861884 -229.798876) (xy 66.89979 -229.798372)
			(xy 66.937696 -229.798876) (xy 67.013077 -229.806935) (xy 67.087175 -229.82296) (xy 67.15915 -229.84677)
			(xy 67.228186 -229.878096) (xy 67.293501 -229.916583) (xy 67.354356 -229.961794) (xy 67.41006 -230.013218)
			(xy 67.459982 -230.070271) (xy 67.503557 -230.132307) (xy 67.540292 -230.198624) (xy 67.569769 -230.26847)
			(xy 67.591655 -230.341053) (xy 67.605702 -230.415551) (xy 67.611751 -230.491121) (xy 68.727829 -230.491121)
			(xy 68.733878 -230.415551) (xy 68.747925 -230.341053) (xy 68.769811 -230.26847) (xy 68.799288 -230.198624)
			(xy 68.836023 -230.132307) (xy 68.879598 -230.070271) (xy 68.92952 -230.013218) (xy 68.985224 -229.961794)
			(xy 69.046079 -229.916583) (xy 69.111394 -229.878096) (xy 69.18043 -229.84677) (xy 69.252405 -229.82296)
			(xy 69.326503 -229.806935) (xy 69.401884 -229.798876) (xy 69.43979 -229.798372) (xy 69.477696 -229.798876)
			(xy 69.553077 -229.806935) (xy 69.627175 -229.82296) (xy 69.69915 -229.84677) (xy 69.768186 -229.878096)
			(xy 69.833501 -229.916583) (xy 69.894356 -229.961794) (xy 69.95006 -230.013218) (xy 69.999982 -230.070271)
			(xy 70.043557 -230.132307) (xy 70.080292 -230.198624) (xy 70.109769 -230.26847) (xy 70.131655 -230.341053)
			(xy 70.145702 -230.415551) (xy 70.151751 -230.491121) (xy 71.267829 -230.491121) (xy 71.273878 -230.415551)
			(xy 71.287925 -230.341053) (xy 71.309811 -230.26847) (xy 71.339288 -230.198624) (xy 71.376023 -230.132307)
			(xy 71.419598 -230.070271) (xy 71.46952 -230.013218) (xy 71.525224 -229.961794) (xy 71.586079 -229.916583)
			(xy 71.651394 -229.878096) (xy 71.72043 -229.84677) (xy 71.792405 -229.82296) (xy 71.866503 -229.806935)
			(xy 71.941884 -229.798876) (xy 71.97979 -229.798372) (xy 72.017696 -229.798876) (xy 72.093077 -229.806935)
			(xy 72.167175 -229.82296) (xy 72.23915 -229.84677) (xy 72.308186 -229.878096) (xy 72.373501 -229.916583)
			(xy 72.434356 -229.961794) (xy 72.49006 -230.013218) (xy 72.539982 -230.070271) (xy 72.583557 -230.132307)
			(xy 72.620292 -230.198624) (xy 72.649769 -230.26847) (xy 72.671655 -230.341053) (xy 72.685702 -230.415551)
			(xy 72.691751 -230.491121) (xy 73.807829 -230.491121) (xy 73.813878 -230.415551) (xy 73.827925 -230.341053)
			(xy 73.849811 -230.26847) (xy 73.879288 -230.198624) (xy 73.916023 -230.132307) (xy 73.959598 -230.070271)
			(xy 74.00952 -230.013218) (xy 74.065224 -229.961794) (xy 74.126079 -229.916583) (xy 74.191394 -229.878096)
			(xy 74.26043 -229.84677) (xy 74.332405 -229.82296) (xy 74.406503 -229.806935) (xy 74.481884 -229.798876)
			(xy 74.51979 -229.798372) (xy 74.557696 -229.798876) (xy 74.633077 -229.806935) (xy 74.707175 -229.82296)
			(xy 74.77915 -229.84677) (xy 74.848186 -229.878096) (xy 74.913501 -229.916583) (xy 74.974356 -229.961794)
			(xy 75.03006 -230.013218) (xy 75.079982 -230.070271) (xy 75.123557 -230.132307) (xy 75.160292 -230.198624)
			(xy 75.189769 -230.26847) (xy 75.211655 -230.341053) (xy 75.225702 -230.415551) (xy 75.231751 -230.491121)
			(xy 76.347829 -230.491121) (xy 76.353878 -230.415551) (xy 76.367925 -230.341053) (xy 76.389811 -230.26847)
			(xy 76.419288 -230.198624) (xy 76.456023 -230.132307) (xy 76.499598 -230.070271) (xy 76.54952 -230.013218)
			(xy 76.605224 -229.961794) (xy 76.666079 -229.916583) (xy 76.731394 -229.878096) (xy 76.80043 -229.84677)
			(xy 76.872405 -229.82296) (xy 76.946503 -229.806935) (xy 77.021884 -229.798876) (xy 77.05979 -229.798372)
			(xy 77.097696 -229.798876) (xy 77.173077 -229.806935) (xy 77.247175 -229.82296) (xy 77.31915 -229.84677)
			(xy 77.388186 -229.878096) (xy 77.453501 -229.916583) (xy 77.514356 -229.961794) (xy 77.57006 -230.013218)
			(xy 77.619982 -230.070271) (xy 77.663557 -230.132307) (xy 77.700292 -230.198624) (xy 77.729769 -230.26847)
			(xy 77.751655 -230.341053) (xy 77.765702 -230.415551) (xy 77.771751 -230.491121) (xy 78.887829 -230.491121)
			(xy 78.893878 -230.415551) (xy 78.907925 -230.341053) (xy 78.929811 -230.26847) (xy 78.959288 -230.198624)
			(xy 78.996023 -230.132307) (xy 79.039598 -230.070271) (xy 79.08952 -230.013218) (xy 79.145224 -229.961794)
			(xy 79.206079 -229.916583) (xy 79.271394 -229.878096) (xy 79.34043 -229.84677) (xy 79.412405 -229.82296)
			(xy 79.486503 -229.806935) (xy 79.561884 -229.798876) (xy 79.59979 -229.798372) (xy 79.637696 -229.798876)
			(xy 79.713077 -229.806935) (xy 79.787175 -229.82296) (xy 79.85915 -229.84677) (xy 79.928186 -229.878096)
			(xy 79.993501 -229.916583) (xy 80.054356 -229.961794) (xy 80.11006 -230.013218) (xy 80.159982 -230.070271)
			(xy 80.203557 -230.132307) (xy 80.240292 -230.198624) (xy 80.269769 -230.26847) (xy 80.291655 -230.341053)
			(xy 80.305702 -230.415551) (xy 80.311751 -230.491121) (xy 81.427829 -230.491121) (xy 81.433878 -230.415551)
			(xy 81.447925 -230.341053) (xy 81.469811 -230.26847) (xy 81.499288 -230.198624) (xy 81.536023 -230.132307)
			(xy 81.579598 -230.070271) (xy 81.62952 -230.013218) (xy 81.685224 -229.961794) (xy 81.746079 -229.916583)
			(xy 81.811394 -229.878096) (xy 81.88043 -229.84677) (xy 81.952405 -229.82296) (xy 82.026503 -229.806935)
			(xy 82.101884 -229.798876) (xy 82.13979 -229.798372) (xy 82.177696 -229.798876) (xy 82.253077 -229.806935)
			(xy 82.327175 -229.82296) (xy 82.39915 -229.84677) (xy 82.468186 -229.878096) (xy 82.533501 -229.916583)
			(xy 82.594356 -229.961794) (xy 82.65006 -230.013218) (xy 82.699982 -230.070271) (xy 82.743557 -230.132307)
			(xy 82.780292 -230.198624) (xy 82.809769 -230.26847) (xy 82.831655 -230.341053) (xy 82.845702 -230.415551)
			(xy 82.851751 -230.491121) (xy 82.849732 -230.566905) (xy 82.83967 -230.642045) (xy 82.821678 -230.71569)
			(xy 82.79596 -230.787006) (xy 82.762808 -230.855183) (xy 82.722596 -230.919451) (xy 82.675781 -230.97908)
			(xy 82.622893 -231.033396) (xy 82.607556 -231.046111) (xy 84.927949 -231.046111) (xy 84.933998 -230.970541)
			(xy 84.948045 -230.896043) (xy 84.969931 -230.82346) (xy 84.999408 -230.753614) (xy 85.036143 -230.687297)
			(xy 85.079718 -230.625261) (xy 85.12964 -230.568208) (xy 85.185344 -230.516784) (xy 85.246199 -230.471573)
			(xy 85.311514 -230.433086) (xy 85.38055 -230.40176) (xy 85.452525 -230.37795) (xy 85.526623 -230.361925)
			(xy 85.602004 -230.353866) (xy 85.63991 -230.353362) (xy 85.677816 -230.353866) (xy 85.753197 -230.361925)
			(xy 85.827295 -230.37795) (xy 85.89927 -230.40176) (xy 85.968306 -230.433086) (xy 86.033621 -230.471573)
			(xy 86.094476 -230.516784) (xy 86.15018 -230.568208) (xy 86.200102 -230.625261) (xy 86.243677 -230.687297)
			(xy 86.280412 -230.753614) (xy 86.309889 -230.82346) (xy 86.331775 -230.896043) (xy 86.345822 -230.970541)
			(xy 86.351871 -231.046111) (xy 87.467949 -231.046111) (xy 87.473998 -230.970541) (xy 87.488045 -230.896043)
			(xy 87.509931 -230.82346) (xy 87.539408 -230.753614) (xy 87.576143 -230.687297) (xy 87.619718 -230.625261)
			(xy 87.66964 -230.568208) (xy 87.725344 -230.516784) (xy 87.786199 -230.471573) (xy 87.851514 -230.433086)
			(xy 87.92055 -230.40176) (xy 87.992525 -230.37795) (xy 88.066623 -230.361925) (xy 88.142004 -230.353866)
			(xy 88.17991 -230.353362) (xy 88.217816 -230.353866) (xy 88.293197 -230.361925) (xy 88.367295 -230.37795)
			(xy 88.43927 -230.40176) (xy 88.508306 -230.433086) (xy 88.573621 -230.471573) (xy 88.634476 -230.516784)
			(xy 88.69018 -230.568208) (xy 88.740102 -230.625261) (xy 88.783677 -230.687297) (xy 88.820412 -230.753614)
			(xy 88.849889 -230.82346) (xy 88.871775 -230.896043) (xy 88.885822 -230.970541) (xy 88.891871 -231.046111)
			(xy 90.007949 -231.046111) (xy 90.013998 -230.970541) (xy 90.028045 -230.896043) (xy 90.049931 -230.82346)
			(xy 90.079408 -230.753614) (xy 90.116143 -230.687297) (xy 90.159718 -230.625261) (xy 90.20964 -230.568208)
			(xy 90.265344 -230.516784) (xy 90.326199 -230.471573) (xy 90.391514 -230.433086) (xy 90.46055 -230.40176)
			(xy 90.532525 -230.37795) (xy 90.606623 -230.361925) (xy 90.682004 -230.353866) (xy 90.71991 -230.353362)
			(xy 90.757816 -230.353866) (xy 90.833197 -230.361925) (xy 90.907295 -230.37795) (xy 90.97927 -230.40176)
			(xy 91.048306 -230.433086) (xy 91.113621 -230.471573) (xy 91.174476 -230.516784) (xy 91.23018 -230.568208)
			(xy 91.280102 -230.625261) (xy 91.323677 -230.687297) (xy 91.360412 -230.753614) (xy 91.389889 -230.82346)
			(xy 91.411775 -230.896043) (xy 91.425822 -230.970541) (xy 91.431871 -231.046111) (xy 91.429852 -231.121895)
			(xy 91.41979 -231.197035) (xy 91.401798 -231.27068) (xy 91.37608 -231.341996) (xy 91.342928 -231.410173)
			(xy 91.302716 -231.474441) (xy 91.255901 -231.53407) (xy 91.203013 -231.588386) (xy 91.144651 -231.636772)
			(xy 91.081476 -231.67868) (xy 91.014205 -231.713636) (xy 90.9436 -231.741243) (xy 90.870459 -231.761189)
			(xy 90.795614 -231.773248) (xy 90.71991 -231.777283) (xy 90.644206 -231.773248) (xy 90.569361 -231.761189)
			(xy 90.49622 -231.741243) (xy 90.425615 -231.713636) (xy 90.358344 -231.67868) (xy 90.295169 -231.636772)
			(xy 90.236807 -231.588386) (xy 90.183919 -231.53407) (xy 90.137104 -231.474441) (xy 90.096892 -231.410173)
			(xy 90.06374 -231.341996) (xy 90.038022 -231.27068) (xy 90.02003 -231.197035) (xy 90.009968 -231.121895)
			(xy 90.007949 -231.046111) (xy 88.891871 -231.046111) (xy 88.889852 -231.121895) (xy 88.87979 -231.197035)
			(xy 88.861798 -231.27068) (xy 88.83608 -231.341996) (xy 88.802928 -231.410173) (xy 88.762716 -231.474441)
			(xy 88.715901 -231.53407) (xy 88.663013 -231.588386) (xy 88.604651 -231.636772) (xy 88.541476 -231.67868)
			(xy 88.474205 -231.713636) (xy 88.4036 -231.741243) (xy 88.330459 -231.761189) (xy 88.255614 -231.773248)
			(xy 88.17991 -231.777283) (xy 88.104206 -231.773248) (xy 88.029361 -231.761189) (xy 87.95622 -231.741243)
			(xy 87.885615 -231.713636) (xy 87.818344 -231.67868) (xy 87.755169 -231.636772) (xy 87.696807 -231.588386)
			(xy 87.643919 -231.53407) (xy 87.597104 -231.474441) (xy 87.556892 -231.410173) (xy 87.52374 -231.341996)
			(xy 87.498022 -231.27068) (xy 87.48003 -231.197035) (xy 87.469968 -231.121895) (xy 87.467949 -231.046111)
			(xy 86.351871 -231.046111) (xy 86.349852 -231.121895) (xy 86.33979 -231.197035) (xy 86.321798 -231.27068)
			(xy 86.29608 -231.341996) (xy 86.262928 -231.410173) (xy 86.222716 -231.474441) (xy 86.175901 -231.53407)
			(xy 86.123013 -231.588386) (xy 86.064651 -231.636772) (xy 86.001476 -231.67868) (xy 85.934205 -231.713636)
			(xy 85.8636 -231.741243) (xy 85.790459 -231.761189) (xy 85.715614 -231.773248) (xy 85.63991 -231.777283)
			(xy 85.564206 -231.773248) (xy 85.489361 -231.761189) (xy 85.41622 -231.741243) (xy 85.345615 -231.713636)
			(xy 85.278344 -231.67868) (xy 85.215169 -231.636772) (xy 85.156807 -231.588386) (xy 85.103919 -231.53407)
			(xy 85.057104 -231.474441) (xy 85.016892 -231.410173) (xy 84.98374 -231.341996) (xy 84.958022 -231.27068)
			(xy 84.94003 -231.197035) (xy 84.929968 -231.121895) (xy 84.927949 -231.046111) (xy 82.607556 -231.046111)
			(xy 82.564531 -231.081782) (xy 82.501356 -231.12369) (xy 82.434085 -231.158646) (xy 82.36348 -231.186253)
			(xy 82.290339 -231.206199) (xy 82.215494 -231.218258) (xy 82.13979 -231.222293) (xy 82.064086 -231.218258)
			(xy 81.989241 -231.206199) (xy 81.9161 -231.186253) (xy 81.845495 -231.158646) (xy 81.778224 -231.12369)
			(xy 81.715049 -231.081782) (xy 81.656687 -231.033396) (xy 81.603799 -230.97908) (xy 81.556984 -230.919451)
			(xy 81.516772 -230.855183) (xy 81.48362 -230.787006) (xy 81.457902 -230.71569) (xy 81.43991 -230.642045)
			(xy 81.429848 -230.566905) (xy 81.427829 -230.491121) (xy 80.311751 -230.491121) (xy 80.309732 -230.566905)
			(xy 80.29967 -230.642045) (xy 80.281678 -230.71569) (xy 80.25596 -230.787006) (xy 80.222808 -230.855183)
			(xy 80.182596 -230.919451) (xy 80.135781 -230.97908) (xy 80.082893 -231.033396) (xy 80.024531 -231.081782)
			(xy 79.961356 -231.12369) (xy 79.894085 -231.158646) (xy 79.82348 -231.186253) (xy 79.750339 -231.206199)
			(xy 79.675494 -231.218258) (xy 79.59979 -231.222293) (xy 79.524086 -231.218258) (xy 79.449241 -231.206199)
			(xy 79.3761 -231.186253) (xy 79.305495 -231.158646) (xy 79.238224 -231.12369) (xy 79.175049 -231.081782)
			(xy 79.116687 -231.033396) (xy 79.063799 -230.97908) (xy 79.016984 -230.919451) (xy 78.976772 -230.855183)
			(xy 78.94362 -230.787006) (xy 78.917902 -230.71569) (xy 78.89991 -230.642045) (xy 78.889848 -230.566905)
			(xy 78.887829 -230.491121) (xy 77.771751 -230.491121) (xy 77.769732 -230.566905) (xy 77.75967 -230.642045)
			(xy 77.741678 -230.71569) (xy 77.71596 -230.787006) (xy 77.682808 -230.855183) (xy 77.642596 -230.919451)
			(xy 77.595781 -230.97908) (xy 77.542893 -231.033396) (xy 77.484531 -231.081782) (xy 77.421356 -231.12369)
			(xy 77.354085 -231.158646) (xy 77.28348 -231.186253) (xy 77.210339 -231.206199) (xy 77.135494 -231.218258)
			(xy 77.05979 -231.222293) (xy 76.984086 -231.218258) (xy 76.909241 -231.206199) (xy 76.8361 -231.186253)
			(xy 76.765495 -231.158646) (xy 76.698224 -231.12369) (xy 76.635049 -231.081782) (xy 76.576687 -231.033396)
			(xy 76.523799 -230.97908) (xy 76.476984 -230.919451) (xy 76.436772 -230.855183) (xy 76.40362 -230.787006)
			(xy 76.377902 -230.71569) (xy 76.35991 -230.642045) (xy 76.349848 -230.566905) (xy 76.347829 -230.491121)
			(xy 75.231751 -230.491121) (xy 75.229732 -230.566905) (xy 75.21967 -230.642045) (xy 75.201678 -230.71569)
			(xy 75.17596 -230.787006) (xy 75.142808 -230.855183) (xy 75.102596 -230.919451) (xy 75.055781 -230.97908)
			(xy 75.002893 -231.033396) (xy 74.944531 -231.081782) (xy 74.881356 -231.12369) (xy 74.814085 -231.158646)
			(xy 74.74348 -231.186253) (xy 74.670339 -231.206199) (xy 74.595494 -231.218258) (xy 74.51979 -231.222293)
			(xy 74.444086 -231.218258) (xy 74.369241 -231.206199) (xy 74.2961 -231.186253) (xy 74.225495 -231.158646)
			(xy 74.158224 -231.12369) (xy 74.095049 -231.081782) (xy 74.036687 -231.033396) (xy 73.983799 -230.97908)
			(xy 73.936984 -230.919451) (xy 73.896772 -230.855183) (xy 73.86362 -230.787006) (xy 73.837902 -230.71569)
			(xy 73.81991 -230.642045) (xy 73.809848 -230.566905) (xy 73.807829 -230.491121) (xy 72.691751 -230.491121)
			(xy 72.689732 -230.566905) (xy 72.67967 -230.642045) (xy 72.661678 -230.71569) (xy 72.63596 -230.787006)
			(xy 72.602808 -230.855183) (xy 72.562596 -230.919451) (xy 72.515781 -230.97908) (xy 72.462893 -231.033396)
			(xy 72.404531 -231.081782) (xy 72.341356 -231.12369) (xy 72.274085 -231.158646) (xy 72.20348 -231.186253)
			(xy 72.130339 -231.206199) (xy 72.055494 -231.218258) (xy 71.97979 -231.222293) (xy 71.904086 -231.218258)
			(xy 71.829241 -231.206199) (xy 71.7561 -231.186253) (xy 71.685495 -231.158646) (xy 71.618224 -231.12369)
			(xy 71.555049 -231.081782) (xy 71.496687 -231.033396) (xy 71.443799 -230.97908) (xy 71.396984 -230.919451)
			(xy 71.356772 -230.855183) (xy 71.32362 -230.787006) (xy 71.297902 -230.71569) (xy 71.27991 -230.642045)
			(xy 71.269848 -230.566905) (xy 71.267829 -230.491121) (xy 70.151751 -230.491121) (xy 70.149732 -230.566905)
			(xy 70.13967 -230.642045) (xy 70.121678 -230.71569) (xy 70.09596 -230.787006) (xy 70.062808 -230.855183)
			(xy 70.022596 -230.919451) (xy 69.975781 -230.97908) (xy 69.922893 -231.033396) (xy 69.864531 -231.081782)
			(xy 69.801356 -231.12369) (xy 69.734085 -231.158646) (xy 69.66348 -231.186253) (xy 69.590339 -231.206199)
			(xy 69.515494 -231.218258) (xy 69.43979 -231.222293) (xy 69.364086 -231.218258) (xy 69.289241 -231.206199)
			(xy 69.2161 -231.186253) (xy 69.145495 -231.158646) (xy 69.078224 -231.12369) (xy 69.015049 -231.081782)
			(xy 68.956687 -231.033396) (xy 68.903799 -230.97908) (xy 68.856984 -230.919451) (xy 68.816772 -230.855183)
			(xy 68.78362 -230.787006) (xy 68.757902 -230.71569) (xy 68.73991 -230.642045) (xy 68.729848 -230.566905)
			(xy 68.727829 -230.491121) (xy 67.611751 -230.491121) (xy 67.609732 -230.566905) (xy 67.59967 -230.642045)
			(xy 67.581678 -230.71569) (xy 67.55596 -230.787006) (xy 67.522808 -230.855183) (xy 67.482596 -230.919451)
			(xy 67.435781 -230.97908) (xy 67.382893 -231.033396) (xy 67.324531 -231.081782) (xy 67.261356 -231.12369)
			(xy 67.194085 -231.158646) (xy 67.12348 -231.186253) (xy 67.050339 -231.206199) (xy 66.975494 -231.218258)
			(xy 66.89979 -231.222293) (xy 66.824086 -231.218258) (xy 66.749241 -231.206199) (xy 66.6761 -231.186253)
			(xy 66.605495 -231.158646) (xy 66.538224 -231.12369) (xy 66.475049 -231.081782) (xy 66.416687 -231.033396)
			(xy 66.363799 -230.97908) (xy 66.316984 -230.919451) (xy 66.276772 -230.855183) (xy 66.24362 -230.787006)
			(xy 66.217902 -230.71569) (xy 66.19991 -230.642045) (xy 66.189848 -230.566905) (xy 66.187829 -230.491121)
			(xy 65.071751 -230.491121) (xy 65.069732 -230.566905) (xy 65.05967 -230.642045) (xy 65.041678 -230.71569)
			(xy 65.01596 -230.787006) (xy 64.982808 -230.855183) (xy 64.942596 -230.919451) (xy 64.895781 -230.97908)
			(xy 64.842893 -231.033396) (xy 64.784531 -231.081782) (xy 64.721356 -231.12369) (xy 64.654085 -231.158646)
			(xy 64.58348 -231.186253) (xy 64.510339 -231.206199) (xy 64.435494 -231.218258) (xy 64.35979 -231.222293)
			(xy 64.284086 -231.218258) (xy 64.209241 -231.206199) (xy 64.1361 -231.186253) (xy 64.065495 -231.158646)
			(xy 63.998224 -231.12369) (xy 63.935049 -231.081782) (xy 63.876687 -231.033396) (xy 63.823799 -230.97908)
			(xy 63.776984 -230.919451) (xy 63.736772 -230.855183) (xy 63.70362 -230.787006) (xy 63.677902 -230.71569)
			(xy 63.65991 -230.642045) (xy 63.649848 -230.566905) (xy 63.647829 -230.491121) (xy 42.525601 -230.491121)
			(xy 42.478719 -230.527202) (xy 42.382066 -230.591482) (xy 42.281209 -230.64894) (xy 42.176629 -230.699304)
			(xy 42.068822 -230.742332) (xy 41.958305 -230.77782) (xy 41.845602 -230.805599) (xy 41.731251 -230.825536)
			(xy 41.615797 -230.837537) (xy 41.49979 -230.841543) (xy 41.383783 -230.837537) (xy 41.268329 -230.825536)
			(xy 41.153978 -230.805599) (xy 41.041275 -230.77782) (xy 40.930758 -230.742332) (xy 40.822951 -230.699304)
			(xy 40.718371 -230.64894) (xy 40.617514 -230.591482) (xy 40.520861 -230.527202) (xy 40.428874 -230.456407)
			(xy 40.34199 -230.379434) (xy 40.260623 -230.296651) (xy 40.185161 -230.208451) (xy 40.115965 -230.115256)
			(xy 40.053363 -230.017508) (xy 39.997654 -229.915674) (xy 39.949103 -229.81024) (xy 39.907942 -229.701707)
			(xy 39.874367 -229.590593) (xy 39.848537 -229.477427) (xy 39.830577 -229.362749) (xy 39.820571 -229.247105)
			(xy 39.818567 -229.131047) (xy 29.755084 -229.131047) (xy 29.755084 -231.08412) (xy 29.755579 -231.10673)
			(xy 29.763588 -231.151235) (xy 29.779349 -231.19362) (xy 29.802364 -231.232545) (xy 29.831907 -231.26678)
			(xy 29.867044 -231.295246) (xy 29.906664 -231.317041) (xy 29.949518 -231.331478) (xy 29.99425 -231.338101)
			(xy 30.039449 -231.3367) (xy 30.083685 -231.327321) (xy 30.104842 -231.319324) (xy 30.145627 -231.303248)
			(xy 30.229545 -231.277863) (xy 30.315461 -231.2604) (xy 30.402629 -231.251011) (xy 30.490293 -231.249778)
			(xy 30.577692 -231.256711) (xy 30.664065 -231.27175) (xy 30.748663 -231.294764) (xy 30.830752 -231.325554)
			(xy 30.909617 -231.363852) (xy 30.984575 -231.409326) (xy 31.054974 -231.46158) (xy 31.120203 -231.52016)
			(xy 31.179696 -231.584559) (xy 31.232935 -231.654216) (xy 31.279458 -231.728527) (xy 31.318861 -231.806846)
			(xy 31.350803 -231.888494) (xy 31.375005 -231.97276) (xy 31.391257 -232.058913) (xy 31.399418 -232.146205)
			(xy 31.399418 -232.233486) (xy 34.599874 -232.233486) (xy 34.599874 -232.146586) (xy 34.607892 -232.060057)
			(xy 34.62386 -231.974637) (xy 34.647641 -231.891055) (xy 34.679033 -231.810023) (xy 34.717767 -231.732234)
			(xy 34.763514 -231.65835) (xy 34.815883 -231.589003) (xy 34.874427 -231.524783) (xy 34.938647 -231.466239)
			(xy 35.007994 -231.41387) (xy 35.081878 -231.368123) (xy 35.159667 -231.329389) (xy 35.240699 -231.297997)
			(xy 35.324281 -231.274216) (xy 35.409701 -231.258248) (xy 35.49623 -231.25023) (xy 35.53968 -231.249728)
			(xy 35.58313 -231.25023) (xy 35.669659 -231.258248) (xy 35.755079 -231.274216) (xy 35.838661 -231.297997)
			(xy 35.919693 -231.329389) (xy 35.997482 -231.368123) (xy 36.071366 -231.41387) (xy 36.140713 -231.466239)
			(xy 36.204933 -231.524783) (xy 36.263477 -231.589003) (xy 36.315846 -231.65835) (xy 36.361593 -231.732234)
			(xy 36.400327 -231.810023) (xy 36.431719 -231.891055) (xy 36.4555 -231.974637) (xy 36.471468 -232.060057)
			(xy 36.479486 -232.146586) (xy 36.479486 -232.233486) (xy 36.471468 -232.320015) (xy 36.4555 -232.405435)
			(xy 36.431719 -232.489017) (xy 36.400327 -232.570049) (xy 36.361593 -232.647838) (xy 36.315846 -232.721722)
			(xy 36.263477 -232.791069) (xy 36.204933 -232.855289) (xy 36.140713 -232.913833) (xy 36.071366 -232.966202)
			(xy 35.997482 -233.011949) (xy 35.919693 -233.050683) (xy 35.838661 -233.082075) (xy 35.755079 -233.105856)
			(xy 35.669659 -233.121824) (xy 35.58313 -233.129842) (xy 35.49623 -233.129842) (xy 35.409701 -233.121824)
			(xy 35.324281 -233.105856) (xy 35.240699 -233.082075) (xy 35.159667 -233.050683) (xy 35.081878 -233.011949)
			(xy 35.007994 -232.966202) (xy 34.938647 -232.913833) (xy 34.874427 -232.855289) (xy 34.815883 -232.791069)
			(xy 34.763514 -232.721722) (xy 34.717767 -232.647838) (xy 34.679033 -232.570049) (xy 34.647641 -232.489017)
			(xy 34.62386 -232.405435) (xy 34.607892 -232.320015) (xy 34.599874 -232.233486) (xy 31.399418 -232.233486)
			(xy 31.399418 -232.233878) (xy 31.391256 -232.32117) (xy 31.375004 -232.407323) (xy 31.350802 -232.491589)
			(xy 31.31886 -232.573236) (xy 31.279456 -232.651555) (xy 31.232933 -232.725866) (xy 31.179694 -232.795523)
			(xy 31.120201 -232.859922) (xy 31.054972 -232.918502) (xy 30.984573 -232.970756) (xy 30.909615 -233.016229)
			(xy 30.830749 -233.054527) (xy 30.74866 -233.085317) (xy 30.664062 -233.108331) (xy 30.577689 -233.123369)
			(xy 30.49029 -233.130302) (xy 30.402626 -233.129069) (xy 30.315458 -233.11968) (xy 30.229542 -233.102217)
			(xy 30.145624 -233.076831) (xy 30.104842 -233.060748) (xy 30.083714 -233.052681) (xy 30.039473 -233.043317)
			(xy 29.994273 -233.041931) (xy 29.949541 -233.048565) (xy 29.90669 -233.063012) (xy 29.867072 -233.084815)
			(xy 29.831938 -233.113285) (xy 29.802397 -233.147524) (xy 29.779383 -233.186451) (xy 29.763621 -233.228836)
			(xy 29.755609 -233.273342) (xy 29.755084 -233.295952) (xy 29.755084 -233.62412) (xy 29.755579 -233.64673)
			(xy 29.763588 -233.691235) (xy 29.779349 -233.73362) (xy 29.802364 -233.772545) (xy 29.831907 -233.80678)
			(xy 29.867044 -233.835246) (xy 29.906664 -233.857041) (xy 29.949518 -233.871478) (xy 29.99425 -233.878101)
			(xy 30.039449 -233.8767) (xy 30.083685 -233.867321) (xy 30.104842 -233.859324) (xy 30.144712 -233.843589)
			(xy 30.226707 -233.818599) (xy 30.310637 -233.801176) (xy 30.395804 -233.791464) (xy 30.481501 -233.789545)
			(xy 30.567018 -233.795433) (xy 30.651644 -233.80908) (xy 30.734676 -233.830374) (xy 30.815426 -233.859136)
			(xy 30.893222 -233.895128) (xy 30.96742 -233.938052) (xy 31.037403 -233.987551) (xy 31.10259 -234.043214)
			(xy 31.16244 -234.10458) (xy 31.216457 -234.171138) (xy 31.264191 -234.242336) (xy 31.305247 -234.317584)
			(xy 31.339284 -234.396256) (xy 31.366018 -234.477699) (xy 31.385229 -234.561237) (xy 31.396757 -234.646178)
			(xy 31.400506 -234.731815) (xy 31.396445 -234.817438) (xy 31.384608 -234.902335) (xy 31.365092 -234.985803)
			(xy 31.338061 -235.067149) (xy 31.303737 -235.145696) (xy 31.283402 -235.183426) (xy 31.273195 -235.202894)
			(xy 31.258905 -235.24446) (xy 31.251981 -235.287865) (xy 31.25263 -235.331814) (xy 31.260831 -235.374996)
			(xy 31.276341 -235.416123) (xy 31.298696 -235.453966) (xy 31.327231 -235.487399) (xy 31.361092 -235.515423)
			(xy 31.399271 -235.537202) (xy 31.440628 -235.552086) (xy 31.483929 -235.559631) (xy 31.505906 -235.560108)
			(xy 34.493454 -235.560108) (xy 34.515428 -235.559639) (xy 34.558719 -235.552072) (xy 34.600064 -235.537172)
			(xy 34.63823 -235.515385) (xy 34.672081 -235.487358) (xy 34.700608 -235.453928) (xy 34.722961 -235.416089)
			(xy 34.738473 -235.37497) (xy 34.746683 -235.331796) (xy 34.747346 -235.287854) (xy 34.740442 -235.244452)
			(xy 34.726177 -235.202884) (xy 34.715958 -235.183426) (xy 34.695494 -235.145216) (xy 34.660862 -235.06575)
			(xy 34.633692 -234.983433) (xy 34.614214 -234.898966) (xy 34.602593 -234.813063) (xy 34.598929 -234.726456)
			(xy 34.603252 -234.63988) (xy 34.615526 -234.554069) (xy 34.635646 -234.469751) (xy 34.663442 -234.387644)
			(xy 34.698678 -234.308444) (xy 34.741054 -234.232823) (xy 34.79021 -234.161424) (xy 34.84573 -234.094853)
			(xy 34.907142 -234.033674) (xy 34.973924 -233.978408) (xy 35.04551 -233.929523) (xy 35.121291 -233.887436)
			(xy 35.200625 -233.852502) (xy 35.282837 -233.825019) (xy 35.36723 -233.805219) (xy 35.453088 -233.793272)
			(xy 35.53968 -233.789278) (xy 35.626272 -233.793272) (xy 35.71213 -233.805219) (xy 35.796523 -233.825019)
			(xy 35.878735 -233.852502) (xy 35.958069 -233.887436) (xy 36.03385 -233.929523) (xy 36.105436 -233.978408)
			(xy 36.172218 -234.033674) (xy 36.23363 -234.094853) (xy 36.28915 -234.161424) (xy 36.338306 -234.232823)
			(xy 36.380682 -234.308444) (xy 36.415918 -234.387644) (xy 36.443714 -234.469751) (xy 36.463834 -234.554069)
			(xy 36.476108 -234.63988) (xy 36.480431 -234.726456) (xy 36.476767 -234.813063) (xy 36.465146 -234.898966)
			(xy 36.445668 -234.983433) (xy 36.418498 -235.06575) (xy 36.383866 -235.145216) (xy 36.363402 -235.183426)
			(xy 36.353195 -235.202894) (xy 36.338905 -235.24446) (xy 36.331981 -235.287865) (xy 36.332524 -235.324646)
			(xy 85.804992 -235.324646) (xy 85.804992 -235.26471) (xy 85.812815 -235.205288) (xy 85.828328 -235.147395)
			(xy 85.851264 -235.092022) (xy 85.881231 -235.040116) (xy 85.917718 -234.992566) (xy 85.960098 -234.950186)
			(xy 86.007648 -234.913699) (xy 86.059554 -234.883732) (xy 86.114927 -234.860796) (xy 86.17282 -234.845283)
			(xy 86.232242 -234.83746) (xy 86.26221 -234.83697) (xy 86.292178 -234.83746) (xy 86.3516 -234.845283)
			(xy 86.409493 -234.860796) (xy 86.464866 -234.883732) (xy 86.516772 -234.913699) (xy 86.564322 -234.950186)
			(xy 86.606702 -234.992566) (xy 86.643189 -235.040116) (xy 86.673156 -235.092022) (xy 86.696092 -235.147395)
			(xy 86.711605 -235.205288) (xy 86.719428 -235.26471) (xy 86.719428 -235.324646) (xy 86.711605 -235.384068)
			(xy 86.696092 -235.441961) (xy 86.673156 -235.497334) (xy 86.643189 -235.54924) (xy 86.606702 -235.59679)
			(xy 86.564322 -235.63917) (xy 86.516772 -235.675657) (xy 86.464866 -235.705624) (xy 86.409493 -235.72856)
			(xy 86.3516 -235.744073) (xy 86.292178 -235.751896) (xy 86.232242 -235.751896) (xy 86.17282 -235.744073)
			(xy 86.114927 -235.72856) (xy 86.059554 -235.705624) (xy 86.007648 -235.675657) (xy 85.960098 -235.63917)
			(xy 85.917718 -235.59679) (xy 85.881231 -235.54924) (xy 85.851264 -235.497334) (xy 85.828328 -235.441961)
			(xy 85.812815 -235.384068) (xy 85.804992 -235.324646) (xy 36.332524 -235.324646) (xy 36.33263 -235.331814)
			(xy 36.340831 -235.374996) (xy 36.356341 -235.416123) (xy 36.378696 -235.453966) (xy 36.407231 -235.487399)
			(xy 36.441092 -235.515423) (xy 36.479271 -235.537202) (xy 36.520628 -235.552086) (xy 36.563929 -235.559631)
			(xy 36.585906 -235.560108) (xy 36.854892 -235.560108) (xy 37.539164 -236.24438) (xy 81.805254 -236.24438)
			(xy 81.805254 -236.184444) (xy 81.813077 -236.125022) (xy 81.82859 -236.067129) (xy 81.851526 -236.011756)
			(xy 81.881493 -235.95985) (xy 81.91798 -235.9123) (xy 81.96036 -235.86992) (xy 82.00791 -235.833433)
			(xy 82.059816 -235.803466) (xy 82.115189 -235.78053) (xy 82.173082 -235.765017) (xy 82.232504 -235.757194)
			(xy 82.262472 -235.756704) (xy 82.29244 -235.757194) (xy 82.351862 -235.765017) (xy 82.409755 -235.78053)
			(xy 82.465128 -235.803466) (xy 82.517034 -235.833433) (xy 82.551427 -235.859824) (xy 84.200982 -235.859824)
			(xy 84.200982 -235.799888) (xy 84.208805 -235.740466) (xy 84.224318 -235.682573) (xy 84.247254 -235.6272)
			(xy 84.277221 -235.575294) (xy 84.313708 -235.527744) (xy 84.356088 -235.485364) (xy 84.403638 -235.448877)
			(xy 84.455544 -235.41891) (xy 84.510917 -235.395974) (xy 84.56881 -235.380461) (xy 84.628232 -235.372638)
			(xy 84.6582 -235.372148) (xy 84.688168 -235.372638) (xy 84.74759 -235.380461) (xy 84.805483 -235.395974)
			(xy 84.860856 -235.41891) (xy 84.912762 -235.448877) (xy 84.960312 -235.485364) (xy 85.002692 -235.527744)
			(xy 85.039179 -235.575294) (xy 85.069146 -235.6272) (xy 85.092082 -235.682573) (xy 85.107595 -235.740466)
			(xy 85.115418 -235.799888) (xy 85.115418 -235.859824) (xy 85.107595 -235.919246) (xy 85.092082 -235.977139)
			(xy 85.069146 -236.032512) (xy 85.039179 -236.084418) (xy 85.002692 -236.131968) (xy 84.960312 -236.174348)
			(xy 84.912762 -236.210835) (xy 84.860856 -236.240802) (xy 84.805483 -236.263738) (xy 84.74759 -236.279251)
			(xy 84.688168 -236.287074) (xy 84.628232 -236.287074) (xy 84.56881 -236.279251) (xy 84.510917 -236.263738)
			(xy 84.455544 -236.240802) (xy 84.403638 -236.210835) (xy 84.356088 -236.174348) (xy 84.313708 -236.131968)
			(xy 84.277221 -236.084418) (xy 84.247254 -236.032512) (xy 84.224318 -235.977139) (xy 84.208805 -235.919246)
			(xy 84.200982 -235.859824) (xy 82.551427 -235.859824) (xy 82.564584 -235.86992) (xy 82.606964 -235.9123)
			(xy 82.643451 -235.95985) (xy 82.673418 -236.011756) (xy 82.696354 -236.067129) (xy 82.711867 -236.125022)
			(xy 82.71969 -236.184444) (xy 82.71969 -236.24438) (xy 82.711867 -236.303802) (xy 82.696354 -236.361695)
			(xy 82.673418 -236.417068) (xy 82.643451 -236.468974) (xy 82.606964 -236.516524) (xy 82.564584 -236.558904)
			(xy 82.517034 -236.595391) (xy 82.465128 -236.625358) (xy 82.409755 -236.648294) (xy 82.351862 -236.663807)
			(xy 82.29244 -236.67163) (xy 82.232504 -236.67163) (xy 82.173082 -236.663807) (xy 82.115189 -236.648294)
			(xy 82.059816 -236.625358) (xy 82.00791 -236.595391) (xy 81.96036 -236.558904) (xy 81.91798 -236.516524)
			(xy 81.881493 -236.468974) (xy 81.851526 -236.417068) (xy 81.82859 -236.361695) (xy 81.813077 -236.303802)
			(xy 81.805254 -236.24438) (xy 37.539164 -236.24438) (xy 38.3733 -237.078516) (xy 83.002864 -237.078516)
			(xy 83.002864 -237.01858) (xy 83.010687 -236.959158) (xy 83.0262 -236.901265) (xy 83.049136 -236.845892)
			(xy 83.079103 -236.793986) (xy 83.11559 -236.746436) (xy 83.15797 -236.704056) (xy 83.20552 -236.667569)
			(xy 83.257426 -236.637602) (xy 83.312799 -236.614666) (xy 83.370692 -236.599153) (xy 83.430114 -236.59133)
			(xy 83.460082 -236.59084) (xy 83.49005 -236.59133) (xy 83.549472 -236.599153) (xy 83.607365 -236.614666)
			(xy 83.662738 -236.637602) (xy 83.714644 -236.667569) (xy 83.762194 -236.704056) (xy 83.804574 -236.746436)
			(xy 83.841061 -236.793986) (xy 83.871028 -236.845892) (xy 83.893964 -236.901265) (xy 83.909477 -236.959158)
			(xy 83.9173 -237.01858) (xy 83.9173 -237.078516) (xy 83.909477 -237.137938) (xy 83.893964 -237.195831)
			(xy 83.893845 -237.196118) (xy 86.831406 -237.196118) (xy 86.831406 -237.136182) (xy 86.839229 -237.07676)
			(xy 86.854742 -237.018867) (xy 86.877678 -236.963494) (xy 86.907645 -236.911588) (xy 86.944132 -236.864038)
			(xy 86.986512 -236.821658) (xy 87.034062 -236.785171) (xy 87.085968 -236.755204) (xy 87.141341 -236.732268)
			(xy 87.199234 -236.716755) (xy 87.258656 -236.708932) (xy 87.288624 -236.708442) (xy 87.318592 -236.708932)
			(xy 87.378014 -236.716755) (xy 87.435907 -236.732268) (xy 87.49128 -236.755204) (xy 87.543186 -236.785171)
			(xy 87.590736 -236.821658) (xy 87.633116 -236.864038) (xy 87.669603 -236.911588) (xy 87.69957 -236.963494)
			(xy 87.722506 -237.018867) (xy 87.738019 -237.07676) (xy 87.745842 -237.136182) (xy 87.745842 -237.196118)
			(xy 87.738019 -237.25554) (xy 87.722506 -237.313433) (xy 87.69957 -237.368806) (xy 87.669603 -237.420712)
			(xy 87.633116 -237.468262) (xy 87.590736 -237.510642) (xy 87.543186 -237.547129) (xy 87.49128 -237.577096)
			(xy 87.435907 -237.600032) (xy 87.378014 -237.615545) (xy 87.318592 -237.623368) (xy 87.258656 -237.623368)
			(xy 87.199234 -237.615545) (xy 87.141341 -237.600032) (xy 87.085968 -237.577096) (xy 87.034062 -237.547129)
			(xy 86.986512 -237.510642) (xy 86.944132 -237.468262) (xy 86.907645 -237.420712) (xy 86.877678 -237.368806)
			(xy 86.854742 -237.313433) (xy 86.839229 -237.25554) (xy 86.831406 -237.196118) (xy 83.893845 -237.196118)
			(xy 83.871028 -237.251204) (xy 83.841061 -237.30311) (xy 83.804574 -237.35066) (xy 83.762194 -237.39304)
			(xy 83.714644 -237.429527) (xy 83.662738 -237.459494) (xy 83.607365 -237.48243) (xy 83.549472 -237.497943)
			(xy 83.49005 -237.505766) (xy 83.430114 -237.505766) (xy 83.370692 -237.497943) (xy 83.312799 -237.48243)
			(xy 83.257426 -237.459494) (xy 83.20552 -237.429527) (xy 83.15797 -237.39304) (xy 83.11559 -237.35066)
			(xy 83.079103 -237.30311) (xy 83.049136 -237.251204) (xy 83.0262 -237.195831) (xy 83.010687 -237.137938)
			(xy 83.002864 -237.078516) (xy 38.3733 -237.078516) (xy 39.349172 -238.054388) (xy 43.923966 -238.054388)
			(xy 44.365164 -237.612936) (xy 44.387897 -237.590934) (xy 44.438089 -237.552421) (xy 44.492878 -237.520788)
			(xy 44.551328 -237.496577) (xy 44.612437 -237.480203) (xy 44.675161 -237.471945) (xy 44.738427 -237.471945)
			(xy 44.801151 -237.480203) (xy 44.86226 -237.496577) (xy 44.92071 -237.520788) (xy 44.975499 -237.552421)
			(xy 45.025691 -237.590934) (xy 45.070426 -237.635669) (xy 45.108939 -237.685861) (xy 45.140572 -237.74065)
			(xy 45.164783 -237.7991) (xy 45.181157 -237.860209) (xy 45.189415 -237.922933) (xy 45.189415 -237.986199)
			(xy 45.181157 -238.048923) (xy 45.16894 -238.094516) (xy 84.927422 -238.094516) (xy 84.927422 -238.03458)
			(xy 84.935245 -237.975158) (xy 84.950758 -237.917265) (xy 84.973694 -237.861892) (xy 85.003661 -237.809986)
			(xy 85.040148 -237.762436) (xy 85.082528 -237.720056) (xy 85.130078 -237.683569) (xy 85.181984 -237.653602)
			(xy 85.237357 -237.630666) (xy 85.29525 -237.615153) (xy 85.354672 -237.60733) (xy 85.38464 -237.60684)
			(xy 85.414608 -237.60733) (xy 85.47403 -237.615153) (xy 85.531923 -237.630666) (xy 85.587296 -237.653602)
			(xy 85.639202 -237.683569) (xy 85.686752 -237.720056) (xy 85.729132 -237.762436) (xy 85.765619 -237.809986)
			(xy 85.795586 -237.861892) (xy 85.818522 -237.917265) (xy 85.834035 -237.975158) (xy 85.841858 -238.03458)
			(xy 85.841858 -238.094516) (xy 85.834035 -238.153938) (xy 85.818522 -238.211831) (xy 85.795586 -238.267204)
			(xy 85.765619 -238.31911) (xy 85.729132 -238.36666) (xy 85.686752 -238.40904) (xy 85.639202 -238.445527)
			(xy 85.587296 -238.475494) (xy 85.531923 -238.49843) (xy 85.47403 -238.513943) (xy 85.414608 -238.521766)
			(xy 85.354672 -238.521766) (xy 85.29525 -238.513943) (xy 85.237357 -238.49843) (xy 85.181984 -238.475494)
			(xy 85.130078 -238.445527) (xy 85.082528 -238.40904) (xy 85.040148 -238.36666) (xy 85.003661 -238.31911)
			(xy 84.973694 -238.267204) (xy 84.950758 -238.211831) (xy 84.935245 -238.153938) (xy 84.927422 -238.094516)
			(xy 45.16894 -238.094516) (xy 45.164783 -238.110032) (xy 45.140572 -238.168482) (xy 45.108939 -238.223271)
			(xy 45.070426 -238.273463) (xy 45.048424 -238.296196) (xy 44.498006 -238.84636) (xy 44.486545 -238.858494)
			(xy 44.469834 -238.887374) (xy 44.46118 -238.9196) (xy 44.461175 -238.952967) (xy 44.46982 -238.985194)
			(xy 44.486524 -239.014079) (xy 44.498006 -239.026192) (xy 44.561023 -239.08918) (xy 80.45626 -239.08918)
			(xy 80.45626 -239.029244) (xy 80.464083 -238.969822) (xy 80.479596 -238.911929) (xy 80.502532 -238.856556)
			(xy 80.532499 -238.80465) (xy 80.568986 -238.7571) (xy 80.611366 -238.71472) (xy 80.658916 -238.678233)
			(xy 80.710822 -238.648266) (xy 80.766195 -238.62533) (xy 80.824088 -238.609817) (xy 80.88351 -238.601994)
			(xy 80.913478 -238.601504) (xy 80.943446 -238.601994) (xy 81.002868 -238.609817) (xy 81.060761 -238.62533)
			(xy 81.116134 -238.648266) (xy 81.16804 -238.678233) (xy 81.21559 -238.71472) (xy 81.23699 -238.73612)
			(xy 82.510866 -238.73612) (xy 82.510866 -238.676184) (xy 82.518689 -238.616762) (xy 82.534202 -238.558869)
			(xy 82.557138 -238.503496) (xy 82.587105 -238.45159) (xy 82.623592 -238.40404) (xy 82.665972 -238.36166)
			(xy 82.713522 -238.325173) (xy 82.765428 -238.295206) (xy 82.820801 -238.27227) (xy 82.878694 -238.256757)
			(xy 82.938116 -238.248934) (xy 82.968084 -238.248444) (xy 82.998052 -238.248934) (xy 83.057474 -238.256757)
			(xy 83.115367 -238.27227) (xy 83.17074 -238.295206) (xy 83.222646 -238.325173) (xy 83.270196 -238.36166)
			(xy 83.312576 -238.40404) (xy 83.349063 -238.45159) (xy 83.37903 -238.503496) (xy 83.401966 -238.558869)
			(xy 83.417479 -238.616762) (xy 83.425302 -238.676184) (xy 83.425302 -238.73612) (xy 83.417479 -238.795542)
			(xy 83.401966 -238.853435) (xy 83.37903 -238.908808) (xy 83.349063 -238.960714) (xy 83.312576 -239.008264)
			(xy 83.270196 -239.050644) (xy 83.222646 -239.087131) (xy 83.17074 -239.117098) (xy 83.115367 -239.140034)
			(xy 83.057474 -239.155547) (xy 82.998052 -239.16337) (xy 82.938116 -239.16337) (xy 82.878694 -239.155547)
			(xy 82.820801 -239.140034) (xy 82.765428 -239.117098) (xy 82.713522 -239.087131) (xy 82.665972 -239.050644)
			(xy 82.623592 -239.008264) (xy 82.587105 -238.960714) (xy 82.557138 -238.908808) (xy 82.534202 -238.853435)
			(xy 82.518689 -238.795542) (xy 82.510866 -238.73612) (xy 81.23699 -238.73612) (xy 81.25797 -238.7571)
			(xy 81.294457 -238.80465) (xy 81.324424 -238.856556) (xy 81.34736 -238.911929) (xy 81.362873 -238.969822)
			(xy 81.370696 -239.029244) (xy 81.370696 -239.08918) (xy 81.362873 -239.148602) (xy 81.34736 -239.206495)
			(xy 81.324424 -239.261868) (xy 81.294457 -239.313774) (xy 81.25797 -239.361324) (xy 81.21559 -239.403704)
			(xy 81.16804 -239.440191) (xy 81.116134 -239.470158) (xy 81.060761 -239.493094) (xy 81.002868 -239.508607)
			(xy 80.943446 -239.51643) (xy 80.88351 -239.51643) (xy 80.824088 -239.508607) (xy 80.766195 -239.493094)
			(xy 80.710822 -239.470158) (xy 80.658916 -239.440191) (xy 80.611366 -239.403704) (xy 80.568986 -239.361324)
			(xy 80.532499 -239.313774) (xy 80.502532 -239.261868) (xy 80.479596 -239.206495) (xy 80.464083 -239.148602)
			(xy 80.45626 -239.08918) (xy 44.561023 -239.08918) (xy 45.042836 -239.570768) (xy 45.064838 -239.593501)
			(xy 45.103351 -239.643693) (xy 45.134984 -239.698482) (xy 45.152783 -239.741452) (xy 84.00464 -239.741452)
			(xy 84.00464 -239.681516) (xy 84.012463 -239.622094) (xy 84.027976 -239.564201) (xy 84.050912 -239.508828)
			(xy 84.080879 -239.456922) (xy 84.117366 -239.409372) (xy 84.159746 -239.366992) (xy 84.207296 -239.330505)
			(xy 84.259202 -239.300538) (xy 84.314575 -239.277602) (xy 84.372468 -239.262089) (xy 84.43189 -239.254266)
			(xy 84.461858 -239.253776) (xy 84.491826 -239.254266) (xy 84.551248 -239.262089) (xy 84.609141 -239.277602)
			(xy 84.664514 -239.300538) (xy 84.71642 -239.330505) (xy 84.76397 -239.366992) (xy 84.80635 -239.409372)
			(xy 84.842837 -239.456922) (xy 84.872804 -239.508828) (xy 84.89574 -239.564201) (xy 84.911253 -239.622094)
			(xy 84.919076 -239.681516) (xy 84.919076 -239.741452) (xy 84.911253 -239.800874) (xy 84.89574 -239.858767)
			(xy 84.872804 -239.91414) (xy 84.842837 -239.966046) (xy 84.80635 -240.013596) (xy 84.76397 -240.055976)
			(xy 84.71642 -240.092463) (xy 84.664514 -240.12243) (xy 84.609141 -240.145366) (xy 84.551248 -240.160879)
			(xy 84.491826 -240.168702) (xy 84.43189 -240.168702) (xy 84.372468 -240.160879) (xy 84.314575 -240.145366)
			(xy 84.259202 -240.12243) (xy 84.207296 -240.092463) (xy 84.159746 -240.055976) (xy 84.117366 -240.013596)
			(xy 84.080879 -239.966046) (xy 84.050912 -239.91414) (xy 84.027976 -239.858767) (xy 84.012463 -239.800874)
			(xy 84.00464 -239.741452) (xy 45.152783 -239.741452) (xy 45.159195 -239.756932) (xy 45.160901 -239.7633)
			(xy 52.53736 -239.7633) (xy 54.188868 -239.7633) (xy 54.188868 -240.340384) (xy 81.863674 -240.340384)
			(xy 81.863674 -240.280448) (xy 81.871497 -240.221026) (xy 81.88701 -240.163133) (xy 81.909946 -240.10776)
			(xy 81.939913 -240.055854) (xy 81.9764 -240.008304) (xy 82.01878 -239.965924) (xy 82.06633 -239.929437)
			(xy 82.118236 -239.89947) (xy 82.173609 -239.876534) (xy 82.231502 -239.861021) (xy 82.290924 -239.853198)
			(xy 82.320892 -239.852708) (xy 82.35086 -239.853198) (xy 82.410282 -239.861021) (xy 82.468175 -239.876534)
			(xy 82.523548 -239.89947) (xy 82.575454 -239.929437) (xy 82.623004 -239.965924) (xy 82.665384 -240.008304)
			(xy 82.701871 -240.055854) (xy 82.731838 -240.10776) (xy 82.754774 -240.163133) (xy 82.770287 -240.221026)
			(xy 82.77811 -240.280448) (xy 82.77811 -240.340384) (xy 82.770287 -240.399806) (xy 82.754774 -240.457699)
			(xy 82.731838 -240.513072) (xy 82.701871 -240.564978) (xy 82.665384 -240.612528) (xy 82.623004 -240.654908)
			(xy 82.575454 -240.691395) (xy 82.523548 -240.721362) (xy 82.468175 -240.744298) (xy 82.410282 -240.759811)
			(xy 82.35086 -240.767634) (xy 82.290924 -240.767634) (xy 82.231502 -240.759811) (xy 82.173609 -240.744298)
			(xy 82.118236 -240.721362) (xy 82.06633 -240.691395) (xy 82.01878 -240.654908) (xy 81.9764 -240.612528)
			(xy 81.939913 -240.564978) (xy 81.909946 -240.513072) (xy 81.88701 -240.457699) (xy 81.871497 -240.399806)
			(xy 81.863674 -240.340384) (xy 54.188868 -240.340384) (xy 54.188868 -241.169037) (xy 66.107556 -241.169037)
			(xy 66.107556 -241.097715) (xy 66.115542 -241.026841) (xy 66.131412 -240.957306) (xy 66.154969 -240.889986)
			(xy 66.185914 -240.825727) (xy 66.22386 -240.765336) (xy 66.268329 -240.709574) (xy 66.318762 -240.659141)
			(xy 66.374524 -240.614672) (xy 66.434915 -240.576726) (xy 66.499174 -240.545781) (xy 66.566494 -240.522224)
			(xy 66.636029 -240.506354) (xy 66.706903 -240.498368) (xy 66.742564 -240.497868) (xy 66.778225 -240.498368)
			(xy 66.849099 -240.506354) (xy 66.918634 -240.522224) (xy 66.985954 -240.545781) (xy 67.050213 -240.576726)
			(xy 67.110604 -240.614672) (xy 67.166366 -240.659141) (xy 67.216799 -240.709574) (xy 67.261268 -240.765336)
			(xy 67.299214 -240.825727) (xy 67.330159 -240.889986) (xy 67.353716 -240.957306) (xy 67.369586 -241.026841)
			(xy 67.377572 -241.097715) (xy 67.377572 -241.169037) (xy 69.099168 -241.169037) (xy 69.099168 -241.097715)
			(xy 69.107154 -241.026841) (xy 69.123024 -240.957306) (xy 69.146581 -240.889986) (xy 69.177526 -240.825727)
			(xy 69.215472 -240.765336) (xy 69.259941 -240.709574) (xy 69.310374 -240.659141) (xy 69.366136 -240.614672)
			(xy 69.426527 -240.576726) (xy 69.490786 -240.545781) (xy 69.558106 -240.522224) (xy 69.627641 -240.506354)
			(xy 69.698515 -240.498368) (xy 69.734176 -240.497868) (xy 69.769837 -240.498368) (xy 69.840711 -240.506354)
			(xy 69.910246 -240.522224) (xy 69.977566 -240.545781) (xy 70.041825 -240.576726) (xy 70.102216 -240.614672)
			(xy 70.157978 -240.659141) (xy 70.208411 -240.709574) (xy 70.25288 -240.765336) (xy 70.290826 -240.825727)
			(xy 70.321771 -240.889986) (xy 70.345328 -240.957306) (xy 70.358265 -241.013992) (xy 83.347034 -241.013992)
			(xy 83.347034 -240.954056) (xy 83.354857 -240.894634) (xy 83.37037 -240.836741) (xy 83.393306 -240.781368)
			(xy 83.423273 -240.729462) (xy 83.45976 -240.681912) (xy 83.50214 -240.639532) (xy 83.54969 -240.603045)
			(xy 83.601596 -240.573078) (xy 83.656969 -240.550142) (xy 83.714862 -240.534629) (xy 83.774284 -240.526806)
			(xy 83.804252 -240.526316) (xy 83.83422 -240.526806) (xy 83.893642 -240.534629) (xy 83.951535 -240.550142)
			(xy 84.006908 -240.573078) (xy 84.058814 -240.603045) (xy 84.106364 -240.639532) (xy 84.148744 -240.681912)
			(xy 84.185231 -240.729462) (xy 84.215198 -240.781368) (xy 84.238134 -240.836741) (xy 84.253647 -240.894634)
			(xy 84.26147 -240.954056) (xy 84.26147 -241.013992) (xy 84.253647 -241.073414) (xy 84.238134 -241.131307)
			(xy 84.215198 -241.18668) (xy 84.185231 -241.238586) (xy 84.148744 -241.286136) (xy 84.106364 -241.328516)
			(xy 84.058814 -241.365003) (xy 84.006908 -241.39497) (xy 83.951535 -241.417906) (xy 83.893642 -241.433419)
			(xy 83.83422 -241.441242) (xy 83.774284 -241.441242) (xy 83.714862 -241.433419) (xy 83.656969 -241.417906)
			(xy 83.601596 -241.39497) (xy 83.54969 -241.365003) (xy 83.50214 -241.328516) (xy 83.45976 -241.286136)
			(xy 83.423273 -241.238586) (xy 83.393306 -241.18668) (xy 83.37037 -241.131307) (xy 83.354857 -241.073414)
			(xy 83.347034 -241.013992) (xy 70.358265 -241.013992) (xy 70.361198 -241.026841) (xy 70.369184 -241.097715)
			(xy 70.369184 -241.169037) (xy 70.361198 -241.239911) (xy 70.345328 -241.309446) (xy 70.321771 -241.376766)
			(xy 70.290826 -241.441025) (xy 70.25288 -241.501416) (xy 70.208411 -241.557178) (xy 70.157978 -241.607611)
			(xy 70.102216 -241.65208) (xy 70.041825 -241.690026) (xy 69.977566 -241.720971) (xy 69.95026 -241.730526)
			(xy 81.184732 -241.730526) (xy 81.184732 -241.67059) (xy 81.192555 -241.611168) (xy 81.208068 -241.553275)
			(xy 81.231004 -241.497902) (xy 81.260971 -241.445996) (xy 81.297458 -241.398446) (xy 81.339838 -241.356066)
			(xy 81.387388 -241.319579) (xy 81.439294 -241.289612) (xy 81.494667 -241.266676) (xy 81.55256 -241.251163)
			(xy 81.611982 -241.24334) (xy 81.64195 -241.24285) (xy 81.671918 -241.24334) (xy 81.73134 -241.251163)
			(xy 81.789233 -241.266676) (xy 81.844606 -241.289612) (xy 81.896512 -241.319579) (xy 81.944062 -241.356066)
			(xy 81.986442 -241.398446) (xy 82.022929 -241.445996) (xy 82.052896 -241.497902) (xy 82.075832 -241.553275)
			(xy 82.091345 -241.611168) (xy 82.099168 -241.67059) (xy 82.099168 -241.730526) (xy 82.091345 -241.789948)
			(xy 82.075832 -241.847841) (xy 82.052896 -241.903214) (xy 82.022929 -241.95512) (xy 81.986442 -242.00267)
			(xy 81.944062 -242.04505) (xy 81.896512 -242.081537) (xy 81.844606 -242.111504) (xy 81.789233 -242.13444)
			(xy 81.73134 -242.149953) (xy 81.671918 -242.157776) (xy 81.611982 -242.157776) (xy 81.55256 -242.149953)
			(xy 81.494667 -242.13444) (xy 81.439294 -242.111504) (xy 81.387388 -242.081537) (xy 81.339838 -242.04505)
			(xy 81.297458 -242.00267) (xy 81.260971 -241.95512) (xy 81.231004 -241.903214) (xy 81.208068 -241.847841)
			(xy 81.192555 -241.789948) (xy 81.184732 -241.730526) (xy 69.95026 -241.730526) (xy 69.910246 -241.744528)
			(xy 69.840711 -241.760398) (xy 69.769837 -241.768384) (xy 69.698515 -241.768384) (xy 69.627641 -241.760398)
			(xy 69.558106 -241.744528) (xy 69.490786 -241.720971) (xy 69.426527 -241.690026) (xy 69.366136 -241.65208)
			(xy 69.310374 -241.607611) (xy 69.259941 -241.557178) (xy 69.215472 -241.501416) (xy 69.177526 -241.441025)
			(xy 69.146581 -241.376766) (xy 69.123024 -241.309446) (xy 69.107154 -241.239911) (xy 69.099168 -241.169037)
			(xy 67.377572 -241.169037) (xy 67.369586 -241.239911) (xy 67.353716 -241.309446) (xy 67.330159 -241.376766)
			(xy 67.299214 -241.441025) (xy 67.261268 -241.501416) (xy 67.216799 -241.557178) (xy 67.166366 -241.607611)
			(xy 67.110604 -241.65208) (xy 67.050213 -241.690026) (xy 66.985954 -241.720971) (xy 66.918634 -241.744528)
			(xy 66.849099 -241.760398) (xy 66.778225 -241.768384) (xy 66.706903 -241.768384) (xy 66.636029 -241.760398)
			(xy 66.566494 -241.744528) (xy 66.499174 -241.720971) (xy 66.434915 -241.690026) (xy 66.374524 -241.65208)
			(xy 66.318762 -241.607611) (xy 66.268329 -241.557178) (xy 66.22386 -241.501416) (xy 66.185914 -241.441025)
			(xy 66.154969 -241.376766) (xy 66.131412 -241.309446) (xy 66.115542 -241.239911) (xy 66.107556 -241.169037)
			(xy 54.188868 -241.169037) (xy 54.188868 -241.415316) (xy 52.53736 -241.415316) (xy 52.53736 -239.7633)
			(xy 45.160901 -239.7633) (xy 45.175569 -239.818041) (xy 45.183827 -239.880765) (xy 45.183827 -239.944031)
			(xy 45.175569 -240.006755) (xy 45.159195 -240.067864) (xy 45.134984 -240.126314) (xy 45.103351 -240.181103)
			(xy 45.064838 -240.231295) (xy 45.020103 -240.27603) (xy 44.969911 -240.314543) (xy 44.915122 -240.346176)
			(xy 44.856672 -240.370387) (xy 44.795563 -240.386761) (xy 44.732839 -240.395019) (xy 44.669573 -240.395019)
			(xy 44.606849 -240.386761) (xy 44.54574 -240.370387) (xy 44.48729 -240.346176) (xy 44.432501 -240.314543)
			(xy 44.382309 -240.27603) (xy 44.359576 -240.254028) (xy 43.962574 -239.856772) (xy 38.015418 -239.856772)
			(xy 37.155628 -238.997236) (xy 36.59505 -238.997236) (xy 36.57328 -238.997705) (xy 36.530383 -239.005171)
			(xy 36.489387 -239.019841) (xy 36.451493 -239.041286) (xy 36.41781 -239.068877) (xy 36.389324 -239.101808)
			(xy 36.366869 -239.139113) (xy 36.351103 -239.1797) (xy 36.342488 -239.22238) (xy 36.341276 -239.265905)
			(xy 36.347502 -239.308999) (xy 36.360985 -239.3504) (xy 36.370768 -239.369854) (xy 36.390948 -239.40905)
			(xy 36.424745 -239.490479) (xy 36.45077 -239.574715) (xy 36.468796 -239.661018) (xy 36.478664 -239.748628)
			(xy 36.480286 -239.836778) (xy 36.47365 -239.924693) (xy 36.458813 -240.0116) (xy 36.435905 -240.096737)
			(xy 36.405128 -240.179356) (xy 36.366752 -240.25873) (xy 36.344352 -240.2967) (xy 36.333151 -240.316106)
			(xy 36.317018 -240.357903) (xy 36.308463 -240.401881) (xy 36.307752 -240.446678) (xy 36.314908 -240.490905)
			(xy 36.329708 -240.533192) (xy 36.351694 -240.572229) (xy 36.380184 -240.606807) (xy 36.414296 -240.635852)
			(xy 36.452972 -240.658466) (xy 36.495015 -240.673948) (xy 36.539121 -240.681817) (xy 36.561522 -240.682272)
			(xy 36.954968 -240.682272) (xy 38.583107 -242.310411) (xy 86.399122 -242.310411) (xy 86.401115 -242.110283)
			(xy 86.411112 -241.910394) (xy 86.429099 -241.711066) (xy 86.455047 -241.512617) (xy 86.488914 -241.315365)
			(xy 86.530646 -241.119626) (xy 86.580175 -240.925713) (xy 86.637424 -240.733938) (xy 86.702299 -240.544606)
			(xy 86.774698 -240.358022) (xy 86.854504 -240.174483) (xy 86.941589 -239.994285) (xy 87.035814 -239.817715)
			(xy 87.137028 -239.645056) (xy 87.245069 -239.476586) (xy 87.359764 -239.312572) (xy 87.48093 -239.153279)
			(xy 87.608371 -238.998962) (xy 87.741885 -238.849866) (xy 87.881257 -238.706232) (xy 88.026264 -238.56829)
			(xy 88.176675 -238.436259) (xy 88.332247 -238.310352) (xy 88.492732 -238.19077) (xy 88.657873 -238.077705)
			(xy 88.827405 -237.971337) (xy 89.001058 -237.871838) (xy 89.178552 -237.779366) (xy 89.359604 -237.69407)
			(xy 89.543924 -237.616086) (xy 89.731216 -237.545538) (xy 89.921181 -237.482541) (xy 90.113514 -237.427195)
			(xy 90.307908 -237.379588) (xy 90.504051 -237.339797) (xy 90.701628 -237.307885) (xy 90.900325 -237.283904)
			(xy 91.099821 -237.267891) (xy 91.299799 -237.259874) (xy 91.399868 -237.259368) (xy 91.499937 -237.259864)
			(xy 91.699915 -237.267861) (xy 91.899414 -237.283853) (xy 92.098112 -237.307814) (xy 92.295693 -237.339706)
			(xy 92.49184 -237.379477) (xy 92.686239 -237.427064) (xy 92.878578 -237.482391) (xy 93.068549 -237.545369)
			(xy 93.255848 -237.615897) (xy 93.440176 -237.693863) (xy 93.621237 -237.779141) (xy 93.79874 -237.871594)
			(xy 93.972403 -237.971076) (xy 94.141946 -238.077426) (xy 94.307099 -238.190475) (xy 94.467596 -238.31004)
			(xy 94.623181 -238.435932) (xy 94.773605 -238.567947) (xy 94.918626 -238.705875) (xy 95.058012 -238.849495)
			(xy 95.191541 -238.998576) (xy 95.318999 -239.152881) (xy 95.44018 -239.312162) (xy 95.554892 -239.476163)
			(xy 95.66295 -239.644623) (xy 95.764182 -239.817272) (xy 95.858425 -239.993832) (xy 95.945528 -240.174022)
			(xy 96.025353 -240.357552) (xy 96.09777 -240.544129) (xy 96.162665 -240.733454) (xy 96.219933 -240.925224)
			(xy 96.269483 -241.119131) (xy 96.311234 -241.314866) (xy 96.345121 -241.512115) (xy 96.371089 -241.710561)
			(xy 96.389096 -241.909888) (xy 96.399114 -242.109775) (xy 96.401127 -242.309903) (xy 96.395131 -242.509951)
			(xy 96.381135 -242.7096) (xy 96.359164 -242.908528) (xy 96.32925 -243.106418) (xy 96.291443 -243.302953)
			(xy 96.245804 -243.497818) (xy 96.192404 -243.690701) (xy 96.13133 -243.881293) (xy 96.062679 -244.069288)
			(xy 95.986561 -244.254387) (xy 95.903099 -244.436292) (xy 95.812426 -244.614711) (xy 95.714687 -244.789361)
			(xy 95.610038 -244.95996) (xy 95.498648 -245.126235) (xy 95.380694 -245.28792) (xy 95.256365 -245.444757)
			(xy 95.125862 -245.596494) (xy 94.989391 -245.742888) (xy 94.847173 -245.883704) (xy 94.699435 -246.018718)
			(xy 94.546413 -246.147713) (xy 94.388353 -246.270482) (xy 94.225507 -246.386829) (xy 94.058137 -246.496567)
			(xy 93.88651 -246.599521) (xy 93.710902 -246.695526) (xy 93.531592 -246.784428) (xy 93.34887 -246.866084)
			(xy 93.163027 -246.940365) (xy 92.97436 -247.007151) (xy 92.783173 -247.066334) (xy 92.589771 -247.117821)
			(xy 92.394464 -247.161529) (xy 92.197564 -247.197388) (xy 91.999387 -247.22534) (xy 91.800251 -247.24534)
			(xy 91.600474 -247.257358) (xy 91.400376 -247.261372) (xy 91.200278 -247.257378) (xy 91.000499 -247.245381)
			(xy 90.801361 -247.225401) (xy 90.603182 -247.197469) (xy 90.406278 -247.16163) (xy 90.210967 -247.117942)
			(xy 90.017559 -247.066475) (xy 89.826366 -247.007311) (xy 89.637693 -246.940544) (xy 89.451842 -246.866282)
			(xy 89.269111 -246.784644) (xy 89.089793 -246.695761) (xy 88.914175 -246.599774) (xy 88.742537 -246.496837)
			(xy 88.575156 -246.387116) (xy 88.412298 -246.270785) (xy 88.254226 -246.148032) (xy 88.101191 -246.019053)
			(xy 87.953439 -245.884055) (xy 87.811206 -245.743252) (xy 87.674721 -245.596872) (xy 87.544202 -245.445149)
			(xy 87.419858 -245.288325) (xy 87.301888 -245.126651) (xy 87.19048 -244.960387) (xy 87.085814 -244.789799)
			(xy 86.988057 -244.61516) (xy 86.897366 -244.436749) (xy 86.813885 -244.254853) (xy 86.737749 -244.069762)
			(xy 86.669079 -243.881773) (xy 86.607986 -243.691188) (xy 86.554566 -243.49831) (xy 86.508906 -243.30345)
			(xy 86.47108 -243.106919) (xy 86.441146 -242.909032) (xy 86.419154 -242.710106) (xy 86.405139 -242.510459)
			(xy 86.399122 -242.310411) (xy 38.583107 -242.310411) (xy 39.038276 -242.76558) (xy 43.958764 -242.76558)
			(xy 44.250864 -242.473226) (xy 44.273597 -242.451224) (xy 44.323789 -242.412711) (xy 44.378578 -242.381078)
			(xy 44.437028 -242.356867) (xy 44.498137 -242.340493) (xy 44.560861 -242.332235) (xy 44.624127 -242.332235)
			(xy 44.686851 -242.340493) (xy 44.74796 -242.356867) (xy 44.80641 -242.381078) (xy 44.861199 -242.412711)
			(xy 44.911391 -242.451224) (xy 44.956126 -242.495959) (xy 44.994639 -242.546151) (xy 45.026272 -242.60094)
			(xy 45.050483 -242.65939) (xy 45.066857 -242.720499) (xy 45.075115 -242.783223) (xy 45.075115 -242.846489)
			(xy 45.066857 -242.909213) (xy 45.050483 -242.970322) (xy 45.026272 -243.028772) (xy 44.994639 -243.083561)
			(xy 44.956126 -243.133753) (xy 44.934124 -243.156486) (xy 44.384468 -243.705888) (xy 44.373005 -243.718019)
			(xy 44.356293 -243.746897) (xy 44.347641 -243.77912) (xy 44.347642 -243.812485) (xy 44.354989 -243.839847)
			(xy 66.107556 -243.839847) (xy 66.107556 -243.768525) (xy 66.115542 -243.697651) (xy 66.131412 -243.628116)
			(xy 66.154969 -243.560796) (xy 66.185914 -243.496537) (xy 66.22386 -243.436146) (xy 66.268329 -243.380384)
			(xy 66.318762 -243.329951) (xy 66.374524 -243.285482) (xy 66.434915 -243.247536) (xy 66.499174 -243.216591)
			(xy 66.566494 -243.193034) (xy 66.636029 -243.177164) (xy 66.706903 -243.169178) (xy 66.742564 -243.168678)
			(xy 66.778225 -243.169178) (xy 66.849099 -243.177164) (xy 66.918634 -243.193034) (xy 66.985954 -243.216591)
			(xy 67.050213 -243.247536) (xy 67.110604 -243.285482) (xy 67.166366 -243.329951) (xy 67.216799 -243.380384)
			(xy 67.261268 -243.436146) (xy 67.299214 -243.496537) (xy 67.330159 -243.560796) (xy 67.353716 -243.628116)
			(xy 67.369586 -243.697651) (xy 67.377572 -243.768525) (xy 67.377572 -243.839847) (xy 69.099168 -243.839847)
			(xy 69.099168 -243.768525) (xy 69.107154 -243.697651) (xy 69.123024 -243.628116) (xy 69.146581 -243.560796)
			(xy 69.177526 -243.496537) (xy 69.215472 -243.436146) (xy 69.259941 -243.380384) (xy 69.310374 -243.329951)
			(xy 69.366136 -243.285482) (xy 69.426527 -243.247536) (xy 69.490786 -243.216591) (xy 69.558106 -243.193034)
			(xy 69.627641 -243.177164) (xy 69.698515 -243.169178) (xy 69.734176 -243.168678) (xy 69.769837 -243.169178)
			(xy 69.840711 -243.177164) (xy 69.910246 -243.193034) (xy 69.977566 -243.216591) (xy 70.041825 -243.247536)
			(xy 70.102216 -243.285482) (xy 70.157978 -243.329951) (xy 70.208411 -243.380384) (xy 70.25288 -243.436146)
			(xy 70.290826 -243.496537) (xy 70.321771 -243.560796) (xy 70.345328 -243.628116) (xy 70.361198 -243.697651)
			(xy 70.369184 -243.768525) (xy 70.369184 -243.839847) (xy 70.361198 -243.910721) (xy 70.345328 -243.980256)
			(xy 70.321771 -244.047576) (xy 70.290826 -244.111835) (xy 70.25288 -244.172226) (xy 70.208411 -244.227988)
			(xy 70.157978 -244.278421) (xy 70.102216 -244.32289) (xy 70.041825 -244.360836) (xy 69.977566 -244.391781)
			(xy 69.910246 -244.415338) (xy 69.840711 -244.431208) (xy 69.769837 -244.439194) (xy 69.698515 -244.439194)
			(xy 69.627641 -244.431208) (xy 69.558106 -244.415338) (xy 69.490786 -244.391781) (xy 69.426527 -244.360836)
			(xy 69.366136 -244.32289) (xy 69.310374 -244.278421) (xy 69.259941 -244.227988) (xy 69.215472 -244.172226)
			(xy 69.177526 -244.111835) (xy 69.146581 -244.047576) (xy 69.123024 -243.980256) (xy 69.107154 -243.910721)
			(xy 69.099168 -243.839847) (xy 67.377572 -243.839847) (xy 67.369586 -243.910721) (xy 67.353716 -243.980256)
			(xy 67.330159 -244.047576) (xy 67.299214 -244.111835) (xy 67.261268 -244.172226) (xy 67.216799 -244.227988)
			(xy 67.166366 -244.278421) (xy 67.110604 -244.32289) (xy 67.050213 -244.360836) (xy 66.985954 -244.391781)
			(xy 66.918634 -244.415338) (xy 66.849099 -244.431208) (xy 66.778225 -244.439194) (xy 66.706903 -244.439194)
			(xy 66.636029 -244.431208) (xy 66.566494 -244.415338) (xy 66.499174 -244.391781) (xy 66.434915 -244.360836)
			(xy 66.374524 -244.32289) (xy 66.318762 -244.278421) (xy 66.268329 -244.227988) (xy 66.22386 -244.172226)
			(xy 66.185914 -244.111835) (xy 66.154969 -244.047576) (xy 66.131412 -243.980256) (xy 66.115542 -243.910721)
			(xy 66.107556 -243.839847) (xy 44.354989 -243.839847) (xy 44.356295 -243.844709) (xy 44.373009 -243.873585)
			(xy 44.384468 -243.88572) (xy 44.882816 -244.383814) (xy 44.904818 -244.406547) (xy 44.943331 -244.456739)
			(xy 44.974964 -244.511528) (xy 44.999175 -244.569978) (xy 45.015549 -244.631087) (xy 45.023807 -244.693811)
			(xy 45.023807 -244.757077) (xy 45.015549 -244.819801) (xy 44.999175 -244.88091) (xy 44.974964 -244.93936)
			(xy 44.943331 -244.994149) (xy 44.904818 -245.044341) (xy 44.860083 -245.089076) (xy 44.809891 -245.127589)
			(xy 44.755102 -245.159222) (xy 44.696652 -245.183433) (xy 44.635543 -245.199807) (xy 44.572819 -245.208065)
			(xy 44.509553 -245.208065) (xy 44.446829 -245.199807) (xy 44.38572 -245.183433) (xy 44.32727 -245.159222)
			(xy 44.272481 -245.127589) (xy 44.222289 -245.089076) (xy 44.199556 -245.067074) (xy 43.799506 -244.667024)
			(xy 38.313106 -244.667024) (xy 37.71519 -244.069108) (xy 36.590732 -244.069108) (xy 36.568867 -244.069562)
			(xy 36.525783 -244.077046) (xy 36.484618 -244.091798) (xy 36.446587 -244.113383) (xy 36.412815 -244.141163)
			(xy 36.3843 -244.174316) (xy 36.361885 -244.211864) (xy 36.346231 -244.252695) (xy 36.337803 -244.295604)
			(xy 36.336847 -244.339323) (xy 36.343394 -244.382559) (xy 36.357249 -244.424036) (xy 36.367212 -244.443504)
			(xy 36.387282 -244.481729) (xy 36.421145 -244.561153) (xy 36.447584 -244.643348) (xy 36.466376 -244.72762)
			(xy 36.477363 -244.81326) (xy 36.480453 -244.899546) (xy 36.475619 -244.985753) (xy 36.462903 -245.071153)
			(xy 36.442411 -245.155028) (xy 36.414316 -245.236671) (xy 36.378855 -245.315395) (xy 36.336326 -245.390536)
			(xy 36.287087 -245.461462) (xy 36.231553 -245.527575) (xy 36.170192 -245.588318) (xy 36.103521 -245.643181)
			(xy 36.048462 -245.680585) (xy 66.107556 -245.680585) (xy 66.107556 -245.609263) (xy 66.115542 -245.538389)
			(xy 66.131412 -245.468854) (xy 66.154969 -245.401534) (xy 66.185914 -245.337275) (xy 66.22386 -245.276884)
			(xy 66.268329 -245.221122) (xy 66.318762 -245.170689) (xy 66.374524 -245.12622) (xy 66.434915 -245.088274)
			(xy 66.499174 -245.057329) (xy 66.566494 -245.033772) (xy 66.636029 -245.017902) (xy 66.706903 -245.009916)
			(xy 66.742564 -245.009416) (xy 66.778225 -245.009916) (xy 66.849099 -245.017902) (xy 66.918634 -245.033772)
			(xy 66.985954 -245.057329) (xy 67.050213 -245.088274) (xy 67.110604 -245.12622) (xy 67.166366 -245.170689)
			(xy 67.216799 -245.221122) (xy 67.261268 -245.276884) (xy 67.299214 -245.337275) (xy 67.330159 -245.401534)
			(xy 67.353716 -245.468854) (xy 67.369586 -245.538389) (xy 67.377572 -245.609263) (xy 67.377572 -245.680585)
			(xy 69.099168 -245.680585) (xy 69.099168 -245.609263) (xy 69.107154 -245.538389) (xy 69.123024 -245.468854)
			(xy 69.146581 -245.401534) (xy 69.177526 -245.337275) (xy 69.215472 -245.276884) (xy 69.259941 -245.221122)
			(xy 69.310374 -245.170689) (xy 69.366136 -245.12622) (xy 69.426527 -245.088274) (xy 69.490786 -245.057329)
			(xy 69.558106 -245.033772) (xy 69.627641 -245.017902) (xy 69.698515 -245.009916) (xy 69.734176 -245.009416)
			(xy 69.769837 -245.009916) (xy 69.840711 -245.017902) (xy 69.910246 -245.033772) (xy 69.977566 -245.057329)
			(xy 70.041825 -245.088274) (xy 70.102216 -245.12622) (xy 70.157978 -245.170689) (xy 70.208411 -245.221122)
			(xy 70.25288 -245.276884) (xy 70.290826 -245.337275) (xy 70.321771 -245.401534) (xy 70.345328 -245.468854)
			(xy 70.361198 -245.538389) (xy 70.369184 -245.609263) (xy 70.369184 -245.680585) (xy 70.361198 -245.751459)
			(xy 70.345328 -245.820994) (xy 70.321771 -245.888314) (xy 70.290826 -245.952573) (xy 70.25288 -246.012964)
			(xy 70.208411 -246.068726) (xy 70.157978 -246.119159) (xy 70.102216 -246.163628) (xy 70.041825 -246.201574)
			(xy 69.977566 -246.232519) (xy 69.910246 -246.256076) (xy 69.840711 -246.271946) (xy 69.769837 -246.279932)
			(xy 69.698515 -246.279932) (xy 69.627641 -246.271946) (xy 69.558106 -246.256076) (xy 69.490786 -246.232519)
			(xy 69.426527 -246.201574) (xy 69.366136 -246.163628) (xy 69.310374 -246.119159) (xy 69.259941 -246.068726)
			(xy 69.215472 -246.012964) (xy 69.177526 -245.952573) (xy 69.146581 -245.888314) (xy 69.123024 -245.820994)
			(xy 69.107154 -245.751459) (xy 69.099168 -245.680585) (xy 67.377572 -245.680585) (xy 67.369586 -245.751459)
			(xy 67.353716 -245.820994) (xy 67.330159 -245.888314) (xy 67.299214 -245.952573) (xy 67.261268 -246.012964)
			(xy 67.216799 -246.068726) (xy 67.166366 -246.119159) (xy 67.110604 -246.163628) (xy 67.050213 -246.201574)
			(xy 66.985954 -246.232519) (xy 66.918634 -246.256076) (xy 66.849099 -246.271946) (xy 66.778225 -246.279932)
			(xy 66.706903 -246.279932) (xy 66.636029 -246.271946) (xy 66.566494 -246.256076) (xy 66.499174 -246.232519)
			(xy 66.434915 -246.201574) (xy 66.374524 -246.163628) (xy 66.318762 -246.119159) (xy 66.268329 -246.068726)
			(xy 66.22386 -246.012964) (xy 66.185914 -245.952573) (xy 66.154969 -245.888314) (xy 66.131412 -245.820994)
			(xy 66.115542 -245.751459) (xy 66.107556 -245.680585) (xy 36.048462 -245.680585) (xy 36.032101 -245.6917)
			(xy 35.956534 -245.733468) (xy 35.877456 -245.768131) (xy 35.795533 -245.7954) (xy 35.711455 -245.815043)
			(xy 35.625931 -245.826895) (xy 35.53968 -245.830857) (xy 35.453429 -245.826895) (xy 35.367905 -245.815043)
			(xy 35.283827 -245.7954) (xy 35.201904 -245.768131) (xy 35.122826 -245.733468) (xy 35.047259 -245.6917)
			(xy 34.975839 -245.643181) (xy 34.909168 -245.588318) (xy 34.847807 -245.527575) (xy 34.792273 -245.461462)
			(xy 34.743034 -245.390536) (xy 34.700505 -245.315395) (xy 34.665044 -245.236671) (xy 34.636949 -245.155028)
			(xy 34.616457 -245.071153) (xy 34.603741 -244.985753) (xy 34.598907 -244.899546) (xy 34.601997 -244.81326)
			(xy 34.612984 -244.72762) (xy 34.631776 -244.643348) (xy 34.658215 -244.561153) (xy 34.692078 -244.481729)
			(xy 34.712148 -244.443504) (xy 34.722109 -244.42404) (xy 34.735939 -244.382564) (xy 34.742466 -244.339333)
			(xy 34.741496 -244.295623) (xy 34.73306 -244.252725) (xy 34.717405 -244.211903) (xy 34.694993 -244.174363)
			(xy 34.666487 -244.141213) (xy 34.632728 -244.113432) (xy 34.594711 -244.09184) (xy 34.55356 -244.077073)
			(xy 34.510488 -244.069568) (xy 34.488628 -244.069108) (xy 31.510732 -244.069108) (xy 31.488867 -244.069562)
			(xy 31.445783 -244.077046) (xy 31.404618 -244.091798) (xy 31.366587 -244.113383) (xy 31.332815 -244.141163)
			(xy 31.3043 -244.174316) (xy 31.281885 -244.211864) (xy 31.266231 -244.252695) (xy 31.257803 -244.295604)
			(xy 31.256847 -244.339323) (xy 31.263394 -244.382559) (xy 31.277249 -244.424036) (xy 31.287212 -244.443504)
			(xy 31.307282 -244.481729) (xy 31.341145 -244.561153) (xy 31.367584 -244.643348) (xy 31.386376 -244.72762)
			(xy 31.397363 -244.81326) (xy 31.400453 -244.899546) (xy 31.395619 -244.985753) (xy 31.382903 -245.071153)
			(xy 31.362411 -245.155028) (xy 31.334316 -245.236671) (xy 31.298855 -245.315395) (xy 31.256326 -245.390536)
			(xy 31.207087 -245.461462) (xy 31.151553 -245.527575) (xy 31.090192 -245.588318) (xy 31.023521 -245.643181)
			(xy 30.952101 -245.6917) (xy 30.876534 -245.733468) (xy 30.797456 -245.768131) (xy 30.715533 -245.7954)
			(xy 30.631455 -245.815043) (xy 30.545931 -245.826895) (xy 30.45968 -245.830857) (xy 30.373429 -245.826895)
			(xy 30.287905 -245.815043) (xy 30.203827 -245.7954) (xy 30.121904 -245.768131) (xy 30.042826 -245.733468)
			(xy 29.967259 -245.6917) (xy 29.895839 -245.643181) (xy 29.829168 -245.588318) (xy 29.767807 -245.527575)
			(xy 29.712273 -245.461462) (xy 29.663034 -245.390536) (xy 29.620505 -245.315395) (xy 29.585044 -245.236671)
			(xy 29.556949 -245.155028) (xy 29.536457 -245.071153) (xy 29.523741 -244.985753) (xy 29.518907 -244.899546)
			(xy 29.521997 -244.81326) (xy 29.532984 -244.72762) (xy 29.551776 -244.643348) (xy 29.578215 -244.561153)
			(xy 29.612078 -244.481729) (xy 29.632148 -244.443504) (xy 29.642109 -244.42404) (xy 29.655939 -244.382564)
			(xy 29.662466 -244.339333) (xy 29.661496 -244.295623) (xy 29.65306 -244.252725) (xy 29.637405 -244.211903)
			(xy 29.614993 -244.174363) (xy 29.586487 -244.141213) (xy 29.552728 -244.113432) (xy 29.514711 -244.09184)
			(xy 29.47356 -244.077073) (xy 29.430488 -244.069568) (xy 29.408628 -244.069108) (xy 29.271722 -244.069108)
			(xy 27.227022 -242.024154) (xy 27.210378 -242.00822) (xy 27.17246 -241.982049) (xy 27.130446 -241.963141)
			(xy 27.085712 -241.952114) (xy 27.039723 -241.949331) (xy 26.993986 -241.954882) (xy 26.949998 -241.968584)
			(xy 26.9092 -241.989991) (xy 26.872929 -242.0184) (xy 26.842371 -242.052881) (xy 26.818528 -242.092304)
			(xy 26.802182 -242.13538) (xy 26.793866 -242.180696) (xy 26.793444 -242.203732) (xy 26.793444 -245.966488)
			(xy 27.253184 -246.426482) (xy 27.253184 -246.89816) (xy 27.252713 -246.928362) (xy 27.245174 -246.988295)
			(xy 27.230219 -247.04682) (xy 27.208083 -247.103022) (xy 27.179112 -247.156026) (xy 27.143757 -247.205004)
			(xy 27.102571 -247.249191) (xy 27.056196 -247.287896) (xy 27.005357 -247.320517) (xy 26.950846 -247.346544)
			(xy 26.893516 -247.36557) (xy 26.834261 -247.377299) (xy 26.774005 -247.381547) (xy 26.713691 -247.378248)
			(xy 26.654258 -247.367453) (xy 26.596635 -247.349332) (xy 26.541722 -247.324167) (xy 26.515822 -247.308624)
			(xy 26.502175 -247.30071) (xy 26.472118 -247.291158) (xy 26.440637 -247.289271) (xy 26.409654 -247.295163)
			(xy 26.381063 -247.308475) (xy 26.368502 -247.318022) (xy 26.343159 -247.338032) (xy 26.288156 -247.371857)
			(xy 26.229135 -247.39805) (xy 26.16715 -247.416143) (xy 26.103306 -247.425812) (xy 26.038743 -247.426887)
			(xy 25.974613 -247.419346) (xy 25.91206 -247.403326) (xy 25.852201 -247.379111) (xy 25.796102 -247.347135)
			(xy 25.744767 -247.307967) (xy 25.721564 -247.28551) (xy 25.5778 -247.141492) (xy 25.565637 -247.130123)
			(xy 25.536796 -247.113511) (xy 25.504641 -247.104927) (xy 25.471359 -247.104953) (xy 25.439217 -247.113589)
			(xy 25.410403 -247.130246) (xy 25.386879 -247.15379) (xy 25.370247 -247.182618) (xy 25.361639 -247.214767)
			(xy 25.361138 -247.231408) (xy 25.361116 -247.473486) (xy 29.519874 -247.473486) (xy 29.519874 -247.386586)
			(xy 29.527892 -247.300057) (xy 29.54386 -247.214637) (xy 29.567641 -247.131055) (xy 29.599033 -247.050023)
			(xy 29.637767 -246.972234) (xy 29.683514 -246.89835) (xy 29.735883 -246.829003) (xy 29.794427 -246.764783)
			(xy 29.858647 -246.706239) (xy 29.927994 -246.65387) (xy 30.001878 -246.608123) (xy 30.079667 -246.569389)
			(xy 30.160699 -246.537997) (xy 30.244281 -246.514216) (xy 30.329701 -246.498248) (xy 30.41623 -246.49023)
			(xy 30.45968 -246.489728) (xy 30.50313 -246.49023) (xy 30.589659 -246.498248) (xy 30.675079 -246.514216)
			(xy 30.758661 -246.537997) (xy 30.839693 -246.569389) (xy 30.917482 -246.608123) (xy 30.991366 -246.65387)
			(xy 31.060713 -246.706239) (xy 31.124933 -246.764783) (xy 31.183477 -246.829003) (xy 31.235846 -246.89835)
			(xy 31.281593 -246.972234) (xy 31.320327 -247.050023) (xy 31.351719 -247.131055) (xy 31.3755 -247.214637)
			(xy 31.391468 -247.300057) (xy 31.399486 -247.386586) (xy 31.399486 -247.473486) (xy 34.599874 -247.473486)
			(xy 34.599874 -247.386586) (xy 34.607892 -247.300057) (xy 34.62386 -247.214637) (xy 34.647641 -247.131055)
			(xy 34.679033 -247.050023) (xy 34.717767 -246.972234) (xy 34.763514 -246.89835) (xy 34.815883 -246.829003)
			(xy 34.874427 -246.764783) (xy 34.938647 -246.706239) (xy 35.007994 -246.65387) (xy 35.081878 -246.608123)
			(xy 35.159667 -246.569389) (xy 35.240699 -246.537997) (xy 35.324281 -246.514216) (xy 35.409701 -246.498248)
			(xy 35.49623 -246.49023) (xy 35.53968 -246.489728) (xy 35.58313 -246.49023) (xy 35.669659 -246.498248)
			(xy 35.755079 -246.514216) (xy 35.838661 -246.537997) (xy 35.919693 -246.569389) (xy 35.997482 -246.608123)
			(xy 36.071366 -246.65387) (xy 36.140713 -246.706239) (xy 36.204933 -246.764783) (xy 36.263477 -246.829003)
			(xy 36.315846 -246.89835) (xy 36.361593 -246.972234) (xy 36.400327 -247.050023) (xy 36.431719 -247.131055)
			(xy 36.439487 -247.158357) (xy 41.706538 -247.158357) (xy 41.706538 -247.087035) (xy 41.714524 -247.016161)
			(xy 41.730394 -246.946626) (xy 41.753951 -246.879306) (xy 41.784896 -246.815047) (xy 41.822842 -246.754656)
			(xy 41.867311 -246.698894) (xy 41.917744 -246.648461) (xy 41.973506 -246.603992) (xy 42.033897 -246.566046)
			(xy 42.098156 -246.535101) (xy 42.165476 -246.511544) (xy 42.235011 -246.495674) (xy 42.305885 -246.487688)
			(xy 42.341546 -246.487188) (xy 42.377207 -246.487688) (xy 42.448081 -246.495674) (xy 42.517616 -246.511544)
			(xy 42.584936 -246.535101) (xy 42.649195 -246.566046) (xy 42.709586 -246.603992) (xy 42.765348 -246.648461)
			(xy 42.815781 -246.698894) (xy 42.86025 -246.754656) (xy 42.898196 -246.815047) (xy 42.929141 -246.879306)
			(xy 42.952698 -246.946626) (xy 42.968568 -247.016161) (xy 42.971528 -247.042428) (xy 44.027072 -247.042428)
			(xy 44.027072 -246.982492) (xy 44.034895 -246.92307) (xy 44.050408 -246.865177) (xy 44.073344 -246.809804)
			(xy 44.103311 -246.757898) (xy 44.139798 -246.710348) (xy 44.182178 -246.667968) (xy 44.229728 -246.631481)
			(xy 44.281634 -246.601514) (xy 44.337007 -246.578578) (xy 44.3949 -246.563065) (xy 44.454322 -246.555242)
			(xy 44.48429 -246.554752) (xy 44.514258 -246.555242) (xy 44.57368 -246.563065) (xy 44.631573 -246.578578)
			(xy 44.686946 -246.601514) (xy 44.738852 -246.631481) (xy 44.786402 -246.667968) (xy 44.828782 -246.710348)
			(xy 44.865269 -246.757898) (xy 44.895236 -246.809804) (xy 44.918172 -246.865177) (xy 44.933685 -246.92307)
			(xy 44.941508 -246.982492) (xy 44.941508 -247.042428) (xy 44.933685 -247.10185) (xy 44.918172 -247.159743)
			(xy 44.895236 -247.215116) (xy 44.865269 -247.267022) (xy 44.828782 -247.314572) (xy 44.786402 -247.356952)
			(xy 44.738852 -247.393439) (xy 44.686946 -247.423406) (xy 44.631573 -247.446342) (xy 44.57368 -247.461855)
			(xy 44.514258 -247.469678) (xy 44.454322 -247.469678) (xy 44.3949 -247.461855) (xy 44.337007 -247.446342)
			(xy 44.281634 -247.423406) (xy 44.229728 -247.393439) (xy 44.182178 -247.356952) (xy 44.139798 -247.314572)
			(xy 44.103311 -247.267022) (xy 44.073344 -247.215116) (xy 44.050408 -247.159743) (xy 44.034895 -247.10185)
			(xy 44.027072 -247.042428) (xy 42.971528 -247.042428) (xy 42.976554 -247.087035) (xy 42.976554 -247.158357)
			(xy 42.968568 -247.229231) (xy 42.952698 -247.298766) (xy 42.929141 -247.366086) (xy 42.898196 -247.430345)
			(xy 42.86025 -247.490736) (xy 42.829173 -247.529705) (xy 66.070726 -247.529705) (xy 66.070726 -247.458383)
			(xy 66.078712 -247.387509) (xy 66.094582 -247.317974) (xy 66.118139 -247.250654) (xy 66.149084 -247.186395)
			(xy 66.18703 -247.126004) (xy 66.231499 -247.070242) (xy 66.281932 -247.019809) (xy 66.337694 -246.97534)
			(xy 66.398085 -246.937394) (xy 66.462344 -246.906449) (xy 66.529664 -246.882892) (xy 66.599199 -246.867022)
			(xy 66.670073 -246.859036) (xy 66.705734 -246.858536) (xy 66.741395 -246.859036) (xy 66.812269 -246.867022)
			(xy 66.881804 -246.882892) (xy 66.949124 -246.906449) (xy 67.013383 -246.937394) (xy 67.073774 -246.97534)
			(xy 67.129536 -247.019809) (xy 67.179969 -247.070242) (xy 67.224438 -247.126004) (xy 67.262384 -247.186395)
			(xy 67.293329 -247.250654) (xy 67.316886 -247.317974) (xy 67.332756 -247.387509) (xy 67.340742 -247.458383)
			(xy 67.340742 -247.529705) (xy 69.062338 -247.529705) (xy 69.062338 -247.458383) (xy 69.070324 -247.387509)
			(xy 69.086194 -247.317974) (xy 69.109751 -247.250654) (xy 69.140696 -247.186395) (xy 69.178642 -247.126004)
			(xy 69.223111 -247.070242) (xy 69.273544 -247.019809) (xy 69.329306 -246.97534) (xy 69.389697 -246.937394)
			(xy 69.453956 -246.906449) (xy 69.521276 -246.882892) (xy 69.590811 -246.867022) (xy 69.661685 -246.859036)
			(xy 69.697346 -246.858536) (xy 69.733007 -246.859036) (xy 69.803881 -246.867022) (xy 69.873416 -246.882892)
			(xy 69.940736 -246.906449) (xy 70.004995 -246.937394) (xy 70.065386 -246.97534) (xy 70.121148 -247.019809)
			(xy 70.171581 -247.070242) (xy 70.21605 -247.126004) (xy 70.253996 -247.186395) (xy 70.284941 -247.250654)
			(xy 70.308498 -247.317974) (xy 70.324368 -247.387509) (xy 70.332354 -247.458383) (xy 70.332354 -247.529705)
			(xy 70.324368 -247.600579) (xy 70.308498 -247.670114) (xy 70.284941 -247.737434) (xy 70.253996 -247.801693)
			(xy 70.21605 -247.862084) (xy 70.171581 -247.917846) (xy 70.121148 -247.968279) (xy 70.065386 -248.012748)
			(xy 70.004995 -248.050694) (xy 69.940736 -248.081639) (xy 69.873416 -248.105196) (xy 69.803881 -248.121066)
			(xy 69.733007 -248.129052) (xy 69.661685 -248.129052) (xy 69.590811 -248.121066) (xy 69.521276 -248.105196)
			(xy 69.453956 -248.081639) (xy 69.389697 -248.050694) (xy 69.329306 -248.012748) (xy 69.273544 -247.968279)
			(xy 69.223111 -247.917846) (xy 69.178642 -247.862084) (xy 69.140696 -247.801693) (xy 69.109751 -247.737434)
			(xy 69.086194 -247.670114) (xy 69.070324 -247.600579) (xy 69.062338 -247.529705) (xy 67.340742 -247.529705)
			(xy 67.332756 -247.600579) (xy 67.316886 -247.670114) (xy 67.293329 -247.737434) (xy 67.262384 -247.801693)
			(xy 67.224438 -247.862084) (xy 67.179969 -247.917846) (xy 67.129536 -247.968279) (xy 67.073774 -248.012748)
			(xy 67.013383 -248.050694) (xy 66.949124 -248.081639) (xy 66.881804 -248.105196) (xy 66.812269 -248.121066)
			(xy 66.741395 -248.129052) (xy 66.670073 -248.129052) (xy 66.599199 -248.121066) (xy 66.529664 -248.105196)
			(xy 66.462344 -248.081639) (xy 66.398085 -248.050694) (xy 66.337694 -248.012748) (xy 66.281932 -247.968279)
			(xy 66.231499 -247.917846) (xy 66.18703 -247.862084) (xy 66.149084 -247.801693) (xy 66.118139 -247.737434)
			(xy 66.094582 -247.670114) (xy 66.078712 -247.600579) (xy 66.070726 -247.529705) (xy 42.829173 -247.529705)
			(xy 42.815781 -247.546498) (xy 42.765348 -247.596931) (xy 42.709586 -247.6414) (xy 42.649195 -247.679346)
			(xy 42.584936 -247.710291) (xy 42.517616 -247.733848) (xy 42.448081 -247.749718) (xy 42.377207 -247.757704)
			(xy 42.305885 -247.757704) (xy 42.235011 -247.749718) (xy 42.165476 -247.733848) (xy 42.098156 -247.710291)
			(xy 42.033897 -247.679346) (xy 41.973506 -247.6414) (xy 41.917744 -247.596931) (xy 41.867311 -247.546498)
			(xy 41.822842 -247.490736) (xy 41.784896 -247.430345) (xy 41.753951 -247.366086) (xy 41.730394 -247.298766)
			(xy 41.714524 -247.229231) (xy 41.706538 -247.158357) (xy 36.439487 -247.158357) (xy 36.4555 -247.214637)
			(xy 36.471468 -247.300057) (xy 36.479486 -247.386586) (xy 36.479486 -247.473486) (xy 36.471468 -247.560015)
			(xy 36.4555 -247.645435) (xy 36.431719 -247.729017) (xy 36.400327 -247.810049) (xy 36.361593 -247.887838)
			(xy 36.315846 -247.961722) (xy 36.263477 -248.031069) (xy 36.204933 -248.095289) (xy 36.140713 -248.153833)
			(xy 36.071366 -248.206202) (xy 35.997482 -248.251949) (xy 35.919693 -248.290683) (xy 35.838661 -248.322075)
			(xy 35.755079 -248.345856) (xy 35.669659 -248.361824) (xy 35.58313 -248.369842) (xy 35.49623 -248.369842)
			(xy 35.409701 -248.361824) (xy 35.324281 -248.345856) (xy 35.240699 -248.322075) (xy 35.159667 -248.290683)
			(xy 35.081878 -248.251949) (xy 35.007994 -248.206202) (xy 34.938647 -248.153833) (xy 34.874427 -248.095289)
			(xy 34.815883 -248.031069) (xy 34.763514 -247.961722) (xy 34.717767 -247.887838) (xy 34.679033 -247.810049)
			(xy 34.647641 -247.729017) (xy 34.62386 -247.645435) (xy 34.607892 -247.560015) (xy 34.599874 -247.473486)
			(xy 31.399486 -247.473486) (xy 31.391468 -247.560015) (xy 31.3755 -247.645435) (xy 31.351719 -247.729017)
			(xy 31.320327 -247.810049) (xy 31.281593 -247.887838) (xy 31.235846 -247.961722) (xy 31.183477 -248.031069)
			(xy 31.124933 -248.095289) (xy 31.060713 -248.153833) (xy 30.991366 -248.206202) (xy 30.917482 -248.251949)
			(xy 30.839693 -248.290683) (xy 30.758661 -248.322075) (xy 30.675079 -248.345856) (xy 30.589659 -248.361824)
			(xy 30.50313 -248.369842) (xy 30.41623 -248.369842) (xy 30.329701 -248.361824) (xy 30.244281 -248.345856)
			(xy 30.160699 -248.322075) (xy 30.079667 -248.290683) (xy 30.001878 -248.251949) (xy 29.927994 -248.206202)
			(xy 29.858647 -248.153833) (xy 29.794427 -248.095289) (xy 29.735883 -248.031069) (xy 29.683514 -247.961722)
			(xy 29.637767 -247.887838) (xy 29.599033 -247.810049) (xy 29.567641 -247.729017) (xy 29.54386 -247.645435)
			(xy 29.527892 -247.560015) (xy 29.519874 -247.473486) (xy 25.361116 -247.473486) (xy 25.360976 -249.021342)
			(xy 43.99837 -249.021342) (xy 43.99837 -248.961406) (xy 44.006193 -248.901984) (xy 44.021706 -248.844091)
			(xy 44.044642 -248.788718) (xy 44.074609 -248.736812) (xy 44.111096 -248.689262) (xy 44.153476 -248.646882)
			(xy 44.201026 -248.610395) (xy 44.252932 -248.580428) (xy 44.308305 -248.557492) (xy 44.366198 -248.541979)
			(xy 44.42562 -248.534156) (xy 44.455588 -248.533666) (xy 44.485556 -248.534156) (xy 44.544978 -248.541979)
			(xy 44.602871 -248.557492) (xy 44.658244 -248.580428) (xy 44.71015 -248.610395) (xy 44.7577 -248.646882)
			(xy 44.80008 -248.689262) (xy 44.836567 -248.736812) (xy 44.866534 -248.788718) (xy 44.88947 -248.844091)
			(xy 44.904983 -248.901984) (xy 44.912806 -248.961406) (xy 44.912806 -249.021342) (xy 44.904983 -249.080764)
			(xy 44.88947 -249.138657) (xy 44.866534 -249.19403) (xy 44.836567 -249.245936) (xy 44.80008 -249.293486)
			(xy 44.7577 -249.335866) (xy 44.71015 -249.372353) (xy 44.658244 -249.40232) (xy 44.602871 -249.425256)
			(xy 44.544978 -249.440769) (xy 44.485556 -249.448592) (xy 44.42562 -249.448592) (xy 44.366198 -249.440769)
			(xy 44.308305 -249.425256) (xy 44.252932 -249.40232) (xy 44.201026 -249.372353) (xy 44.153476 -249.335866)
			(xy 44.111096 -249.293486) (xy 44.074609 -249.245936) (xy 44.044642 -249.19403) (xy 44.021706 -249.138657)
			(xy 44.006193 -249.080764) (xy 43.99837 -249.021342) (xy 25.360976 -249.021342) (xy 25.360887 -250.013486)
			(xy 29.519874 -250.013486) (xy 29.519874 -249.926586) (xy 29.527892 -249.840057) (xy 29.54386 -249.754637)
			(xy 29.567641 -249.671055) (xy 29.599033 -249.590023) (xy 29.637767 -249.512234) (xy 29.683514 -249.43835)
			(xy 29.735883 -249.369003) (xy 29.794427 -249.304783) (xy 29.858647 -249.246239) (xy 29.927994 -249.19387)
			(xy 30.001878 -249.148123) (xy 30.079667 -249.109389) (xy 30.160699 -249.077997) (xy 30.244281 -249.054216)
			(xy 30.329701 -249.038248) (xy 30.41623 -249.03023) (xy 30.45968 -249.029728) (xy 30.50313 -249.03023)
			(xy 30.589659 -249.038248) (xy 30.675079 -249.054216) (xy 30.758661 -249.077997) (xy 30.839693 -249.109389)
			(xy 30.917482 -249.148123) (xy 30.991366 -249.19387) (xy 31.060713 -249.246239) (xy 31.124933 -249.304783)
			(xy 31.183477 -249.369003) (xy 31.235846 -249.43835) (xy 31.281593 -249.512234) (xy 31.320327 -249.590023)
			(xy 31.351719 -249.671055) (xy 31.3755 -249.754637) (xy 31.391468 -249.840057) (xy 31.399486 -249.926586)
			(xy 31.399486 -250.013486) (xy 34.599874 -250.013486) (xy 34.599874 -249.926586) (xy 34.607892 -249.840057)
			(xy 34.62386 -249.754637) (xy 34.647641 -249.671055) (xy 34.679033 -249.590023) (xy 34.717767 -249.512234)
			(xy 34.763514 -249.43835) (xy 34.815883 -249.369003) (xy 34.874427 -249.304783) (xy 34.938647 -249.246239)
			(xy 35.007994 -249.19387) (xy 35.081878 -249.148123) (xy 35.159667 -249.109389) (xy 35.240699 -249.077997)
			(xy 35.324281 -249.054216) (xy 35.409701 -249.038248) (xy 35.49623 -249.03023) (xy 35.53968 -249.029728)
			(xy 35.58313 -249.03023) (xy 35.669659 -249.038248) (xy 35.755079 -249.054216) (xy 35.838661 -249.077997)
			(xy 35.919693 -249.109389) (xy 35.997482 -249.148123) (xy 36.071366 -249.19387) (xy 36.140713 -249.246239)
			(xy 36.204933 -249.304783) (xy 36.263477 -249.369003) (xy 36.315846 -249.43835) (xy 36.361593 -249.512234)
			(xy 36.400327 -249.590023) (xy 36.431719 -249.671055) (xy 36.4555 -249.754637) (xy 36.469432 -249.829167)
			(xy 41.706538 -249.829167) (xy 41.706538 -249.757845) (xy 41.714524 -249.686971) (xy 41.730394 -249.617436)
			(xy 41.753951 -249.550116) (xy 41.784896 -249.485857) (xy 41.822842 -249.425466) (xy 41.867311 -249.369704)
			(xy 41.917744 -249.319271) (xy 41.973506 -249.274802) (xy 42.033897 -249.236856) (xy 42.098156 -249.205911)
			(xy 42.165476 -249.182354) (xy 42.235011 -249.166484) (xy 42.305885 -249.158498) (xy 42.341546 -249.157998)
			(xy 42.377207 -249.158498) (xy 42.448081 -249.166484) (xy 42.517616 -249.182354) (xy 42.584936 -249.205911)
			(xy 42.649195 -249.236856) (xy 42.709586 -249.274802) (xy 42.765348 -249.319271) (xy 42.815781 -249.369704)
			(xy 42.86025 -249.425466) (xy 42.898196 -249.485857) (xy 42.901451 -249.492617) (xy 66.070726 -249.492617)
			(xy 66.070726 -249.421295) (xy 66.078712 -249.350421) (xy 66.094582 -249.280886) (xy 66.118139 -249.213566)
			(xy 66.149084 -249.149307) (xy 66.18703 -249.088916) (xy 66.231499 -249.033154) (xy 66.281932 -248.982721)
			(xy 66.337694 -248.938252) (xy 66.398085 -248.900306) (xy 66.462344 -248.869361) (xy 66.529664 -248.845804)
			(xy 66.599199 -248.829934) (xy 66.670073 -248.821948) (xy 66.705734 -248.821448) (xy 66.741395 -248.821948)
			(xy 66.812269 -248.829934) (xy 66.881804 -248.845804) (xy 66.949124 -248.869361) (xy 67.013383 -248.900306)
			(xy 67.073774 -248.938252) (xy 67.129536 -248.982721) (xy 67.179969 -249.033154) (xy 67.224438 -249.088916)
			(xy 67.262384 -249.149307) (xy 67.293329 -249.213566) (xy 67.316886 -249.280886) (xy 67.332756 -249.350421)
			(xy 67.340742 -249.421295) (xy 67.340742 -249.492617) (xy 69.062338 -249.492617) (xy 69.062338 -249.421295)
			(xy 69.070324 -249.350421) (xy 69.086194 -249.280886) (xy 69.109751 -249.213566) (xy 69.140696 -249.149307)
			(xy 69.178642 -249.088916) (xy 69.223111 -249.033154) (xy 69.273544 -248.982721) (xy 69.329306 -248.938252)
			(xy 69.389697 -248.900306) (xy 69.453956 -248.869361) (xy 69.521276 -248.845804) (xy 69.590811 -248.829934)
			(xy 69.661685 -248.821948) (xy 69.697346 -248.821448) (xy 69.733007 -248.821948) (xy 69.803881 -248.829934)
			(xy 69.873416 -248.845804) (xy 69.940736 -248.869361) (xy 70.004995 -248.900306) (xy 70.065386 -248.938252)
			(xy 70.121148 -248.982721) (xy 70.171581 -249.033154) (xy 70.21605 -249.088916) (xy 70.253996 -249.149307)
			(xy 70.284941 -249.213566) (xy 70.308498 -249.280886) (xy 70.324368 -249.350421) (xy 70.332354 -249.421295)
			(xy 70.332354 -249.492617) (xy 70.324368 -249.563491) (xy 70.308498 -249.633026) (xy 70.284941 -249.700346)
			(xy 70.253996 -249.764605) (xy 70.21605 -249.824996) (xy 70.171581 -249.880758) (xy 70.121148 -249.931191)
			(xy 70.065386 -249.97566) (xy 70.004995 -250.013606) (xy 69.940736 -250.044551) (xy 69.873416 -250.068108)
			(xy 69.803881 -250.083978) (xy 69.733007 -250.091964) (xy 69.661685 -250.091964) (xy 69.590811 -250.083978)
			(xy 69.521276 -250.068108) (xy 69.453956 -250.044551) (xy 69.389697 -250.013606) (xy 69.329306 -249.97566)
			(xy 69.273544 -249.931191) (xy 69.223111 -249.880758) (xy 69.178642 -249.824996) (xy 69.140696 -249.764605)
			(xy 69.109751 -249.700346) (xy 69.086194 -249.633026) (xy 69.070324 -249.563491) (xy 69.062338 -249.492617)
			(xy 67.340742 -249.492617) (xy 67.332756 -249.563491) (xy 67.316886 -249.633026) (xy 67.293329 -249.700346)
			(xy 67.262384 -249.764605) (xy 67.224438 -249.824996) (xy 67.179969 -249.880758) (xy 67.129536 -249.931191)
			(xy 67.073774 -249.97566) (xy 67.013383 -250.013606) (xy 66.949124 -250.044551) (xy 66.881804 -250.068108)
			(xy 66.812269 -250.083978) (xy 66.741395 -250.091964) (xy 66.670073 -250.091964) (xy 66.599199 -250.083978)
			(xy 66.529664 -250.068108) (xy 66.462344 -250.044551) (xy 66.398085 -250.013606) (xy 66.337694 -249.97566)
			(xy 66.281932 -249.931191) (xy 66.231499 -249.880758) (xy 66.18703 -249.824996) (xy 66.149084 -249.764605)
			(xy 66.118139 -249.700346) (xy 66.094582 -249.633026) (xy 66.078712 -249.563491) (xy 66.070726 -249.492617)
			(xy 42.901451 -249.492617) (xy 42.929141 -249.550116) (xy 42.952698 -249.617436) (xy 42.968568 -249.686971)
			(xy 42.976554 -249.757845) (xy 42.976554 -249.829167) (xy 42.968568 -249.900041) (xy 42.952698 -249.969576)
			(xy 42.929141 -250.036896) (xy 42.898196 -250.101155) (xy 42.86025 -250.161546) (xy 42.815781 -250.217308)
			(xy 42.765348 -250.267741) (xy 42.709586 -250.31221) (xy 42.649195 -250.350156) (xy 42.584936 -250.381101)
			(xy 42.517616 -250.404658) (xy 42.448081 -250.420528) (xy 42.377207 -250.428514) (xy 42.305885 -250.428514)
			(xy 42.235011 -250.420528) (xy 42.165476 -250.404658) (xy 42.098156 -250.381101) (xy 42.033897 -250.350156)
			(xy 41.973506 -250.31221) (xy 41.917744 -250.267741) (xy 41.867311 -250.217308) (xy 41.822842 -250.161546)
			(xy 41.784896 -250.101155) (xy 41.753951 -250.036896) (xy 41.730394 -249.969576) (xy 41.714524 -249.900041)
			(xy 41.706538 -249.829167) (xy 36.469432 -249.829167) (xy 36.471468 -249.840057) (xy 36.479486 -249.926586)
			(xy 36.479486 -250.013486) (xy 36.471468 -250.100015) (xy 36.4555 -250.185435) (xy 36.431719 -250.269017)
			(xy 36.400327 -250.350049) (xy 36.361593 -250.427838) (xy 36.315846 -250.501722) (xy 36.263477 -250.571069)
			(xy 36.204933 -250.635289) (xy 36.140713 -250.693833) (xy 36.071366 -250.746202) (xy 35.997482 -250.791949)
			(xy 35.919693 -250.830683) (xy 35.838661 -250.862075) (xy 35.755079 -250.885856) (xy 35.669659 -250.901824)
			(xy 35.58313 -250.909842) (xy 35.49623 -250.909842) (xy 35.409701 -250.901824) (xy 35.324281 -250.885856)
			(xy 35.240699 -250.862075) (xy 35.159667 -250.830683) (xy 35.081878 -250.791949) (xy 35.007994 -250.746202)
			(xy 34.938647 -250.693833) (xy 34.874427 -250.635289) (xy 34.815883 -250.571069) (xy 34.763514 -250.501722)
			(xy 34.717767 -250.427838) (xy 34.679033 -250.350049) (xy 34.647641 -250.269017) (xy 34.62386 -250.185435)
			(xy 34.607892 -250.100015) (xy 34.599874 -250.013486) (xy 31.399486 -250.013486) (xy 31.391468 -250.100015)
			(xy 31.3755 -250.185435) (xy 31.351719 -250.269017) (xy 31.320327 -250.350049) (xy 31.281593 -250.427838)
			(xy 31.235846 -250.501722) (xy 31.183477 -250.571069) (xy 31.124933 -250.635289) (xy 31.060713 -250.693833)
			(xy 30.991366 -250.746202) (xy 30.917482 -250.791949) (xy 30.839693 -250.830683) (xy 30.758661 -250.862075)
			(xy 30.675079 -250.885856) (xy 30.589659 -250.901824) (xy 30.50313 -250.909842) (xy 30.41623 -250.909842)
			(xy 30.329701 -250.901824) (xy 30.244281 -250.885856) (xy 30.160699 -250.862075) (xy 30.079667 -250.830683)
			(xy 30.001878 -250.791949) (xy 29.927994 -250.746202) (xy 29.858647 -250.693833) (xy 29.794427 -250.635289)
			(xy 29.735883 -250.571069) (xy 29.683514 -250.501722) (xy 29.637767 -250.427838) (xy 29.599033 -250.350049)
			(xy 29.567641 -250.269017) (xy 29.54386 -250.185435) (xy 29.527892 -250.100015) (xy 29.519874 -250.013486)
			(xy 25.360887 -250.013486) (xy 25.360884 -250.051824) (xy 25.904952 -250.595892) (xy 25.904952 -251.4793)
			(xy 44.18125 -251.4793) (xy 44.18125 -251.419364) (xy 44.189073 -251.359942) (xy 44.204586 -251.302049)
			(xy 44.227522 -251.246676) (xy 44.257489 -251.19477) (xy 44.293976 -251.14722) (xy 44.336356 -251.10484)
			(xy 44.383906 -251.068353) (xy 44.435812 -251.038386) (xy 44.491185 -251.01545) (xy 44.549078 -250.999937)
			(xy 44.6085 -250.992114) (xy 44.638468 -250.991624) (xy 44.668436 -250.992114) (xy 44.727858 -250.999937)
			(xy 44.785751 -251.01545) (xy 44.841124 -251.038386) (xy 44.89303 -251.068353) (xy 44.94058 -251.10484)
			(xy 44.98296 -251.14722) (xy 45.019447 -251.19477) (xy 45.049414 -251.246676) (xy 45.07235 -251.302049)
			(xy 45.087863 -251.359942) (xy 45.095686 -251.419364) (xy 45.095686 -251.4793) (xy 45.087863 -251.538722)
			(xy 45.07235 -251.596615) (xy 45.055985 -251.636123) (xy 66.070726 -251.636123) (xy 66.070726 -251.564801)
			(xy 66.078712 -251.493927) (xy 66.094582 -251.424392) (xy 66.118139 -251.357072) (xy 66.149084 -251.292813)
			(xy 66.18703 -251.232422) (xy 66.231499 -251.17666) (xy 66.281932 -251.126227) (xy 66.337694 -251.081758)
			(xy 66.398085 -251.043812) (xy 66.462344 -251.012867) (xy 66.529664 -250.98931) (xy 66.599199 -250.97344)
			(xy 66.670073 -250.965454) (xy 66.705734 -250.964954) (xy 66.741395 -250.965454) (xy 66.812269 -250.97344)
			(xy 66.881804 -250.98931) (xy 66.949124 -251.012867) (xy 67.013383 -251.043812) (xy 67.073774 -251.081758)
			(xy 67.129536 -251.126227) (xy 67.179969 -251.17666) (xy 67.224438 -251.232422) (xy 67.262384 -251.292813)
			(xy 67.293329 -251.357072) (xy 67.316886 -251.424392) (xy 67.332756 -251.493927) (xy 67.340742 -251.564801)
			(xy 67.340742 -251.636123) (xy 69.062338 -251.636123) (xy 69.062338 -251.564801) (xy 69.070324 -251.493927)
			(xy 69.086194 -251.424392) (xy 69.109751 -251.357072) (xy 69.140696 -251.292813) (xy 69.178642 -251.232422)
			(xy 69.223111 -251.17666) (xy 69.273544 -251.126227) (xy 69.329306 -251.081758) (xy 69.389697 -251.043812)
			(xy 69.453956 -251.012867) (xy 69.521276 -250.98931) (xy 69.590811 -250.97344) (xy 69.661685 -250.965454)
			(xy 69.697346 -250.964954) (xy 69.733007 -250.965454) (xy 69.803881 -250.97344) (xy 69.873416 -250.98931)
			(xy 69.940736 -251.012867) (xy 70.004995 -251.043812) (xy 70.065386 -251.081758) (xy 70.121148 -251.126227)
			(xy 70.171581 -251.17666) (xy 70.21605 -251.232422) (xy 70.253996 -251.292813) (xy 70.284941 -251.357072)
			(xy 70.308498 -251.424392) (xy 70.324368 -251.493927) (xy 70.332354 -251.564801) (xy 70.332354 -251.636123)
			(xy 70.324368 -251.706997) (xy 70.308498 -251.776532) (xy 70.284941 -251.843852) (xy 70.253996 -251.908111)
			(xy 70.21605 -251.968502) (xy 70.171581 -252.024264) (xy 70.121148 -252.074697) (xy 70.065386 -252.119166)
			(xy 70.004995 -252.157112) (xy 69.940736 -252.188057) (xy 69.873416 -252.211614) (xy 69.803881 -252.227484)
			(xy 69.733007 -252.23547) (xy 69.661685 -252.23547) (xy 69.590811 -252.227484) (xy 69.521276 -252.211614)
			(xy 69.453956 -252.188057) (xy 69.389697 -252.157112) (xy 69.329306 -252.119166) (xy 69.273544 -252.074697)
			(xy 69.223111 -252.024264) (xy 69.178642 -251.968502) (xy 69.140696 -251.908111) (xy 69.109751 -251.843852)
			(xy 69.086194 -251.776532) (xy 69.070324 -251.706997) (xy 69.062338 -251.636123) (xy 67.340742 -251.636123)
			(xy 67.332756 -251.706997) (xy 67.316886 -251.776532) (xy 67.293329 -251.843852) (xy 67.262384 -251.908111)
			(xy 67.224438 -251.968502) (xy 67.179969 -252.024264) (xy 67.129536 -252.074697) (xy 67.073774 -252.119166)
			(xy 67.013383 -252.157112) (xy 66.949124 -252.188057) (xy 66.881804 -252.211614) (xy 66.812269 -252.227484)
			(xy 66.741395 -252.23547) (xy 66.670073 -252.23547) (xy 66.599199 -252.227484) (xy 66.529664 -252.211614)
			(xy 66.462344 -252.188057) (xy 66.398085 -252.157112) (xy 66.337694 -252.119166) (xy 66.281932 -252.074697)
			(xy 66.231499 -252.024264) (xy 66.18703 -251.968502) (xy 66.149084 -251.908111) (xy 66.118139 -251.843852)
			(xy 66.094582 -251.776532) (xy 66.078712 -251.706997) (xy 66.070726 -251.636123) (xy 45.055985 -251.636123)
			(xy 45.049414 -251.651988) (xy 45.019447 -251.703894) (xy 44.98296 -251.751444) (xy 44.94058 -251.793824)
			(xy 44.89303 -251.830311) (xy 44.841124 -251.860278) (xy 44.785751 -251.883214) (xy 44.727858 -251.898727)
			(xy 44.668436 -251.90655) (xy 44.6085 -251.90655) (xy 44.549078 -251.898727) (xy 44.491185 -251.883214)
			(xy 44.435812 -251.860278) (xy 44.383906 -251.830311) (xy 44.336356 -251.793824) (xy 44.293976 -251.751444)
			(xy 44.257489 -251.703894) (xy 44.227522 -251.651988) (xy 44.204586 -251.596615) (xy 44.189073 -251.538722)
			(xy 44.18125 -251.4793) (xy 25.904952 -251.4793) (xy 25.904952 -252.553486) (xy 29.519874 -252.553486)
			(xy 29.519874 -252.466586) (xy 29.527892 -252.380057) (xy 29.54386 -252.294637) (xy 29.567641 -252.211055)
			(xy 29.599033 -252.130023) (xy 29.637767 -252.052234) (xy 29.683514 -251.97835) (xy 29.735883 -251.909003)
			(xy 29.794427 -251.844783) (xy 29.858647 -251.786239) (xy 29.927994 -251.73387) (xy 30.001878 -251.688123)
			(xy 30.079667 -251.649389) (xy 30.160699 -251.617997) (xy 30.244281 -251.594216) (xy 30.329701 -251.578248)
			(xy 30.41623 -251.57023) (xy 30.45968 -251.569728) (xy 30.50313 -251.57023) (xy 30.589659 -251.578248)
			(xy 30.675079 -251.594216) (xy 30.758661 -251.617997) (xy 30.839693 -251.649389) (xy 30.917482 -251.688123)
			(xy 30.991366 -251.73387) (xy 31.060713 -251.786239) (xy 31.124933 -251.844783) (xy 31.183477 -251.909003)
			(xy 31.235846 -251.97835) (xy 31.281593 -252.052234) (xy 31.320327 -252.130023) (xy 31.351719 -252.211055)
			(xy 31.3755 -252.294637) (xy 31.391468 -252.380057) (xy 31.399486 -252.466586) (xy 31.399486 -252.553486)
			(xy 34.599874 -252.553486) (xy 34.599874 -252.466586) (xy 34.607892 -252.380057) (xy 34.62386 -252.294637)
			(xy 34.647641 -252.211055) (xy 34.679033 -252.130023) (xy 34.717767 -252.052234) (xy 34.763514 -251.97835)
			(xy 34.815883 -251.909003) (xy 34.874427 -251.844783) (xy 34.938647 -251.786239) (xy 35.007994 -251.73387)
			(xy 35.081878 -251.688123) (xy 35.159667 -251.649389) (xy 35.240699 -251.617997) (xy 35.324281 -251.594216)
			(xy 35.409701 -251.578248) (xy 35.49623 -251.57023) (xy 35.53968 -251.569728) (xy 35.58313 -251.57023)
			(xy 35.669659 -251.578248) (xy 35.755079 -251.594216) (xy 35.838661 -251.617997) (xy 35.919693 -251.649389)
			(xy 35.997482 -251.688123) (xy 36.071366 -251.73387) (xy 36.140713 -251.786239) (xy 36.204933 -251.844783)
			(xy 36.263477 -251.909003) (xy 36.315846 -251.97835) (xy 36.361593 -252.052234) (xy 36.400327 -252.130023)
			(xy 36.431719 -252.211055) (xy 36.4555 -252.294637) (xy 36.471468 -252.380057) (xy 36.479486 -252.466586)
			(xy 36.479486 -252.497437) (xy 41.706538 -252.497437) (xy 41.706538 -252.426115) (xy 41.714524 -252.355241)
			(xy 41.730394 -252.285706) (xy 41.753951 -252.218386) (xy 41.784896 -252.154127) (xy 41.822842 -252.093736)
			(xy 41.867311 -252.037974) (xy 41.917744 -251.987541) (xy 41.973506 -251.943072) (xy 42.033897 -251.905126)
			(xy 42.098156 -251.874181) (xy 42.165476 -251.850624) (xy 42.235011 -251.834754) (xy 42.305885 -251.826768)
			(xy 42.341546 -251.826268) (xy 42.377207 -251.826768) (xy 42.448081 -251.834754) (xy 42.517616 -251.850624)
			(xy 42.584936 -251.874181) (xy 42.649195 -251.905126) (xy 42.709586 -251.943072) (xy 42.765348 -251.987541)
			(xy 42.815781 -252.037974) (xy 42.86025 -252.093736) (xy 42.898196 -252.154127) (xy 42.929141 -252.218386)
			(xy 42.952698 -252.285706) (xy 42.968568 -252.355241) (xy 42.976554 -252.426115) (xy 42.976554 -252.497437)
			(xy 42.968568 -252.568311) (xy 42.952698 -252.637846) (xy 42.929141 -252.705166) (xy 42.898196 -252.769425)
			(xy 42.86025 -252.829816) (xy 42.815781 -252.885578) (xy 42.765348 -252.936011) (xy 42.709586 -252.98048)
			(xy 42.649195 -253.018426) (xy 42.584936 -253.049371) (xy 42.517616 -253.072928) (xy 42.448081 -253.088798)
			(xy 42.377207 -253.096784) (xy 42.305885 -253.096784) (xy 42.235011 -253.088798) (xy 42.165476 -253.072928)
			(xy 42.098156 -253.049371) (xy 42.033897 -253.018426) (xy 41.973506 -252.98048) (xy 41.917744 -252.936011)
			(xy 41.867311 -252.885578) (xy 41.822842 -252.829816) (xy 41.784896 -252.769425) (xy 41.753951 -252.705166)
			(xy 41.730394 -252.637846) (xy 41.714524 -252.568311) (xy 41.706538 -252.497437) (xy 36.479486 -252.497437)
			(xy 36.479486 -252.553486) (xy 36.471468 -252.640015) (xy 36.4555 -252.725435) (xy 36.431719 -252.809017)
			(xy 36.400327 -252.890049) (xy 36.361593 -252.967838) (xy 36.315846 -253.041722) (xy 36.263477 -253.111069)
			(xy 36.204933 -253.175289) (xy 36.140713 -253.233833) (xy 36.071366 -253.286202) (xy 35.997482 -253.331949)
			(xy 35.919693 -253.370683) (xy 35.838661 -253.402075) (xy 35.755079 -253.425856) (xy 35.702911 -253.435608)
			(xy 44.106828 -253.435608) (xy 44.106828 -253.375672) (xy 44.114651 -253.31625) (xy 44.130164 -253.258357)
			(xy 44.1531 -253.202984) (xy 44.183067 -253.151078) (xy 44.219554 -253.103528) (xy 44.261934 -253.061148)
			(xy 44.309484 -253.024661) (xy 44.36139 -252.994694) (xy 44.416763 -252.971758) (xy 44.474656 -252.956245)
			(xy 44.534078 -252.948422) (xy 44.564046 -252.947932) (xy 44.594014 -252.948422) (xy 44.653436 -252.956245)
			(xy 44.711329 -252.971758) (xy 44.766702 -252.994694) (xy 44.818608 -253.024661) (xy 44.866158 -253.061148)
			(xy 44.908538 -253.103528) (xy 44.945025 -253.151078) (xy 44.974992 -253.202984) (xy 44.997928 -253.258357)
			(xy 45.013441 -253.31625) (xy 45.021264 -253.375672) (xy 45.021264 -253.435608) (xy 45.013441 -253.49503)
			(xy 44.997928 -253.552923) (xy 44.974992 -253.608296) (xy 44.945025 -253.660202) (xy 44.908538 -253.707752)
			(xy 44.866158 -253.750132) (xy 44.818608 -253.786619) (xy 44.766702 -253.816586) (xy 44.711329 -253.839522)
			(xy 44.653436 -253.855035) (xy 44.594014 -253.862858) (xy 44.534078 -253.862858) (xy 44.474656 -253.855035)
			(xy 44.416763 -253.839522) (xy 44.36139 -253.816586) (xy 44.309484 -253.786619) (xy 44.261934 -253.750132)
			(xy 44.219554 -253.707752) (xy 44.183067 -253.660202) (xy 44.1531 -253.608296) (xy 44.130164 -253.552923)
			(xy 44.114651 -253.49503) (xy 44.106828 -253.435608) (xy 35.702911 -253.435608) (xy 35.669659 -253.441824)
			(xy 35.58313 -253.449842) (xy 35.49623 -253.449842) (xy 35.409701 -253.441824) (xy 35.324281 -253.425856)
			(xy 35.240699 -253.402075) (xy 35.159667 -253.370683) (xy 35.081878 -253.331949) (xy 35.007994 -253.286202)
			(xy 34.938647 -253.233833) (xy 34.874427 -253.175289) (xy 34.815883 -253.111069) (xy 34.763514 -253.041722)
			(xy 34.717767 -252.967838) (xy 34.679033 -252.890049) (xy 34.647641 -252.809017) (xy 34.62386 -252.725435)
			(xy 34.607892 -252.640015) (xy 34.599874 -252.553486) (xy 31.399486 -252.553486) (xy 31.391468 -252.640015)
			(xy 31.3755 -252.725435) (xy 31.351719 -252.809017) (xy 31.320327 -252.890049) (xy 31.281593 -252.967838)
			(xy 31.235846 -253.041722) (xy 31.183477 -253.111069) (xy 31.124933 -253.175289) (xy 31.060713 -253.233833)
			(xy 30.991366 -253.286202) (xy 30.917482 -253.331949) (xy 30.839693 -253.370683) (xy 30.758661 -253.402075)
			(xy 30.675079 -253.425856) (xy 30.589659 -253.441824) (xy 30.50313 -253.449842) (xy 30.41623 -253.449842)
			(xy 30.329701 -253.441824) (xy 30.244281 -253.425856) (xy 30.160699 -253.402075) (xy 30.079667 -253.370683)
			(xy 30.001878 -253.331949) (xy 29.927994 -253.286202) (xy 29.858647 -253.233833) (xy 29.794427 -253.175289)
			(xy 29.735883 -253.111069) (xy 29.683514 -253.041722) (xy 29.637767 -252.967838) (xy 29.599033 -252.890049)
			(xy 29.567641 -252.809017) (xy 29.54386 -252.725435) (xy 29.527892 -252.640015) (xy 29.519874 -252.553486)
			(xy 25.904952 -252.553486) (xy 25.904952 -253.52883) (xy 25.924773 -253.550187) (xy 25.959406 -253.597045)
			(xy 25.987809 -253.647921) (xy 26.009524 -253.701991) (xy 26.024198 -253.75838) (xy 26.031594 -253.816176)
			(xy 26.031593 -253.874444) (xy 26.024194 -253.93224) (xy 26.009517 -253.988628) (xy 25.9878 -254.042698)
			(xy 25.959395 -254.093572) (xy 25.92476 -254.140429) (xy 25.904952 -254.161798) (xy 25.904952 -255.093486)
			(xy 29.519874 -255.093486) (xy 29.519874 -255.006586) (xy 29.527892 -254.920057) (xy 29.54386 -254.834637)
			(xy 29.567641 -254.751055) (xy 29.599033 -254.670023) (xy 29.637767 -254.592234) (xy 29.683514 -254.51835)
			(xy 29.735883 -254.449003) (xy 29.794427 -254.384783) (xy 29.858647 -254.326239) (xy 29.927994 -254.27387)
			(xy 30.001878 -254.228123) (xy 30.079667 -254.189389) (xy 30.160699 -254.157997) (xy 30.244281 -254.134216)
			(xy 30.329701 -254.118248) (xy 30.41623 -254.11023) (xy 30.45968 -254.109728) (xy 30.50313 -254.11023)
			(xy 30.589659 -254.118248) (xy 30.675079 -254.134216) (xy 30.758661 -254.157997) (xy 30.839693 -254.189389)
			(xy 30.917482 -254.228123) (xy 30.991366 -254.27387) (xy 31.060713 -254.326239) (xy 31.124933 -254.384783)
			(xy 31.183477 -254.449003) (xy 31.235846 -254.51835) (xy 31.281593 -254.592234) (xy 31.320327 -254.670023)
			(xy 31.351719 -254.751055) (xy 31.3755 -254.834637) (xy 31.391468 -254.920057) (xy 31.399486 -255.006586)
			(xy 31.399486 -255.093486) (xy 34.599874 -255.093486) (xy 34.599874 -255.006586) (xy 34.607892 -254.920057)
			(xy 34.62386 -254.834637) (xy 34.647641 -254.751055) (xy 34.679033 -254.670023) (xy 34.717767 -254.592234)
			(xy 34.763514 -254.51835) (xy 34.815883 -254.449003) (xy 34.874427 -254.384783) (xy 34.938647 -254.326239)
			(xy 35.007994 -254.27387) (xy 35.081878 -254.228123) (xy 35.159667 -254.189389) (xy 35.240699 -254.157997)
			(xy 35.324281 -254.134216) (xy 35.409701 -254.118248) (xy 35.49623 -254.11023) (xy 35.53968 -254.109728)
			(xy 35.58313 -254.11023) (xy 35.669659 -254.118248) (xy 35.755079 -254.134216) (xy 35.838661 -254.157997)
			(xy 35.919693 -254.189389) (xy 35.997482 -254.228123) (xy 36.071366 -254.27387) (xy 36.140713 -254.326239)
			(xy 36.204933 -254.384783) (xy 36.263477 -254.449003) (xy 36.315846 -254.51835) (xy 36.361593 -254.592234)
			(xy 36.400327 -254.670023) (xy 36.431719 -254.751055) (xy 36.4555 -254.834637) (xy 36.471468 -254.920057)
			(xy 36.473542 -254.942441) (xy 41.636688 -254.942441) (xy 41.636688 -254.871119) (xy 41.644674 -254.800245)
			(xy 41.660544 -254.73071) (xy 41.684101 -254.66339) (xy 41.715046 -254.599131) (xy 41.752992 -254.53874)
			(xy 41.797461 -254.482978) (xy 41.847894 -254.432545) (xy 41.903656 -254.388076) (xy 41.964047 -254.35013)
			(xy 42.028306 -254.319185) (xy 42.095626 -254.295628) (xy 42.165161 -254.279758) (xy 42.236035 -254.271772)
			(xy 42.271696 -254.271272) (xy 42.307357 -254.271772) (xy 42.378231 -254.279758) (xy 42.447766 -254.295628)
			(xy 42.515086 -254.319185) (xy 42.579345 -254.35013) (xy 42.598721 -254.362305) (xy 77.412588 -254.362305)
			(xy 77.412588 -254.290983) (xy 77.420574 -254.220109) (xy 77.436444 -254.150574) (xy 77.460001 -254.083254)
			(xy 77.490946 -254.018995) (xy 77.528892 -253.958604) (xy 77.573361 -253.902842) (xy 77.623794 -253.852409)
			(xy 77.679556 -253.80794) (xy 77.739947 -253.769994) (xy 77.804206 -253.739049) (xy 77.871526 -253.715492)
			(xy 77.941061 -253.699622) (xy 78.011935 -253.691636) (xy 78.047596 -253.691136) (xy 78.083257 -253.691636)
			(xy 78.154131 -253.699622) (xy 78.223666 -253.715492) (xy 78.290986 -253.739049) (xy 78.355245 -253.769994)
			(xy 78.415636 -253.80794) (xy 78.471398 -253.852409) (xy 78.521831 -253.902842) (xy 78.5663 -253.958604)
			(xy 78.604246 -254.018995) (xy 78.635191 -254.083254) (xy 78.658748 -254.150574) (xy 78.674618 -254.220109)
			(xy 78.682604 -254.290983) (xy 78.682604 -254.362305) (xy 80.217002 -254.362305) (xy 80.217002 -254.290983)
			(xy 80.224988 -254.220109) (xy 80.240858 -254.150574) (xy 80.264415 -254.083254) (xy 80.29536 -254.018995)
			(xy 80.333306 -253.958604) (xy 80.377775 -253.902842) (xy 80.428208 -253.852409) (xy 80.48397 -253.80794)
			(xy 80.544361 -253.769994) (xy 80.60862 -253.739049) (xy 80.67594 -253.715492) (xy 80.745475 -253.699622)
			(xy 80.816349 -253.691636) (xy 80.85201 -253.691136) (xy 80.887671 -253.691636) (xy 80.958545 -253.699622)
			(xy 81.02808 -253.715492) (xy 81.0954 -253.739049) (xy 81.159659 -253.769994) (xy 81.22005 -253.80794)
			(xy 81.275812 -253.852409) (xy 81.326245 -253.902842) (xy 81.370714 -253.958604) (xy 81.40866 -254.018995)
			(xy 81.439605 -254.083254) (xy 81.463162 -254.150574) (xy 81.479032 -254.220109) (xy 81.487018 -254.290983)
			(xy 81.487018 -254.362305) (xy 81.479032 -254.433179) (xy 81.463162 -254.502714) (xy 81.439605 -254.570034)
			(xy 81.40866 -254.634293) (xy 81.370714 -254.694684) (xy 81.326245 -254.750446) (xy 81.275812 -254.800879)
			(xy 81.22005 -254.845348) (xy 81.159659 -254.883294) (xy 81.0954 -254.914239) (xy 81.02808 -254.937796)
			(xy 80.958545 -254.953666) (xy 80.887671 -254.961652) (xy 80.816349 -254.961652) (xy 80.745475 -254.953666)
			(xy 80.67594 -254.937796) (xy 80.60862 -254.914239) (xy 80.544361 -254.883294) (xy 80.48397 -254.845348)
			(xy 80.428208 -254.800879) (xy 80.377775 -254.750446) (xy 80.333306 -254.694684) (xy 80.29536 -254.634293)
			(xy 80.264415 -254.570034) (xy 80.240858 -254.502714) (xy 80.224988 -254.433179) (xy 80.217002 -254.362305)
			(xy 78.682604 -254.362305) (xy 78.674618 -254.433179) (xy 78.658748 -254.502714) (xy 78.635191 -254.570034)
			(xy 78.604246 -254.634293) (xy 78.5663 -254.694684) (xy 78.521831 -254.750446) (xy 78.471398 -254.800879)
			(xy 78.415636 -254.845348) (xy 78.355245 -254.883294) (xy 78.290986 -254.914239) (xy 78.223666 -254.937796)
			(xy 78.154131 -254.953666) (xy 78.083257 -254.961652) (xy 78.011935 -254.961652) (xy 77.941061 -254.953666)
			(xy 77.871526 -254.937796) (xy 77.804206 -254.914239) (xy 77.739947 -254.883294) (xy 77.679556 -254.845348)
			(xy 77.623794 -254.800879) (xy 77.573361 -254.750446) (xy 77.528892 -254.694684) (xy 77.490946 -254.634293)
			(xy 77.460001 -254.570034) (xy 77.436444 -254.502714) (xy 77.420574 -254.433179) (xy 77.412588 -254.362305)
			(xy 42.598721 -254.362305) (xy 42.639736 -254.388076) (xy 42.695498 -254.432545) (xy 42.745931 -254.482978)
			(xy 42.7904 -254.53874) (xy 42.828346 -254.599131) (xy 42.859291 -254.66339) (xy 42.882848 -254.73071)
			(xy 42.898718 -254.800245) (xy 42.906704 -254.871119) (xy 42.906704 -254.942441) (xy 42.898718 -255.013315)
			(xy 42.882848 -255.08285) (xy 42.859291 -255.15017) (xy 42.828346 -255.214429) (xy 42.7904 -255.27482)
			(xy 42.745931 -255.330582) (xy 42.695498 -255.381015) (xy 42.639736 -255.425484) (xy 42.579345 -255.46343)
			(xy 42.515086 -255.494375) (xy 42.447766 -255.517932) (xy 42.378231 -255.533802) (xy 42.307357 -255.541788)
			(xy 42.236035 -255.541788) (xy 42.165161 -255.533802) (xy 42.095626 -255.517932) (xy 42.028306 -255.494375)
			(xy 41.964047 -255.46343) (xy 41.903656 -255.425484) (xy 41.847894 -255.381015) (xy 41.797461 -255.330582)
			(xy 41.752992 -255.27482) (xy 41.715046 -255.214429) (xy 41.684101 -255.15017) (xy 41.660544 -255.08285)
			(xy 41.644674 -255.013315) (xy 41.636688 -254.942441) (xy 36.473542 -254.942441) (xy 36.479486 -255.006586)
			(xy 36.479486 -255.093486) (xy 36.471468 -255.180015) (xy 36.4555 -255.265435) (xy 36.431719 -255.349017)
			(xy 36.400327 -255.430049) (xy 36.361593 -255.507838) (xy 36.315846 -255.581722) (xy 36.263477 -255.651069)
			(xy 36.204933 -255.715289) (xy 36.140713 -255.773833) (xy 36.071366 -255.826202) (xy 35.997482 -255.871949)
			(xy 35.919693 -255.910683) (xy 35.838661 -255.942075) (xy 35.755079 -255.965856) (xy 35.669659 -255.981824)
			(xy 35.58313 -255.989842) (xy 35.49623 -255.989842) (xy 35.409701 -255.981824) (xy 35.324281 -255.965856)
			(xy 35.240699 -255.942075) (xy 35.159667 -255.910683) (xy 35.081878 -255.871949) (xy 35.007994 -255.826202)
			(xy 34.938647 -255.773833) (xy 34.874427 -255.715289) (xy 34.815883 -255.651069) (xy 34.763514 -255.581722)
			(xy 34.717767 -255.507838) (xy 34.679033 -255.430049) (xy 34.647641 -255.349017) (xy 34.62386 -255.265435)
			(xy 34.607892 -255.180015) (xy 34.599874 -255.093486) (xy 31.399486 -255.093486) (xy 31.391468 -255.180015)
			(xy 31.3755 -255.265435) (xy 31.351719 -255.349017) (xy 31.320327 -255.430049) (xy 31.281593 -255.507838)
			(xy 31.235846 -255.581722) (xy 31.183477 -255.651069) (xy 31.124933 -255.715289) (xy 31.060713 -255.773833)
			(xy 30.991366 -255.826202) (xy 30.917482 -255.871949) (xy 30.839693 -255.910683) (xy 30.758661 -255.942075)
			(xy 30.675079 -255.965856) (xy 30.589659 -255.981824) (xy 30.50313 -255.989842) (xy 30.41623 -255.989842)
			(xy 30.329701 -255.981824) (xy 30.244281 -255.965856) (xy 30.160699 -255.942075) (xy 30.079667 -255.910683)
			(xy 30.001878 -255.871949) (xy 29.927994 -255.826202) (xy 29.858647 -255.773833) (xy 29.794427 -255.715289)
			(xy 29.735883 -255.651069) (xy 29.683514 -255.581722) (xy 29.637767 -255.507838) (xy 29.599033 -255.430049)
			(xy 29.567641 -255.349017) (xy 29.54386 -255.265435) (xy 29.527892 -255.180015) (xy 29.519874 -255.093486)
			(xy 25.904952 -255.093486) (xy 25.904952 -257.633486) (xy 29.519874 -257.633486) (xy 29.519874 -257.546586)
			(xy 29.527892 -257.460057) (xy 29.54386 -257.374637) (xy 29.567641 -257.291055) (xy 29.599033 -257.210023)
			(xy 29.637767 -257.132234) (xy 29.683514 -257.05835) (xy 29.735883 -256.989003) (xy 29.794427 -256.924783)
			(xy 29.858647 -256.866239) (xy 29.927994 -256.81387) (xy 30.001878 -256.768123) (xy 30.079667 -256.729389)
			(xy 30.160699 -256.697997) (xy 30.244281 -256.674216) (xy 30.329701 -256.658248) (xy 30.41623 -256.65023)
			(xy 30.45968 -256.649728) (xy 30.50313 -256.65023) (xy 30.589659 -256.658248) (xy 30.675079 -256.674216)
			(xy 30.758661 -256.697997) (xy 30.839693 -256.729389) (xy 30.917482 -256.768123) (xy 30.991366 -256.81387)
			(xy 31.060713 -256.866239) (xy 31.124933 -256.924783) (xy 31.183477 -256.989003) (xy 31.235846 -257.05835)
			(xy 31.281593 -257.132234) (xy 31.320327 -257.210023) (xy 31.351719 -257.291055) (xy 31.3755 -257.374637)
			(xy 31.391468 -257.460057) (xy 31.399486 -257.546586) (xy 31.399486 -257.633486) (xy 34.599874 -257.633486)
			(xy 34.599874 -257.546586) (xy 34.607892 -257.460057) (xy 34.62386 -257.374637) (xy 34.647641 -257.291055)
			(xy 34.679033 -257.210023) (xy 34.717767 -257.132234) (xy 34.763514 -257.05835) (xy 34.815883 -256.989003)
			(xy 34.874427 -256.924783) (xy 34.938647 -256.866239) (xy 35.007994 -256.81387) (xy 35.081878 -256.768123)
			(xy 35.159667 -256.729389) (xy 35.240699 -256.697997) (xy 35.324281 -256.674216) (xy 35.409701 -256.658248)
			(xy 35.49623 -256.65023) (xy 35.53968 -256.649728) (xy 35.58313 -256.65023) (xy 35.669659 -256.658248)
			(xy 35.755079 -256.674216) (xy 35.838661 -256.697997) (xy 35.919693 -256.729389) (xy 35.997482 -256.768123)
			(xy 36.071366 -256.81387) (xy 36.140713 -256.866239) (xy 36.183619 -256.905353) (xy 41.636688 -256.905353)
			(xy 41.636688 -256.834031) (xy 41.644674 -256.763157) (xy 41.660544 -256.693622) (xy 41.684101 -256.626302)
			(xy 41.715046 -256.562043) (xy 41.752992 -256.501652) (xy 41.797461 -256.44589) (xy 41.847894 -256.395457)
			(xy 41.903656 -256.350988) (xy 41.964047 -256.313042) (xy 42.028306 -256.282097) (xy 42.095626 -256.25854)
			(xy 42.165161 -256.24267) (xy 42.236035 -256.234684) (xy 42.271696 -256.234184) (xy 42.307357 -256.234684)
			(xy 42.378231 -256.24267) (xy 42.398903 -256.247388) (xy 44.170074 -256.247388) (xy 44.170074 -256.187452)
			(xy 44.177897 -256.12803) (xy 44.19341 -256.070137) (xy 44.216346 -256.014764) (xy 44.246313 -255.962858)
			(xy 44.2828 -255.915308) (xy 44.32518 -255.872928) (xy 44.37273 -255.836441) (xy 44.424636 -255.806474)
			(xy 44.480009 -255.783538) (xy 44.537902 -255.768025) (xy 44.597324 -255.760202) (xy 44.627292 -255.759712)
			(xy 44.65726 -255.760202) (xy 44.716682 -255.768025) (xy 44.774575 -255.783538) (xy 44.829948 -255.806474)
			(xy 44.881854 -255.836441) (xy 44.929404 -255.872928) (xy 44.947099 -255.890623) (xy 77.362804 -255.890623)
			(xy 77.362804 -255.819301) (xy 77.37079 -255.748427) (xy 77.38666 -255.678892) (xy 77.410217 -255.611572)
			(xy 77.441162 -255.547313) (xy 77.479108 -255.486922) (xy 77.523577 -255.43116) (xy 77.57401 -255.380727)
			(xy 77.629772 -255.336258) (xy 77.690163 -255.298312) (xy 77.754422 -255.267367) (xy 77.821742 -255.24381)
			(xy 77.891277 -255.22794) (xy 77.962151 -255.219954) (xy 77.997812 -255.219454) (xy 78.033473 -255.219954)
			(xy 78.104347 -255.22794) (xy 78.173882 -255.24381) (xy 78.241202 -255.267367) (xy 78.305461 -255.298312)
			(xy 78.365852 -255.336258) (xy 78.421614 -255.380727) (xy 78.472047 -255.43116) (xy 78.516516 -255.486922)
			(xy 78.554462 -255.547313) (xy 78.585407 -255.611572) (xy 78.608964 -255.678892) (xy 78.624834 -255.748427)
			(xy 78.63282 -255.819301) (xy 78.63282 -255.890623) (xy 80.167218 -255.890623) (xy 80.167218 -255.819301)
			(xy 80.175204 -255.748427) (xy 80.191074 -255.678892) (xy 80.214631 -255.611572) (xy 80.245576 -255.547313)
			(xy 80.283522 -255.486922) (xy 80.327991 -255.43116) (xy 80.378424 -255.380727) (xy 80.434186 -255.336258)
			(xy 80.494577 -255.298312) (xy 80.558836 -255.267367) (xy 80.626156 -255.24381) (xy 80.695691 -255.22794)
			(xy 80.766565 -255.219954) (xy 80.802226 -255.219454) (xy 80.837887 -255.219954) (xy 80.908761 -255.22794)
			(xy 80.978296 -255.24381) (xy 81.045616 -255.267367) (xy 81.109875 -255.298312) (xy 81.170266 -255.336258)
			(xy 81.226028 -255.380727) (xy 81.276461 -255.43116) (xy 81.32093 -255.486922) (xy 81.358876 -255.547313)
			(xy 81.389821 -255.611572) (xy 81.413378 -255.678892) (xy 81.429248 -255.748427) (xy 81.437234 -255.819301)
			(xy 81.437234 -255.890623) (xy 81.429248 -255.961497) (xy 81.413378 -256.031032) (xy 81.389821 -256.098352)
			(xy 81.358876 -256.162611) (xy 81.32093 -256.223002) (xy 81.276461 -256.278764) (xy 81.226028 -256.329197)
			(xy 81.170266 -256.373666) (xy 81.109875 -256.411612) (xy 81.045616 -256.442557) (xy 80.978296 -256.466114)
			(xy 80.908761 -256.481984) (xy 80.837887 -256.48997) (xy 80.766565 -256.48997) (xy 80.695691 -256.481984)
			(xy 80.626156 -256.466114) (xy 80.558836 -256.442557) (xy 80.494577 -256.411612) (xy 80.434186 -256.373666)
			(xy 80.378424 -256.329197) (xy 80.327991 -256.278764) (xy 80.283522 -256.223002) (xy 80.245576 -256.162611)
			(xy 80.214631 -256.098352) (xy 80.191074 -256.031032) (xy 80.175204 -255.961497) (xy 80.167218 -255.890623)
			(xy 78.63282 -255.890623) (xy 78.624834 -255.961497) (xy 78.608964 -256.031032) (xy 78.585407 -256.098352)
			(xy 78.554462 -256.162611) (xy 78.516516 -256.223002) (xy 78.472047 -256.278764) (xy 78.421614 -256.329197)
			(xy 78.365852 -256.373666) (xy 78.305461 -256.411612) (xy 78.241202 -256.442557) (xy 78.173882 -256.466114)
			(xy 78.104347 -256.481984) (xy 78.033473 -256.48997) (xy 77.962151 -256.48997) (xy 77.891277 -256.481984)
			(xy 77.821742 -256.466114) (xy 77.754422 -256.442557) (xy 77.690163 -256.411612) (xy 77.629772 -256.373666)
			(xy 77.57401 -256.329197) (xy 77.523577 -256.278764) (xy 77.479108 -256.223002) (xy 77.441162 -256.162611)
			(xy 77.410217 -256.098352) (xy 77.38666 -256.031032) (xy 77.37079 -255.961497) (xy 77.362804 -255.890623)
			(xy 44.947099 -255.890623) (xy 44.971784 -255.915308) (xy 45.008271 -255.962858) (xy 45.038238 -256.014764)
			(xy 45.061174 -256.070137) (xy 45.076687 -256.12803) (xy 45.08451 -256.187452) (xy 45.08451 -256.247388)
			(xy 45.076687 -256.30681) (xy 45.061174 -256.364703) (xy 45.038238 -256.420076) (xy 45.008271 -256.471982)
			(xy 44.971784 -256.519532) (xy 44.929404 -256.561912) (xy 44.881854 -256.598399) (xy 44.829948 -256.628366)
			(xy 44.774575 -256.651302) (xy 44.716682 -256.666815) (xy 44.65726 -256.674638) (xy 44.597324 -256.674638)
			(xy 44.537902 -256.666815) (xy 44.480009 -256.651302) (xy 44.424636 -256.628366) (xy 44.37273 -256.598399)
			(xy 44.32518 -256.561912) (xy 44.2828 -256.519532) (xy 44.246313 -256.471982) (xy 44.216346 -256.420076)
			(xy 44.19341 -256.364703) (xy 44.177897 -256.30681) (xy 44.170074 -256.247388) (xy 42.398903 -256.247388)
			(xy 42.447766 -256.25854) (xy 42.515086 -256.282097) (xy 42.579345 -256.313042) (xy 42.639736 -256.350988)
			(xy 42.695498 -256.395457) (xy 42.745931 -256.44589) (xy 42.7904 -256.501652) (xy 42.828346 -256.562043)
			(xy 42.859291 -256.626302) (xy 42.882848 -256.693622) (xy 42.898718 -256.763157) (xy 42.906704 -256.834031)
			(xy 42.906704 -256.905353) (xy 42.898718 -256.976227) (xy 42.882848 -257.045762) (xy 42.859291 -257.113082)
			(xy 42.828346 -257.177341) (xy 42.7904 -257.237732) (xy 42.745931 -257.293494) (xy 42.695498 -257.343927)
			(xy 42.639736 -257.388396) (xy 42.579345 -257.426342) (xy 42.515086 -257.457287) (xy 42.447766 -257.480844)
			(xy 42.378231 -257.496714) (xy 42.307357 -257.5047) (xy 42.236035 -257.5047) (xy 42.165161 -257.496714)
			(xy 42.095626 -257.480844) (xy 42.028306 -257.457287) (xy 41.964047 -257.426342) (xy 41.903656 -257.388396)
			(xy 41.847894 -257.343927) (xy 41.797461 -257.293494) (xy 41.752992 -257.237732) (xy 41.715046 -257.177341)
			(xy 41.684101 -257.113082) (xy 41.660544 -257.045762) (xy 41.644674 -256.976227) (xy 41.636688 -256.905353)
			(xy 36.183619 -256.905353) (xy 36.204933 -256.924783) (xy 36.263477 -256.989003) (xy 36.315846 -257.05835)
			(xy 36.361593 -257.132234) (xy 36.400327 -257.210023) (xy 36.431719 -257.291055) (xy 36.4555 -257.374637)
			(xy 36.471468 -257.460057) (xy 36.479486 -257.546586) (xy 36.479486 -257.615537) (xy 77.379314 -257.615537)
			(xy 77.379314 -257.544215) (xy 77.3873 -257.473341) (xy 77.40317 -257.403806) (xy 77.426727 -257.336486)
			(xy 77.457672 -257.272227) (xy 77.495618 -257.211836) (xy 77.540087 -257.156074) (xy 77.59052 -257.105641)
			(xy 77.646282 -257.061172) (xy 77.706673 -257.023226) (xy 77.770932 -256.992281) (xy 77.838252 -256.968724)
			(xy 77.907787 -256.952854) (xy 77.978661 -256.944868) (xy 78.014322 -256.944368) (xy 78.049983 -256.944868)
			(xy 78.120857 -256.952854) (xy 78.190392 -256.968724) (xy 78.257712 -256.992281) (xy 78.321971 -257.023226)
			(xy 78.382362 -257.061172) (xy 78.438124 -257.105641) (xy 78.488557 -257.156074) (xy 78.533026 -257.211836)
			(xy 78.570972 -257.272227) (xy 78.601917 -257.336486) (xy 78.625474 -257.403806) (xy 78.641344 -257.473341)
			(xy 78.64933 -257.544215) (xy 78.64933 -257.615537) (xy 80.183728 -257.615537) (xy 80.183728 -257.544215)
			(xy 80.191714 -257.473341) (xy 80.207584 -257.403806) (xy 80.231141 -257.336486) (xy 80.262086 -257.272227)
			(xy 80.300032 -257.211836) (xy 80.344501 -257.156074) (xy 80.394934 -257.105641) (xy 80.450696 -257.061172)
			(xy 80.511087 -257.023226) (xy 80.575346 -256.992281) (xy 80.642666 -256.968724) (xy 80.712201 -256.952854)
			(xy 80.783075 -256.944868) (xy 80.818736 -256.944368) (xy 80.854397 -256.944868) (xy 80.925271 -256.952854)
			(xy 80.994806 -256.968724) (xy 81.062126 -256.992281) (xy 81.126385 -257.023226) (xy 81.186776 -257.061172)
			(xy 81.242538 -257.105641) (xy 81.292971 -257.156074) (xy 81.33744 -257.211836) (xy 81.375386 -257.272227)
			(xy 81.406331 -257.336486) (xy 81.429888 -257.403806) (xy 81.445758 -257.473341) (xy 81.453744 -257.544215)
			(xy 81.453744 -257.615537) (xy 81.445758 -257.686411) (xy 81.429888 -257.755946) (xy 81.406331 -257.823266)
			(xy 81.375386 -257.887525) (xy 81.33744 -257.947916) (xy 81.292971 -258.003678) (xy 81.242538 -258.054111)
			(xy 81.186776 -258.09858) (xy 81.126385 -258.136526) (xy 81.062126 -258.167471) (xy 80.994806 -258.191028)
			(xy 80.925271 -258.206898) (xy 80.854397 -258.214884) (xy 80.783075 -258.214884) (xy 80.712201 -258.206898)
			(xy 80.642666 -258.191028) (xy 80.575346 -258.167471) (xy 80.511087 -258.136526) (xy 80.450696 -258.09858)
			(xy 80.394934 -258.054111) (xy 80.344501 -258.003678) (xy 80.300032 -257.947916) (xy 80.262086 -257.887525)
			(xy 80.231141 -257.823266) (xy 80.207584 -257.755946) (xy 80.191714 -257.686411) (xy 80.183728 -257.615537)
			(xy 78.64933 -257.615537) (xy 78.641344 -257.686411) (xy 78.625474 -257.755946) (xy 78.601917 -257.823266)
			(xy 78.570972 -257.887525) (xy 78.533026 -257.947916) (xy 78.488557 -258.003678) (xy 78.438124 -258.054111)
			(xy 78.382362 -258.09858) (xy 78.321971 -258.136526) (xy 78.257712 -258.167471) (xy 78.190392 -258.191028)
			(xy 78.120857 -258.206898) (xy 78.049983 -258.214884) (xy 77.978661 -258.214884) (xy 77.907787 -258.206898)
			(xy 77.838252 -258.191028) (xy 77.770932 -258.167471) (xy 77.706673 -258.136526) (xy 77.646282 -258.09858)
			(xy 77.59052 -258.054111) (xy 77.540087 -258.003678) (xy 77.495618 -257.947916) (xy 77.457672 -257.887525)
			(xy 77.426727 -257.823266) (xy 77.40317 -257.755946) (xy 77.3873 -257.686411) (xy 77.379314 -257.615537)
			(xy 36.479486 -257.615537) (xy 36.479486 -257.633486) (xy 36.471468 -257.720015) (xy 36.4555 -257.805435)
			(xy 36.431719 -257.889017) (xy 36.400327 -257.970049) (xy 36.361593 -258.047838) (xy 36.315846 -258.121722)
			(xy 36.280028 -258.169152) (xy 44.112924 -258.169152) (xy 44.112924 -258.109216) (xy 44.120747 -258.049794)
			(xy 44.13626 -257.991901) (xy 44.159196 -257.936528) (xy 44.189163 -257.884622) (xy 44.22565 -257.837072)
			(xy 44.26803 -257.794692) (xy 44.31558 -257.758205) (xy 44.367486 -257.728238) (xy 44.422859 -257.705302)
			(xy 44.480752 -257.689789) (xy 44.540174 -257.681966) (xy 44.570142 -257.681476) (xy 44.60011 -257.681966)
			(xy 44.659532 -257.689789) (xy 44.717425 -257.705302) (xy 44.772798 -257.728238) (xy 44.824704 -257.758205)
			(xy 44.872254 -257.794692) (xy 44.914634 -257.837072) (xy 44.951121 -257.884622) (xy 44.981088 -257.936528)
			(xy 45.004024 -257.991901) (xy 45.019537 -258.049794) (xy 45.02736 -258.109216) (xy 45.02736 -258.169152)
			(xy 45.019537 -258.228574) (xy 45.004024 -258.286467) (xy 44.981088 -258.34184) (xy 44.951121 -258.393746)
			(xy 44.914634 -258.441296) (xy 44.872254 -258.483676) (xy 44.824704 -258.520163) (xy 44.772798 -258.55013)
			(xy 44.717425 -258.573066) (xy 44.659532 -258.588579) (xy 44.60011 -258.596402) (xy 44.540174 -258.596402)
			(xy 44.480752 -258.588579) (xy 44.422859 -258.573066) (xy 44.367486 -258.55013) (xy 44.31558 -258.520163)
			(xy 44.26803 -258.483676) (xy 44.22565 -258.441296) (xy 44.189163 -258.393746) (xy 44.159196 -258.34184)
			(xy 44.13626 -258.286467) (xy 44.120747 -258.228574) (xy 44.112924 -258.169152) (xy 36.280028 -258.169152)
			(xy 36.263477 -258.191069) (xy 36.204933 -258.255289) (xy 36.140713 -258.313833) (xy 36.071366 -258.366202)
			(xy 35.997482 -258.411949) (xy 35.919693 -258.450683) (xy 35.838661 -258.482075) (xy 35.755079 -258.505856)
			(xy 35.669659 -258.521824) (xy 35.58313 -258.529842) (xy 35.49623 -258.529842) (xy 35.409701 -258.521824)
			(xy 35.324281 -258.505856) (xy 35.240699 -258.482075) (xy 35.159667 -258.450683) (xy 35.081878 -258.411949)
			(xy 35.007994 -258.366202) (xy 34.938647 -258.313833) (xy 34.874427 -258.255289) (xy 34.815883 -258.191069)
			(xy 34.763514 -258.121722) (xy 34.717767 -258.047838) (xy 34.679033 -257.970049) (xy 34.647641 -257.889017)
			(xy 34.62386 -257.805435) (xy 34.607892 -257.720015) (xy 34.599874 -257.633486) (xy 31.399486 -257.633486)
			(xy 31.391468 -257.720015) (xy 31.3755 -257.805435) (xy 31.351719 -257.889017) (xy 31.320327 -257.970049)
			(xy 31.281593 -258.047838) (xy 31.235846 -258.121722) (xy 31.183477 -258.191069) (xy 31.124933 -258.255289)
			(xy 31.060713 -258.313833) (xy 30.991366 -258.366202) (xy 30.917482 -258.411949) (xy 30.839693 -258.450683)
			(xy 30.758661 -258.482075) (xy 30.675079 -258.505856) (xy 30.589659 -258.521824) (xy 30.50313 -258.529842)
			(xy 30.41623 -258.529842) (xy 30.329701 -258.521824) (xy 30.244281 -258.505856) (xy 30.160699 -258.482075)
			(xy 30.079667 -258.450683) (xy 30.001878 -258.411949) (xy 29.927994 -258.366202) (xy 29.858647 -258.313833)
			(xy 29.794427 -258.255289) (xy 29.735883 -258.191069) (xy 29.683514 -258.121722) (xy 29.637767 -258.047838)
			(xy 29.599033 -257.970049) (xy 29.567641 -257.889017) (xy 29.54386 -257.805435) (xy 29.527892 -257.720015)
			(xy 29.519874 -257.633486) (xy 25.904952 -257.633486) (xy 25.904952 -258.128008) (xy 26.825803 -259.048859)
			(xy 41.636688 -259.048859) (xy 41.636688 -258.977537) (xy 41.644674 -258.906663) (xy 41.660544 -258.837128)
			(xy 41.684101 -258.769808) (xy 41.715046 -258.705549) (xy 41.752992 -258.645158) (xy 41.797461 -258.589396)
			(xy 41.847894 -258.538963) (xy 41.903656 -258.494494) (xy 41.964047 -258.456548) (xy 42.028306 -258.425603)
			(xy 42.095626 -258.402046) (xy 42.165161 -258.386176) (xy 42.236035 -258.37819) (xy 42.271696 -258.37769)
			(xy 42.307357 -258.37819) (xy 42.378231 -258.386176) (xy 42.447766 -258.402046) (xy 42.515086 -258.425603)
			(xy 42.579345 -258.456548) (xy 42.639736 -258.494494) (xy 42.695498 -258.538963) (xy 42.745931 -258.589396)
			(xy 42.7904 -258.645158) (xy 42.828346 -258.705549) (xy 42.859291 -258.769808) (xy 42.882848 -258.837128)
			(xy 42.898718 -258.906663) (xy 42.906704 -258.977537) (xy 42.906704 -259.048859) (xy 42.898718 -259.119733)
			(xy 42.882848 -259.189268) (xy 42.859291 -259.256588) (xy 42.846794 -259.282539) (xy 77.392268 -259.282539)
			(xy 77.392268 -259.211217) (xy 77.400254 -259.140343) (xy 77.416124 -259.070808) (xy 77.439681 -259.003488)
			(xy 77.470626 -258.939229) (xy 77.508572 -258.878838) (xy 77.553041 -258.823076) (xy 77.603474 -258.772643)
			(xy 77.659236 -258.728174) (xy 77.719627 -258.690228) (xy 77.783886 -258.659283) (xy 77.851206 -258.635726)
			(xy 77.920741 -258.619856) (xy 77.991615 -258.61187) (xy 78.027276 -258.61137) (xy 78.062937 -258.61187)
			(xy 78.133811 -258.619856) (xy 78.203346 -258.635726) (xy 78.270666 -258.659283) (xy 78.334925 -258.690228)
			(xy 78.395316 -258.728174) (xy 78.451078 -258.772643) (xy 78.501511 -258.823076) (xy 78.54598 -258.878838)
			(xy 78.583926 -258.939229) (xy 78.614871 -259.003488) (xy 78.638428 -259.070808) (xy 78.654298 -259.140343)
			(xy 78.662284 -259.211217) (xy 78.662284 -259.282539) (xy 80.196682 -259.282539) (xy 80.196682 -259.211217)
			(xy 80.204668 -259.140343) (xy 80.220538 -259.070808) (xy 80.244095 -259.003488) (xy 80.27504 -258.939229)
			(xy 80.312986 -258.878838) (xy 80.357455 -258.823076) (xy 80.407888 -258.772643) (xy 80.46365 -258.728174)
			(xy 80.524041 -258.690228) (xy 80.5883 -258.659283) (xy 80.65562 -258.635726) (xy 80.725155 -258.619856)
			(xy 80.796029 -258.61187) (xy 80.83169 -258.61137) (xy 80.867351 -258.61187) (xy 80.938225 -258.619856)
			(xy 81.00776 -258.635726) (xy 81.07508 -258.659283) (xy 81.139339 -258.690228) (xy 81.19973 -258.728174)
			(xy 81.255492 -258.772643) (xy 81.305925 -258.823076) (xy 81.350394 -258.878838) (xy 81.38834 -258.939229)
			(xy 81.419285 -259.003488) (xy 81.442842 -259.070808) (xy 81.458712 -259.140343) (xy 81.466698 -259.211217)
			(xy 81.466698 -259.282539) (xy 81.458712 -259.353413) (xy 81.442842 -259.422948) (xy 81.419285 -259.490268)
			(xy 81.38834 -259.554527) (xy 81.350394 -259.614918) (xy 81.305925 -259.67068) (xy 81.255492 -259.721113)
			(xy 81.19973 -259.765582) (xy 81.139339 -259.803528) (xy 81.07508 -259.834473) (xy 81.00776 -259.85803)
			(xy 80.938225 -259.8739) (xy 80.867351 -259.881886) (xy 80.796029 -259.881886) (xy 80.725155 -259.8739)
			(xy 80.65562 -259.85803) (xy 80.5883 -259.834473) (xy 80.524041 -259.803528) (xy 80.46365 -259.765582)
			(xy 80.407888 -259.721113) (xy 80.357455 -259.67068) (xy 80.312986 -259.614918) (xy 80.27504 -259.554527)
			(xy 80.244095 -259.490268) (xy 80.220538 -259.422948) (xy 80.204668 -259.353413) (xy 80.196682 -259.282539)
			(xy 78.662284 -259.282539) (xy 78.654298 -259.353413) (xy 78.638428 -259.422948) (xy 78.614871 -259.490268)
			(xy 78.583926 -259.554527) (xy 78.54598 -259.614918) (xy 78.501511 -259.67068) (xy 78.451078 -259.721113)
			(xy 78.395316 -259.765582) (xy 78.334925 -259.803528) (xy 78.270666 -259.834473) (xy 78.203346 -259.85803)
			(xy 78.133811 -259.8739) (xy 78.062937 -259.881886) (xy 77.991615 -259.881886) (xy 77.920741 -259.8739)
			(xy 77.851206 -259.85803) (xy 77.783886 -259.834473) (xy 77.719627 -259.803528) (xy 77.659236 -259.765582)
			(xy 77.603474 -259.721113) (xy 77.553041 -259.67068) (xy 77.508572 -259.614918) (xy 77.470626 -259.554527)
			(xy 77.439681 -259.490268) (xy 77.416124 -259.422948) (xy 77.400254 -259.353413) (xy 77.392268 -259.282539)
			(xy 42.846794 -259.282539) (xy 42.828346 -259.320847) (xy 42.7904 -259.381238) (xy 42.745931 -259.437)
			(xy 42.695498 -259.487433) (xy 42.639736 -259.531902) (xy 42.579345 -259.569848) (xy 42.515086 -259.600793)
			(xy 42.447766 -259.62435) (xy 42.378231 -259.64022) (xy 42.307357 -259.648206) (xy 42.236035 -259.648206)
			(xy 42.165161 -259.64022) (xy 42.095626 -259.62435) (xy 42.028306 -259.600793) (xy 41.964047 -259.569848)
			(xy 41.903656 -259.531902) (xy 41.847894 -259.487433) (xy 41.797461 -259.437) (xy 41.752992 -259.381238)
			(xy 41.715046 -259.320847) (xy 41.684101 -259.256588) (xy 41.660544 -259.189268) (xy 41.644674 -259.119733)
			(xy 41.636688 -259.048859) (xy 26.825803 -259.048859) (xy 26.966672 -259.189728) (xy 29.519372 -259.189728)
			(xy 31.399988 -259.189728) (xy 31.399988 -260.173486) (xy 34.599874 -260.173486) (xy 34.599874 -260.086586)
			(xy 34.607892 -260.000057) (xy 34.62386 -259.914637) (xy 34.647641 -259.831055) (xy 34.679033 -259.750023)
			(xy 34.717767 -259.672234) (xy 34.763514 -259.59835) (xy 34.815883 -259.529003) (xy 34.874427 -259.464783)
			(xy 34.938647 -259.406239) (xy 35.007994 -259.35387) (xy 35.081878 -259.308123) (xy 35.159667 -259.269389)
			(xy 35.240699 -259.237997) (xy 35.324281 -259.214216) (xy 35.409701 -259.198248) (xy 35.49623 -259.19023)
			(xy 35.53968 -259.189728) (xy 35.58313 -259.19023) (xy 35.669659 -259.198248) (xy 35.755079 -259.214216)
			(xy 35.838661 -259.237997) (xy 35.919693 -259.269389) (xy 35.997482 -259.308123) (xy 36.071366 -259.35387)
			(xy 36.140713 -259.406239) (xy 36.204933 -259.464783) (xy 36.263477 -259.529003) (xy 36.315846 -259.59835)
			(xy 36.361593 -259.672234) (xy 36.400327 -259.750023) (xy 36.431719 -259.831055) (xy 36.4555 -259.914637)
			(xy 36.471468 -260.000057) (xy 36.479486 -260.086586) (xy 36.479486 -260.173486) (xy 36.471468 -260.260015)
			(xy 36.4555 -260.345435) (xy 36.431719 -260.429017) (xy 36.400327 -260.510049) (xy 36.361593 -260.587838)
			(xy 36.315846 -260.661722) (xy 36.263477 -260.731069) (xy 36.204933 -260.795289) (xy 36.140713 -260.853833)
			(xy 36.071366 -260.906202) (xy 35.997482 -260.951949) (xy 35.919693 -260.990683) (xy 35.838661 -261.022075)
			(xy 35.755079 -261.045856) (xy 35.669659 -261.061824) (xy 35.58313 -261.069842) (xy 35.49623 -261.069842)
			(xy 35.409701 -261.061824) (xy 35.324281 -261.045856) (xy 35.240699 -261.022075) (xy 35.159667 -260.990683)
			(xy 35.081878 -260.951949) (xy 35.007994 -260.906202) (xy 34.938647 -260.853833) (xy 34.874427 -260.795289)
			(xy 34.815883 -260.731069) (xy 34.763514 -260.661722) (xy 34.717767 -260.587838) (xy 34.679033 -260.510049)
			(xy 34.647641 -260.429017) (xy 34.62386 -260.345435) (xy 34.607892 -260.260015) (xy 34.599874 -260.173486)
			(xy 31.399988 -260.173486) (xy 31.399988 -261.070344) (xy 29.519372 -261.070344) (xy 29.519372 -259.189728)
			(xy 26.966672 -259.189728) (xy 37.367464 -269.59052) (xy 37.367464 -273.509486) (xy 36.429188 -274.448016)
			(xy 36.412932 -274.519644) (xy 36.425378 -274.554188) (xy 36.439367 -274.594867) (xy 36.46073 -274.678203)
			(xy 36.474391 -274.763141) (xy 36.480235 -274.848972) (xy 36.478214 -274.934978) (xy 36.468345 -275.02044)
			(xy 36.45071 -275.104643) (xy 36.425457 -275.186883) (xy 36.392797 -275.266472) (xy 36.353003 -275.342745)
			(xy 36.306408 -275.415064) (xy 36.253401 -275.482824) (xy 36.194425 -275.545458) (xy 36.129975 -275.602443)
			(xy 36.060589 -275.653302) (xy 35.986846 -275.69761) (xy 35.909365 -275.734996) (xy 35.828792 -275.765148)
			(xy 35.745802 -275.787814) (xy 35.661088 -275.802803) (xy 35.575359 -275.809992) (xy 35.489332 -275.809318)
			(xy 35.403726 -275.800789) (xy 35.319257 -275.784476) (xy 35.236631 -275.760514) (xy 35.15654 -275.729105)
			(xy 35.079653 -275.69051) (xy 35.006614 -275.645053) (xy 34.938032 -275.593114) (xy 34.874481 -275.535128)
			(xy 34.816494 -275.471578) (xy 34.764554 -275.402997) (xy 34.719096 -275.329958) (xy 34.680501 -275.253071)
			(xy 34.64909 -275.172981) (xy 34.625127 -275.090356) (xy 34.608813 -275.005887) (xy 34.600282 -274.920281)
			(xy 34.599608 -274.834254) (xy 34.606795 -274.748525) (xy 34.621783 -274.663811) (xy 34.644448 -274.58082)
			(xy 34.674599 -274.500247) (xy 34.711984 -274.422765) (xy 34.756291 -274.349022) (xy 34.807149 -274.279635)
			(xy 34.864133 -274.215184) (xy 34.926767 -274.156208) (xy 34.994526 -274.1032) (xy 35.066844 -274.056604)
			(xy 35.143116 -274.016808) (xy 35.222705 -273.984147) (xy 35.304945 -273.958893) (xy 35.389147 -273.941257)
			(xy 35.474609 -273.931387) (xy 35.560615 -273.929365) (xy 35.646446 -273.935208) (xy 35.731385 -273.948868)
			(xy 35.81472 -273.970229) (xy 35.855402 -273.984212) (xy 35.872501 -273.989616) (xy 35.908283 -273.991715)
			(xy 35.943239 -273.983791) (xy 35.974619 -273.966468) (xy 35.987736 -273.95424) (xy 36.706556 -273.235674)
			(xy 36.706556 -273.100038) (xy 36.70607 -273.077874) (xy 36.698371 -273.034218) (xy 36.683219 -272.992559)
			(xy 36.661071 -272.954159) (xy 36.632599 -272.920182) (xy 36.598667 -272.891657) (xy 36.560302 -272.86945)
			(xy 36.518666 -272.854232) (xy 36.475023 -272.846465) (xy 36.430694 -272.846385) (xy 36.387023 -272.853994)
			(xy 36.345333 -272.869061) (xy 36.306888 -272.89113) (xy 36.272852 -272.919532) (xy 36.258246 -272.936208)
			(xy 36.229941 -272.968985) (xy 36.168237 -273.029759) (xy 36.101206 -273.084601) (xy 36.029414 -273.133045)
			(xy 35.953471 -273.174681) (xy 35.874021 -273.209156) (xy 35.791737 -273.236178) (xy 35.707316 -273.255517)
			(xy 35.621474 -273.26701) (xy 35.534939 -273.270559) (xy 35.448445 -273.266134) (xy 35.362724 -273.253773)
			(xy 35.278503 -273.23358) (xy 35.196497 -273.205727) (xy 35.117399 -273.17045) (xy 35.041882 -273.128047)
			(xy 34.970584 -273.078879) (xy 34.904111 -273.023361) (xy 34.843026 -272.961966) (xy 34.787846 -272.895212)
			(xy 34.73904 -272.823666) (xy 34.69702 -272.747934) (xy 34.662144 -272.668659) (xy 34.634707 -272.586513)
			(xy 34.614942 -272.502191) (xy 34.603015 -272.416408) (xy 34.599029 -272.329892) (xy 34.603017 -272.243377)
			(xy 34.614945 -272.157594) (xy 34.634711 -272.073273) (xy 34.66215 -271.991126) (xy 34.697027 -271.911852)
			(xy 34.739048 -271.836121) (xy 34.787855 -271.764576) (xy 34.843036 -271.697823) (xy 34.904122 -271.636428)
			(xy 34.970597 -271.580912) (xy 35.041895 -271.531745) (xy 35.117413 -271.489343) (xy 35.196511 -271.454067)
			(xy 35.278518 -271.426215) (xy 35.362739 -271.406024) (xy 35.44846 -271.393664) (xy 35.534955 -271.389241)
			(xy 35.62149 -271.392791) (xy 35.707331 -271.404286) (xy 35.791752 -271.423626) (xy 35.874035 -271.450649)
			(xy 35.953485 -271.485126) (xy 36.029427 -271.526763) (xy 36.101218 -271.575208) (xy 36.168249 -271.630051)
			(xy 36.229952 -271.690827) (xy 36.258246 -271.723612) (xy 36.272901 -271.740252) (xy 36.306922 -271.768682)
			(xy 36.34536 -271.790776) (xy 36.38705 -271.805866) (xy 36.430725 -271.813492) (xy 36.475061 -271.813423)
			(xy 36.518712 -271.805662) (xy 36.560355 -271.790443) (xy 36.598724 -271.76823) (xy 36.632657 -271.739695)
			(xy 36.661124 -271.705705) (xy 36.68326 -271.66729) (xy 36.698395 -271.625617) (xy 36.706068 -271.58195)
			(xy 36.706556 -271.559782) (xy 36.706556 -270.560038) (xy 36.70607 -270.537874) (xy 36.698371 -270.494218)
			(xy 36.683219 -270.452559) (xy 36.661071 -270.414159) (xy 36.632599 -270.380182) (xy 36.598667 -270.351657)
			(xy 36.560302 -270.32945) (xy 36.518666 -270.314232) (xy 36.475023 -270.306465) (xy 36.430694 -270.306385)
			(xy 36.387023 -270.313994) (xy 36.345333 -270.329061) (xy 36.306888 -270.35113) (xy 36.272852 -270.379532)
			(xy 36.258246 -270.396208) (xy 36.229736 -270.429223) (xy 36.167539 -270.490393) (xy 36.099942 -270.545539)
			(xy 36.027528 -270.594186) (xy 35.950919 -270.635915) (xy 35.870774 -270.670369) (xy 35.787782 -270.697251)
			(xy 35.702657 -270.71633) (xy 35.616131 -270.727441) (xy 35.528947 -270.73049) (xy 35.441856 -270.725449)
			(xy 35.355606 -270.712363) (xy 35.270939 -270.691343) (xy 35.188583 -270.662571) (xy 35.109247 -270.626294)
			(xy 35.033612 -270.582824) (xy 34.962329 -270.532535) (xy 34.89601 -270.475858) (xy 34.835227 -270.413283)
			(xy 34.780502 -270.345346) (xy 34.732305 -270.272631) (xy 34.691051 -270.195765) (xy 34.657095 -270.115408)
			(xy 34.630728 -270.032251) (xy 34.612178 -269.947009) (xy 34.601603 -269.860415) (xy 34.599095 -269.773214)
			(xy 34.604676 -269.686156) (xy 34.618297 -269.599989) (xy 34.639841 -269.515454) (xy 34.653982 -269.474188)
			(xy 34.666428 -269.439644) (xy 34.650172 -269.368016) (xy 24.596852 -259.314442) (xy 24.596852 -252.02007)
			(xy 24.57661 -251.998239) (xy 24.541357 -251.950263) (xy 24.512621 -251.898122) (xy 24.490884 -251.842697)
			(xy 24.476514 -251.784921) (xy 24.472646 -251.755402) (xy 24.467566 -251.711206) (xy 24.279352 -251.523246)
			(xy 24.279352 -237.044738) (xy 24.278855 -237.021703) (xy 24.270556 -236.976385) (xy 24.254223 -236.933307)
			(xy 24.230391 -236.893879) (xy 24.199841 -236.859394) (xy 24.163575 -236.830981) (xy 24.122781 -236.809572)
			(xy 24.078795 -236.795868) (xy 24.03306 -236.790319) (xy 23.987073 -236.793106) (xy 23.942343 -236.804139)
			(xy 23.900335 -236.823054) (xy 23.862425 -236.849233) (xy 23.845774 -236.86516) (xy 22.836632 -237.874556)
			(xy 22.836632 -258.045966) (xy 32.820356 -268.029944) (xy 32.820356 -277.38451) (xy 32.751506 -277.45336)
			(xy 34.599874 -277.45336) (xy 34.599874 -277.36646) (xy 34.607892 -277.279931) (xy 34.62386 -277.194511)
			(xy 34.647641 -277.110929) (xy 34.679033 -277.029897) (xy 34.717767 -276.952108) (xy 34.763514 -276.878224)
			(xy 34.815883 -276.808877) (xy 34.874427 -276.744657) (xy 34.938647 -276.686113) (xy 35.007994 -276.633744)
			(xy 35.081878 -276.587997) (xy 35.159667 -276.549263) (xy 35.240699 -276.517871) (xy 35.324281 -276.49409)
			(xy 35.409701 -276.478122) (xy 35.49623 -276.470104) (xy 35.53968 -276.469602) (xy 35.58313 -276.470104)
			(xy 35.669659 -276.478122) (xy 35.755079 -276.49409) (xy 35.838661 -276.517871) (xy 35.919693 -276.549263)
			(xy 35.997482 -276.587997) (xy 36.071366 -276.633744) (xy 36.140713 -276.686113) (xy 36.204933 -276.744657)
			(xy 36.263477 -276.808877) (xy 36.315846 -276.878224) (xy 36.361593 -276.952108) (xy 36.400327 -277.029897)
			(xy 36.431719 -277.110929) (xy 36.4555 -277.194511) (xy 36.471468 -277.279931) (xy 36.479486 -277.36646)
			(xy 36.479486 -277.45336) (xy 36.471468 -277.539889) (xy 36.4555 -277.625309) (xy 36.431719 -277.708891)
			(xy 36.400327 -277.789923) (xy 36.361593 -277.867712) (xy 36.315846 -277.941596) (xy 36.263477 -278.010943)
			(xy 36.204933 -278.075163) (xy 36.140713 -278.133707) (xy 36.071366 -278.186076) (xy 35.997482 -278.231823)
			(xy 35.919693 -278.270557) (xy 35.838661 -278.301949) (xy 35.755079 -278.32573) (xy 35.669659 -278.341698)
			(xy 35.58313 -278.349716) (xy 35.49623 -278.349716) (xy 35.409701 -278.341698) (xy 35.324281 -278.32573)
			(xy 35.240699 -278.301949) (xy 35.159667 -278.270557) (xy 35.081878 -278.231823) (xy 35.007994 -278.186076)
			(xy 34.938647 -278.133707) (xy 34.874427 -278.075163) (xy 34.815883 -278.010943) (xy 34.763514 -277.941596)
			(xy 34.717767 -277.867712) (xy 34.679033 -277.789923) (xy 34.647641 -277.708891) (xy 34.62386 -277.625309)
			(xy 34.607892 -277.539889) (xy 34.599874 -277.45336) (xy 32.751506 -277.45336) (xy 31.111952 -279.092914)
			(xy 31.100556 -279.105087) (xy 31.083899 -279.133958) (xy 31.075279 -279.166155) (xy 31.075285 -279.199487)
			(xy 31.083915 -279.231682) (xy 31.100582 -279.260547) (xy 31.111952 -279.272746) (xy 31.112714 -279.273254)
			(xy 31.114238 -279.274778) (xy 31.114492 -279.275032) (xy 31.14517 -279.305478) (xy 31.201425 -279.371104)
			(xy 31.25142 -279.441617) (xy 31.294731 -279.516421) (xy 31.330993 -279.594885) (xy 31.3599 -279.676346)
			(xy 31.381209 -279.760116) (xy 31.394739 -279.845488) (xy 31.400376 -279.931742) (xy 31.398072 -280.018149)
			(xy 31.387848 -280.10398) (xy 31.369788 -280.18851) (xy 31.344046 -280.271025) (xy 31.327852 -280.311098)
			(xy 31.31957 -280.332257) (xy 31.309811 -280.376629) (xy 31.308096 -280.42203) (xy 31.314479 -280.467012)
			(xy 31.328757 -280.510143) (xy 31.350476 -280.550048) (xy 31.378943 -280.585457) (xy 31.413251 -280.615241)
			(xy 31.452308 -280.638452) (xy 31.494869 -280.654349) (xy 31.539578 -280.662427) (xy 31.562294 -280.662888)
			(xy 34.359342 -280.662888) (xy 34.650172 -280.371804) (xy 34.666428 -280.300176) (xy 34.653982 -280.265632)
			(xy 34.639992 -280.22495) (xy 34.618628 -280.141611) (xy 34.604966 -280.056668) (xy 34.599121 -279.970832)
			(xy 34.601141 -279.884821) (xy 34.611011 -279.799355) (xy 34.628646 -279.715147) (xy 34.653901 -279.632903)
			(xy 34.686563 -279.553309) (xy 34.726359 -279.477032) (xy 34.772957 -279.40471) (xy 34.825967 -279.336946)
			(xy 34.884945 -279.274309) (xy 34.949399 -279.217321) (xy 35.01879 -279.166459) (xy 35.092536 -279.122149)
			(xy 35.170022 -279.084761) (xy 35.250599 -279.054608) (xy 35.333594 -279.031941) (xy 35.418313 -279.016952)
			(xy 35.504047 -279.009764) (xy 35.590078 -279.010438) (xy 35.675689 -279.018968) (xy 35.760162 -279.035283)
			(xy 35.842792 -279.059247) (xy 35.922887 -279.090659) (xy 35.999778 -279.129256) (xy 36.072821 -279.174717)
			(xy 36.141406 -279.226659) (xy 36.204959 -279.28465) (xy 36.262949 -279.348204) (xy 36.314891 -279.41679)
			(xy 36.36035 -279.489833) (xy 36.398946 -279.566725) (xy 36.430357 -279.64682) (xy 36.443414 -279.691842)
			(xy 39.383698 -279.691842) (xy 39.383698 -279.631906) (xy 39.391521 -279.572484) (xy 39.407034 -279.514591)
			(xy 39.42997 -279.459218) (xy 39.459937 -279.407312) (xy 39.496424 -279.359762) (xy 39.538804 -279.317382)
			(xy 39.586354 -279.280895) (xy 39.63826 -279.250928) (xy 39.693633 -279.227992) (xy 39.751526 -279.212479)
			(xy 39.810948 -279.204656) (xy 39.840916 -279.204166) (xy 39.870884 -279.204656) (xy 39.930306 -279.212479)
			(xy 39.988199 -279.227992) (xy 40.043572 -279.250928) (xy 40.095478 -279.280895) (xy 40.143028 -279.317382)
			(xy 40.185408 -279.359762) (xy 40.221895 -279.407312) (xy 40.251862 -279.459218) (xy 40.274798 -279.514591)
			(xy 40.290311 -279.572484) (xy 40.298134 -279.631906) (xy 40.298134 -279.691842) (xy 40.290311 -279.751264)
			(xy 40.274798 -279.809157) (xy 40.251862 -279.86453) (xy 40.221895 -279.916436) (xy 40.185408 -279.963986)
			(xy 40.143028 -280.006366) (xy 40.095478 -280.042853) (xy 40.043572 -280.07282) (xy 39.988199 -280.095756)
			(xy 39.930306 -280.111269) (xy 39.870884 -280.119092) (xy 39.810948 -280.119092) (xy 39.751526 -280.111269)
			(xy 39.693633 -280.095756) (xy 39.63826 -280.07282) (xy 39.586354 -280.042853) (xy 39.538804 -280.006366)
			(xy 39.496424 -279.963986) (xy 39.459937 -279.916436) (xy 39.42997 -279.86453) (xy 39.407034 -279.809157)
			(xy 39.391521 -279.751264) (xy 39.383698 -279.691842) (xy 36.443414 -279.691842) (xy 36.45432 -279.72945)
			(xy 36.470634 -279.813924) (xy 36.479163 -279.899534) (xy 36.479836 -279.985566) (xy 36.472647 -280.0713)
			(xy 36.457656 -280.156018) (xy 36.434988 -280.239013) (xy 36.404834 -280.31959) (xy 36.367445 -280.397075)
			(xy 36.323134 -280.470821) (xy 36.272271 -280.540211) (xy 36.215282 -280.604664) (xy 36.152644 -280.663642)
			(xy 36.08488 -280.71665) (xy 36.012557 -280.763247) (xy 35.936279 -280.803043) (xy 35.856685 -280.835704)
			(xy 35.77444 -280.860957) (xy 35.690232 -280.878591) (xy 35.604766 -280.888459) (xy 35.518755 -280.890479)
			(xy 35.432919 -280.884633) (xy 35.347977 -280.87097) (xy 35.264637 -280.849604) (xy 35.223958 -280.835608)
			(xy 35.206858 -280.830195) (xy 35.171068 -280.82808) (xy 35.136099 -280.835993) (xy 35.104707 -280.853311)
			(xy 35.091624 -280.86558) (xy 34.633154 -281.323796) (xy 31.230824 -281.323796) (xy 31.208677 -281.324282)
			(xy 31.165054 -281.331973) (xy 31.123425 -281.347108) (xy 31.085049 -281.36923) (xy 31.051088 -281.397668)
			(xy 31.022571 -281.431562) (xy 31.00036 -281.469886) (xy 30.985127 -281.51148) (xy 30.977335 -281.555084)
			(xy 30.977218 -281.599379) (xy 30.984781 -281.643024) (xy 30.999794 -281.684697) (xy 31.021802 -281.723138)
			(xy 31.050141 -281.757182) (xy 31.06674 -281.771852) (xy 31.099276 -281.799994) (xy 31.159622 -281.86131)
			(xy 31.214114 -281.927881) (xy 31.262297 -281.999153) (xy 31.303769 -282.074527) (xy 31.338182 -282.153375)
			(xy 31.365249 -282.235036) (xy 31.384744 -282.318829) (xy 31.396503 -282.404052) (xy 31.400427 -282.489993)
			(xy 31.398438 -282.53336) (xy 34.599874 -282.53336) (xy 34.599874 -282.44646) (xy 34.607892 -282.359931)
			(xy 34.62386 -282.274511) (xy 34.647641 -282.190929) (xy 34.679033 -282.109897) (xy 34.717767 -282.032108)
			(xy 34.763514 -281.958224) (xy 34.815883 -281.888877) (xy 34.874427 -281.824657) (xy 34.938647 -281.766113)
			(xy 35.007994 -281.713744) (xy 35.081878 -281.667997) (xy 35.159667 -281.629263) (xy 35.240699 -281.597871)
			(xy 35.324281 -281.57409) (xy 35.409701 -281.558122) (xy 35.49623 -281.550104) (xy 35.53968 -281.549602)
			(xy 35.58313 -281.550104) (xy 35.669659 -281.558122) (xy 35.755079 -281.57409) (xy 35.838661 -281.597871)
			(xy 35.919693 -281.629263) (xy 35.997482 -281.667997) (xy 36.071366 -281.713744) (xy 36.140713 -281.766113)
			(xy 36.204933 -281.824657) (xy 36.263477 -281.888877) (xy 36.315846 -281.958224) (xy 36.361593 -282.032108)
			(xy 36.400327 -282.109897) (xy 36.431719 -282.190929) (xy 36.4555 -282.274511) (xy 36.471468 -282.359931)
			(xy 36.479486 -282.44646) (xy 36.479486 -282.53336) (xy 36.471468 -282.619889) (xy 36.4555 -282.705309)
			(xy 36.431719 -282.788891) (xy 36.400327 -282.869923) (xy 36.361593 -282.947712) (xy 36.315846 -283.021596)
			(xy 36.263477 -283.090943) (xy 36.204933 -283.155163) (xy 36.140713 -283.213707) (xy 36.071366 -283.266076)
			(xy 35.997482 -283.311823) (xy 35.919693 -283.350557) (xy 35.838661 -283.381949) (xy 35.755079 -283.40573)
			(xy 35.669659 -283.421698) (xy 35.58313 -283.429716) (xy 35.49623 -283.429716) (xy 35.409701 -283.421698)
			(xy 35.324281 -283.40573) (xy 35.240699 -283.381949) (xy 35.159667 -283.350557) (xy 35.081878 -283.311823)
			(xy 35.007994 -283.266076) (xy 34.938647 -283.213707) (xy 34.874427 -283.155163) (xy 34.815883 -283.090943)
			(xy 34.763514 -283.021596) (xy 34.717767 -282.947712) (xy 34.679033 -282.869923) (xy 34.647641 -282.788891)
			(xy 34.62386 -282.705309) (xy 34.607892 -282.619889) (xy 34.599874 -282.53336) (xy 31.398438 -282.53336)
			(xy 31.396486 -282.575933) (xy 31.38471 -282.661154) (xy 31.365199 -282.744942) (xy 31.338116 -282.826599)
			(xy 31.303687 -282.90544) (xy 31.262201 -282.980806) (xy 31.214003 -283.052068) (xy 31.159497 -283.118629)
			(xy 31.09914 -283.179933) (xy 31.033435 -283.235467) (xy 30.962931 -283.284767) (xy 30.888219 -283.327421)
			(xy 30.809923 -283.363072) (xy 30.728698 -283.391422) (xy 30.645223 -283.412234) (xy 30.560196 -283.425334)
			(xy 30.474328 -283.430612) (xy 30.388336 -283.428025) (xy 30.302941 -283.417593) (xy 30.218855 -283.399404)
			(xy 30.136782 -283.373611) (xy 30.057409 -283.340428) (xy 29.981398 -283.300134) (xy 29.909386 -283.253065)
			(xy 29.841975 -283.199615) (xy 29.779727 -283.14023) (xy 29.723165 -283.075408) (xy 29.67276 -283.00569)
			(xy 29.628935 -282.931659) (xy 29.61005 -282.893008) (xy 29.601832 -282.87707) (xy 29.578097 -282.850213)
			(xy 29.547829 -282.831016) (xy 29.513416 -282.820995) (xy 29.495496 -282.820364) (xy 29.364686 -282.820364)
			(xy 28.977336 -283.207968) (xy 28.9659 -283.220055) (xy 28.949212 -283.248829) (xy 28.940543 -283.280942)
			(xy 28.940483 -283.314205) (xy 28.944316 -283.330396) (xy 28.950837 -283.356823) (xy 28.957194 -283.410881)
			(xy 28.955803 -283.465293) (xy 28.946692 -283.518956) (xy 28.930045 -283.570778) (xy 28.906201 -283.619708)
			(xy 28.875645 -283.664752) (xy 28.838996 -283.704995) (xy 28.796999 -283.73962) (xy 28.750506 -283.767924)
			(xy 28.700462 -283.789332) (xy 28.647884 -283.803409) (xy 28.593838 -283.80987) (xy 28.539423 -283.808583)
			(xy 28.485744 -283.799574) (xy 28.43389 -283.783027) (xy 28.384914 -283.759277) (xy 28.339812 -283.728806)
			(xy 28.299499 -283.692234) (xy 28.264793 -283.650303) (xy 28.236401 -283.603865) (xy 28.214897 -283.553862)
			(xy 28.200719 -283.501311) (xy 28.194155 -283.447277) (xy 28.194254 -283.420058) (xy 28.194231 -283.397592)
			(xy 28.187236 -283.353219) (xy 28.172552 -283.310766) (xy 28.150636 -283.271554) (xy 28.122169 -283.236803)
			(xy 28.088039 -283.207596) (xy 28.049308 -283.184842) (xy 28.00718 -283.169248) (xy 27.962968 -283.1613)
			(xy 27.940508 -283.160724) (xy 26.978102 -283.160724) (xy 25.31618 -281.498548) (xy 25.31618 -270.510508)
			(xy 21.109432 -266.30376) (xy 21.092791 -266.287794) (xy 21.054868 -266.261563) (xy 21.012834 -266.242603)
			(xy 20.96807 -266.231536) (xy 20.922044 -266.228724) (xy 20.876266 -266.234261) (xy 20.832238 -266.247965)
			(xy 20.791403 -266.269385) (xy 20.755103 -266.29782) (xy 20.724526 -266.332337) (xy 20.700678 -266.371802)
			(xy 20.684339 -266.414922) (xy 20.676046 -266.460282) (xy 20.6756 -266.483338) (xy 20.6756 -268.547342)
			(xy 20.676062 -268.56895) (xy 20.683426 -268.611535) (xy 20.697885 -268.652262) (xy 20.719021 -268.689958)
			(xy 20.746227 -268.723538) (xy 20.778718 -268.752034) (xy 20.81556 -268.774627) (xy 20.855691 -268.790665)
			(xy 20.897956 -268.799687) (xy 20.941138 -268.801433) (xy 20.96262 -268.799056) (xy 20.992379 -268.795669)
			(xy 21.052274 -268.795738) (xy 21.111649 -268.803618) (xy 21.169488 -268.819176) (xy 21.224804 -268.842144)
			(xy 21.276651 -268.872132) (xy 21.324145 -268.908625) (xy 21.366472 -268.951002) (xy 21.402911 -268.998537)
			(xy 21.432839 -269.050419) (xy 21.455744 -269.105762) (xy 21.471235 -269.163619) (xy 21.479047 -269.223002)
			(xy 21.479047 -269.282897) (xy 21.471235 -269.34228) (xy 21.455744 -269.400137) (xy 21.432839 -269.45548)
			(xy 21.402912 -269.507362) (xy 21.366473 -269.554897) (xy 21.324145 -269.597274) (xy 21.276652 -269.633768)
			(xy 21.224805 -269.663755) (xy 21.169489 -269.686724) (xy 21.11165 -269.702282) (xy 21.052275 -269.710162)
			(xy 20.99238 -269.710231) (xy 20.96262 -269.706852) (xy 20.941131 -269.704464) (xy 20.897931 -269.706164)
			(xy 20.855642 -269.715155) (xy 20.815487 -269.731176) (xy 20.778624 -269.753766) (xy 20.746119 -269.782271)
			(xy 20.71891 -269.815869) (xy 20.697782 -269.853588) (xy 20.683347 -269.894341) (xy 20.676021 -269.936949)
			(xy 20.6756 -269.958566) (xy 20.6756 -274.804882) (xy 24.100518 -274.804882) (xy 24.100518 -274.744946)
			(xy 24.108341 -274.685524) (xy 24.123854 -274.627631) (xy 24.14679 -274.572258) (xy 24.176757 -274.520352)
			(xy 24.213244 -274.472802) (xy 24.255624 -274.430422) (xy 24.303174 -274.393935) (xy 24.35508 -274.363968)
			(xy 24.410453 -274.341032) (xy 24.468346 -274.325519) (xy 24.527768 -274.317696) (xy 24.557736 -274.317206)
			(xy 24.587704 -274.317696) (xy 24.647126 -274.325519) (xy 24.705019 -274.341032) (xy 24.760392 -274.363968)
			(xy 24.812298 -274.393935) (xy 24.859848 -274.430422) (xy 24.902228 -274.472802) (xy 24.938715 -274.520352)
			(xy 24.968682 -274.572258) (xy 24.991618 -274.627631) (xy 25.007131 -274.685524) (xy 25.014954 -274.744946)
			(xy 25.014954 -274.804882) (xy 25.007131 -274.864304) (xy 24.991618 -274.922197) (xy 24.968682 -274.97757)
			(xy 24.938715 -275.029476) (xy 24.902228 -275.077026) (xy 24.859848 -275.119406) (xy 24.812298 -275.155893)
			(xy 24.760392 -275.18586) (xy 24.705019 -275.208796) (xy 24.647126 -275.224309) (xy 24.587704 -275.232132)
			(xy 24.527768 -275.232132) (xy 24.468346 -275.224309) (xy 24.410453 -275.208796) (xy 24.35508 -275.18586)
			(xy 24.303174 -275.155893) (xy 24.255624 -275.119406) (xy 24.213244 -275.077026) (xy 24.176757 -275.029476)
			(xy 24.14679 -274.97757) (xy 24.123854 -274.922197) (xy 24.108341 -274.864304) (xy 24.100518 -274.804882)
			(xy 20.6756 -274.804882) (xy 20.6756 -275.41093) (xy 24.200612 -278.935688) (xy 24.200612 -283.553154)
			(xy 24.7462 -284.098742) (xy 26.25139 -284.098742) (xy 26.25139 -284.038806) (xy 26.259213 -283.979384)
			(xy 26.274726 -283.921491) (xy 26.297662 -283.866118) (xy 26.327629 -283.814212) (xy 26.364116 -283.766662)
			(xy 26.406496 -283.724282) (xy 26.454046 -283.687795) (xy 26.505952 -283.657828) (xy 26.561325 -283.634892)
			(xy 26.619218 -283.619379) (xy 26.67864 -283.611556) (xy 26.708608 -283.611066) (xy 26.738576 -283.611556)
			(xy 26.797998 -283.619379) (xy 26.855891 -283.634892) (xy 26.911264 -283.657828) (xy 26.96317 -283.687795)
			(xy 27.01072 -283.724282) (xy 27.0531 -283.766662) (xy 27.089587 -283.814212) (xy 27.119554 -283.866118)
			(xy 27.14249 -283.921491) (xy 27.158003 -283.979384) (xy 27.165826 -284.038806) (xy 27.165826 -284.098742)
			(xy 27.158003 -284.158164) (xy 27.14249 -284.216057) (xy 27.119554 -284.27143) (xy 27.089587 -284.323336)
			(xy 27.0531 -284.370886) (xy 27.01072 -284.413266) (xy 26.96317 -284.449753) (xy 26.911264 -284.47972)
			(xy 26.855891 -284.502656) (xy 26.797998 -284.518169) (xy 26.738576 -284.525992) (xy 26.67864 -284.525992)
			(xy 26.619218 -284.518169) (xy 26.561325 -284.502656) (xy 26.505952 -284.47972) (xy 26.454046 -284.449753)
			(xy 26.406496 -284.413266) (xy 26.364116 -284.370886) (xy 26.327629 -284.323336) (xy 26.297662 -284.27143)
			(xy 26.274726 -284.216057) (xy 26.259213 -284.158164) (xy 26.25139 -284.098742) (xy 24.7462 -284.098742)
			(xy 25.720818 -285.07336) (xy 29.519874 -285.07336) (xy 29.519874 -284.98646) (xy 29.527892 -284.899931)
			(xy 29.54386 -284.814511) (xy 29.567641 -284.730929) (xy 29.599033 -284.649897) (xy 29.637767 -284.572108)
			(xy 29.683514 -284.498224) (xy 29.735883 -284.428877) (xy 29.794427 -284.364657) (xy 29.858647 -284.306113)
			(xy 29.927994 -284.253744) (xy 30.001878 -284.207997) (xy 30.079667 -284.169263) (xy 30.160699 -284.137871)
			(xy 30.244281 -284.11409) (xy 30.329701 -284.098122) (xy 30.41623 -284.090104) (xy 30.45968 -284.089602)
			(xy 30.50313 -284.090104) (xy 30.589659 -284.098122) (xy 30.675079 -284.11409) (xy 30.758661 -284.137871)
			(xy 30.839693 -284.169263) (xy 30.917482 -284.207997) (xy 30.991366 -284.253744) (xy 31.060713 -284.306113)
			(xy 31.124933 -284.364657) (xy 31.183477 -284.428877) (xy 31.235846 -284.498224) (xy 31.281593 -284.572108)
			(xy 31.320327 -284.649897) (xy 31.351719 -284.730929) (xy 31.3755 -284.814511) (xy 31.391468 -284.899931)
			(xy 31.399486 -284.98646) (xy 31.399486 -285.07336) (xy 34.599874 -285.07336) (xy 34.599874 -284.98646)
			(xy 34.607892 -284.899931) (xy 34.62386 -284.814511) (xy 34.647641 -284.730929) (xy 34.679033 -284.649897)
			(xy 34.717767 -284.572108) (xy 34.763514 -284.498224) (xy 34.815883 -284.428877) (xy 34.874427 -284.364657)
			(xy 34.938647 -284.306113) (xy 35.007994 -284.253744) (xy 35.081878 -284.207997) (xy 35.159667 -284.169263)
			(xy 35.240699 -284.137871) (xy 35.324281 -284.11409) (xy 35.409701 -284.098122) (xy 35.49623 -284.090104)
			(xy 35.53968 -284.089602) (xy 35.58313 -284.090104) (xy 35.669659 -284.098122) (xy 35.755079 -284.11409)
			(xy 35.838661 -284.137871) (xy 35.919693 -284.169263) (xy 35.997482 -284.207997) (xy 36.071366 -284.253744)
			(xy 36.140713 -284.306113) (xy 36.204933 -284.364657) (xy 36.263477 -284.428877) (xy 36.315846 -284.498224)
			(xy 36.361593 -284.572108) (xy 36.400327 -284.649897) (xy 36.431719 -284.730929) (xy 36.4555 -284.814511)
			(xy 36.471468 -284.899931) (xy 36.479486 -284.98646) (xy 36.479486 -285.07336) (xy 36.471468 -285.159889)
			(xy 36.4555 -285.245309) (xy 36.431719 -285.328891) (xy 36.400327 -285.409923) (xy 36.361593 -285.487712)
			(xy 36.315846 -285.561596) (xy 36.263477 -285.630943) (xy 36.204933 -285.695163) (xy 36.140713 -285.753707)
			(xy 36.071366 -285.806076) (xy 35.997482 -285.851823) (xy 35.919693 -285.890557) (xy 35.838661 -285.921949)
			(xy 35.755079 -285.94573) (xy 35.669659 -285.961698) (xy 35.58313 -285.969716) (xy 35.49623 -285.969716)
			(xy 35.409701 -285.961698) (xy 35.324281 -285.94573) (xy 35.240699 -285.921949) (xy 35.159667 -285.890557)
			(xy 35.081878 -285.851823) (xy 35.007994 -285.806076) (xy 34.938647 -285.753707) (xy 34.874427 -285.695163)
			(xy 34.815883 -285.630943) (xy 34.763514 -285.561596) (xy 34.717767 -285.487712) (xy 34.679033 -285.409923)
			(xy 34.647641 -285.328891) (xy 34.62386 -285.245309) (xy 34.607892 -285.159889) (xy 34.599874 -285.07336)
			(xy 31.399486 -285.07336) (xy 31.391468 -285.159889) (xy 31.3755 -285.245309) (xy 31.351719 -285.328891)
			(xy 31.320327 -285.409923) (xy 31.281593 -285.487712) (xy 31.235846 -285.561596) (xy 31.183477 -285.630943)
			(xy 31.124933 -285.695163) (xy 31.060713 -285.753707) (xy 30.991366 -285.806076) (xy 30.917482 -285.851823)
			(xy 30.839693 -285.890557) (xy 30.758661 -285.921949) (xy 30.675079 -285.94573) (xy 30.589659 -285.961698)
			(xy 30.50313 -285.969716) (xy 30.41623 -285.969716) (xy 30.329701 -285.961698) (xy 30.244281 -285.94573)
			(xy 30.160699 -285.921949) (xy 30.079667 -285.890557) (xy 30.001878 -285.851823) (xy 29.927994 -285.806076)
			(xy 29.858647 -285.753707) (xy 29.794427 -285.695163) (xy 29.735883 -285.630943) (xy 29.683514 -285.561596)
			(xy 29.637767 -285.487712) (xy 29.599033 -285.409923) (xy 29.567641 -285.328891) (xy 29.54386 -285.245309)
			(xy 29.527892 -285.159889) (xy 29.519874 -285.07336) (xy 25.720818 -285.07336) (xy 27.002994 -286.355536)
			(xy 27.803348 -286.355536) (xy 28.38323 -286.935418) (xy 29.766006 -286.935418) (xy 29.795564 -286.903837)
			(xy 29.859568 -286.845644) (xy 29.928648 -286.793577) (xy 30.002218 -286.748075) (xy 30.079658 -286.709525)
			(xy 30.160311 -286.678251) (xy 30.243496 -286.654519) (xy 30.32851 -286.638529) (xy 30.414633 -286.630416)
			(xy 30.501137 -286.630249) (xy 30.587291 -286.638029) (xy 30.672366 -286.65369) (xy 30.755642 -286.677101)
			(xy 30.836416 -286.708063) (xy 30.914003 -286.746314) (xy 30.987749 -286.791531) (xy 31.057029 -286.843331)
			(xy 31.121258 -286.901277) (xy 31.179892 -286.964877) (xy 31.232436 -287.033596) (xy 31.278444 -287.10685)
			(xy 31.317529 -287.184021) (xy 31.349359 -287.264457) (xy 31.373665 -287.347476) (xy 31.390243 -287.432377)
			(xy 31.398951 -287.518442) (xy 31.399715 -287.604943) (xy 31.392531 -287.691148) (xy 31.377457 -287.776329)
			(xy 31.354622 -287.859766) (xy 31.324219 -287.940751) (xy 31.305754 -287.979866) (xy 31.296011 -288.001129)
			(xy 31.283608 -288.04622) (xy 31.279663 -288.09282) (xy 31.28431 -288.139354) (xy 31.297392 -288.184253)
			(xy 31.318467 -288.226001) (xy 31.346825 -288.263188) (xy 31.381507 -288.294561) (xy 31.421343 -288.319058)
			(xy 31.464989 -288.335854) (xy 31.510971 -288.344382) (xy 31.534354 -288.344864) (xy 34.465006 -288.344864)
			(xy 34.488379 -288.344324) (xy 34.534334 -288.335762) (xy 34.57795 -288.318946) (xy 34.617759 -288.294441)
			(xy 34.652419 -288.263075) (xy 34.680763 -288.225902) (xy 34.701836 -288.184176) (xy 34.714929 -288.139301)
			(xy 34.7196 -288.092789) (xy 34.715692 -288.046207) (xy 34.703337 -288.001123) (xy 34.693606 -287.979866)
			(xy 34.675205 -287.940764) (xy 34.644817 -287.859857) (xy 34.621983 -287.776503) (xy 34.606895 -287.691405)
			(xy 34.599681 -287.605282) (xy 34.600402 -287.51886) (xy 34.609052 -287.432869) (xy 34.625557 -287.348034)
			(xy 34.649779 -287.265073) (xy 34.681513 -287.184685) (xy 34.720491 -287.107548) (xy 34.766384 -287.034315)
			(xy 34.818804 -286.965602) (xy 34.87731 -286.901991) (xy 34.941407 -286.844018) (xy 35.010554 -286.792173)
			(xy 35.084168 -286.746892) (xy 35.161627 -286.708559) (xy 35.242277 -286.677497) (xy 35.325438 -286.653968)
			(xy 35.410407 -286.638171) (xy 35.496467 -286.630239) (xy 35.582893 -286.630239) (xy 35.668953 -286.638171)
			(xy 35.753922 -286.653968) (xy 35.837083 -286.677497) (xy 35.917733 -286.708559) (xy 35.995192 -286.746892)
			(xy 36.022156 -286.763478) (xy 39.866061 -286.763478) (xy 39.872161 -286.708041) (xy 39.886267 -286.654084)
			(xy 39.908079 -286.602755) (xy 39.937133 -286.555149) (xy 39.972808 -286.512281) (xy 40.014345 -286.475064)
			(xy 40.060858 -286.444291) (xy 40.111355 -286.420619) (xy 40.164762 -286.404551) (xy 40.219938 -286.396431)
			(xy 40.247824 -286.395922) (xy 40.27571 -286.396431) (xy 40.330886 -286.404551) (xy 40.384293 -286.420619)
			(xy 40.43479 -286.444291) (xy 40.481303 -286.475064) (xy 40.52284 -286.512281) (xy 40.558515 -286.555149)
			(xy 40.587569 -286.602755) (xy 40.609381 -286.654084) (xy 40.623487 -286.708041) (xy 40.629587 -286.763478)
			(xy 40.62755 -286.819212) (xy 40.61742 -286.874055) (xy 40.599413 -286.926839) (xy 40.573912 -286.976439)
			(xy 40.541461 -287.021797) (xy 40.502752 -287.061946) (xy 40.458609 -287.096032) (xy 40.409974 -287.123328)
			(xy 40.357883 -287.143251) (xy 40.303446 -287.155377) (xy 40.247824 -287.159448) (xy 40.192202 -287.155377)
			(xy 40.137765 -287.143251) (xy 40.085674 -287.123328) (xy 40.037039 -287.096032) (xy 39.992896 -287.061946)
			(xy 39.954187 -287.021797) (xy 39.921736 -286.976439) (xy 39.896235 -286.926839) (xy 39.878228 -286.874055)
			(xy 39.868098 -286.819212) (xy 39.866061 -286.763478) (xy 36.022156 -286.763478) (xy 36.068806 -286.792173)
			(xy 36.137953 -286.844018) (xy 36.20205 -286.901991) (xy 36.260556 -286.965602) (xy 36.312976 -287.034315)
			(xy 36.358869 -287.107548) (xy 36.397847 -287.184685) (xy 36.429581 -287.265073) (xy 36.453803 -287.348034)
			(xy 36.470308 -287.432869) (xy 36.478958 -287.51886) (xy 36.479679 -287.605282) (xy 36.472465 -287.691405)
			(xy 36.457377 -287.776503) (xy 36.434543 -287.859857) (xy 36.404155 -287.940764) (xy 36.385754 -287.979866)
			(xy 36.376011 -288.001129) (xy 36.363608 -288.04622) (xy 36.359663 -288.09282) (xy 36.36431 -288.139354)
			(xy 36.377392 -288.184253) (xy 36.398467 -288.226001) (xy 36.426825 -288.263188) (xy 36.461507 -288.294561)
			(xy 36.501343 -288.319058) (xy 36.544989 -288.335854) (xy 36.590971 -288.344382) (xy 36.614354 -288.344864)
			(xy 40.037512 -288.344864) (xy 40.141398 -288.240724) (xy 40.164471 -288.218394) (xy 40.215486 -288.179404)
			(xy 40.271217 -288.147517) (xy 40.330682 -288.123293) (xy 40.392831 -288.10716) (xy 40.456569 -288.099402)
			(xy 40.520774 -288.100157) (xy 40.584313 -288.109411) (xy 40.646065 -288.127) (xy 40.704944 -288.152615)
			(xy 40.75991 -288.185804) (xy 40.809995 -288.225982) (xy 40.832532 -288.248852) (xy 40.84842 -288.264794)
			(xy 40.884745 -288.291365) (xy 40.92518 -288.311124) (xy 40.968463 -288.323454) (xy 41.013241 -288.32797)
			(xy 41.058114 -288.324531) (xy 41.101681 -288.313244) (xy 41.14258 -288.294463) (xy 41.179532 -288.268773)
			(xy 41.195752 -288.25317) (xy 42.518584 -286.930084) (xy 42.518584 -281.319224) (xy 37.796216 -276.596856)
			(xy 37.796216 -262.746998) (xy 40.320722 -260.222492) (xy 43.867324 -260.222492) (xy 44.336208 -259.753608)
			(xy 44.358941 -259.731606) (xy 44.409133 -259.693093) (xy 44.463922 -259.66146) (xy 44.522372 -259.637249)
			(xy 44.583481 -259.620875) (xy 44.646205 -259.612617) (xy 44.709471 -259.612617) (xy 44.772195 -259.620875)
			(xy 44.833304 -259.637249) (xy 44.891754 -259.66146) (xy 44.946543 -259.693093) (xy 44.996735 -259.731606)
			(xy 45.04147 -259.776341) (xy 45.079983 -259.826533) (xy 45.111616 -259.881322) (xy 45.135827 -259.939772)
			(xy 45.152201 -260.000881) (xy 45.160459 -260.063605) (xy 45.160459 -260.126871) (xy 45.152201 -260.189595)
			(xy 45.135827 -260.250704) (xy 45.111616 -260.309154) (xy 45.079983 -260.363943) (xy 45.04147 -260.414135)
			(xy 45.019468 -260.436868) (xy 44.541903 -260.914235) (xy 77.375758 -260.914235) (xy 77.375758 -260.842913)
			(xy 77.383744 -260.772039) (xy 77.399614 -260.702504) (xy 77.423171 -260.635184) (xy 77.454116 -260.570925)
			(xy 77.492062 -260.510534) (xy 77.536531 -260.454772) (xy 77.586964 -260.404339) (xy 77.642726 -260.35987)
			(xy 77.703117 -260.321924) (xy 77.767376 -260.290979) (xy 77.834696 -260.267422) (xy 77.904231 -260.251552)
			(xy 77.975105 -260.243566) (xy 78.010766 -260.243066) (xy 78.046427 -260.243566) (xy 78.117301 -260.251552)
			(xy 78.186836 -260.267422) (xy 78.254156 -260.290979) (xy 78.318415 -260.321924) (xy 78.378806 -260.35987)
			(xy 78.434568 -260.404339) (xy 78.485001 -260.454772) (xy 78.52947 -260.510534) (xy 78.567416 -260.570925)
			(xy 78.598361 -260.635184) (xy 78.621918 -260.702504) (xy 78.637788 -260.772039) (xy 78.645774 -260.842913)
			(xy 78.645774 -260.914235) (xy 80.180172 -260.914235) (xy 80.180172 -260.842913) (xy 80.188158 -260.772039)
			(xy 80.204028 -260.702504) (xy 80.227585 -260.635184) (xy 80.25853 -260.570925) (xy 80.296476 -260.510534)
			(xy 80.340945 -260.454772) (xy 80.391378 -260.404339) (xy 80.44714 -260.35987) (xy 80.507531 -260.321924)
			(xy 80.57179 -260.290979) (xy 80.63911 -260.267422) (xy 80.708645 -260.251552) (xy 80.779519 -260.243566)
			(xy 80.81518 -260.243066) (xy 80.850841 -260.243566) (xy 80.921715 -260.251552) (xy 80.99125 -260.267422)
			(xy 81.05857 -260.290979) (xy 81.122829 -260.321924) (xy 81.18322 -260.35987) (xy 81.238982 -260.404339)
			(xy 81.289415 -260.454772) (xy 81.333884 -260.510534) (xy 81.37183 -260.570925) (xy 81.402775 -260.635184)
			(xy 81.426332 -260.702504) (xy 81.442202 -260.772039) (xy 81.450188 -260.842913) (xy 81.450188 -260.914235)
			(xy 81.442202 -260.985109) (xy 81.426332 -261.054644) (xy 81.402775 -261.121964) (xy 81.37183 -261.186223)
			(xy 81.333884 -261.246614) (xy 81.289415 -261.302376) (xy 81.238982 -261.352809) (xy 81.18322 -261.397278)
			(xy 81.122829 -261.435224) (xy 81.05857 -261.466169) (xy 80.99125 -261.489726) (xy 80.921715 -261.505596)
			(xy 80.850841 -261.513582) (xy 80.779519 -261.513582) (xy 80.708645 -261.505596) (xy 80.63911 -261.489726)
			(xy 80.57179 -261.466169) (xy 80.507531 -261.435224) (xy 80.44714 -261.397278) (xy 80.391378 -261.352809)
			(xy 80.340945 -261.302376) (xy 80.296476 -261.246614) (xy 80.25853 -261.186223) (xy 80.227585 -261.121964)
			(xy 80.204028 -261.054644) (xy 80.188158 -260.985109) (xy 80.180172 -260.914235) (xy 78.645774 -260.914235)
			(xy 78.637788 -260.985109) (xy 78.621918 -261.054644) (xy 78.598361 -261.121964) (xy 78.567416 -261.186223)
			(xy 78.52947 -261.246614) (xy 78.485001 -261.302376) (xy 78.434568 -261.352809) (xy 78.378806 -261.397278)
			(xy 78.318415 -261.435224) (xy 78.254156 -261.466169) (xy 78.186836 -261.489726) (xy 78.117301 -261.505596)
			(xy 78.046427 -261.513582) (xy 77.975105 -261.513582) (xy 77.904231 -261.505596) (xy 77.834696 -261.489726)
			(xy 77.767376 -261.466169) (xy 77.703117 -261.435224) (xy 77.642726 -261.397278) (xy 77.586964 -261.352809)
			(xy 77.536531 -261.302376) (xy 77.492062 -261.246614) (xy 77.454116 -261.186223) (xy 77.423171 -261.121964)
			(xy 77.399614 -261.054644) (xy 77.383744 -260.985109) (xy 77.375758 -260.914235) (xy 44.541903 -260.914235)
			(xy 44.407074 -261.049008) (xy 44.395614 -261.061139) (xy 44.378906 -261.090015) (xy 44.370258 -261.122236)
			(xy 44.370263 -261.155598) (xy 44.378919 -261.187816) (xy 44.395635 -261.216688) (xy 44.407074 -261.22884)
			(xy 44.61851 -261.440168) (xy 52.335176 -261.440168) (xy 53.987192 -261.440168) (xy 53.987192 -262.600033)
			(xy 77.342738 -262.600033) (xy 77.342738 -262.528711) (xy 77.350724 -262.457837) (xy 77.366594 -262.388302)
			(xy 77.390151 -262.320982) (xy 77.421096 -262.256723) (xy 77.459042 -262.196332) (xy 77.503511 -262.14057)
			(xy 77.553944 -262.090137) (xy 77.609706 -262.045668) (xy 77.670097 -262.007722) (xy 77.734356 -261.976777)
			(xy 77.801676 -261.95322) (xy 77.871211 -261.93735) (xy 77.942085 -261.929364) (xy 77.977746 -261.928864)
			(xy 78.013407 -261.929364) (xy 78.084281 -261.93735) (xy 78.153816 -261.95322) (xy 78.221136 -261.976777)
			(xy 78.285395 -262.007722) (xy 78.345786 -262.045668) (xy 78.401548 -262.090137) (xy 78.451981 -262.14057)
			(xy 78.49645 -262.196332) (xy 78.534396 -262.256723) (xy 78.565341 -262.320982) (xy 78.588898 -262.388302)
			(xy 78.604768 -262.457837) (xy 78.612754 -262.528711) (xy 78.612754 -262.600033) (xy 80.147152 -262.600033)
			(xy 80.147152 -262.528711) (xy 80.155138 -262.457837) (xy 80.171008 -262.388302) (xy 80.194565 -262.320982)
			(xy 80.22551 -262.256723) (xy 80.263456 -262.196332) (xy 80.307925 -262.14057) (xy 80.358358 -262.090137)
			(xy 80.41412 -262.045668) (xy 80.474511 -262.007722) (xy 80.53877 -261.976777) (xy 80.60609 -261.95322)
			(xy 80.675625 -261.93735) (xy 80.746499 -261.929364) (xy 80.78216 -261.928864) (xy 80.817821 -261.929364)
			(xy 80.888695 -261.93735) (xy 80.95823 -261.95322) (xy 81.02555 -261.976777) (xy 81.089809 -262.007722)
			(xy 81.1502 -262.045668) (xy 81.205962 -262.090137) (xy 81.256395 -262.14057) (xy 81.300864 -262.196332)
			(xy 81.33881 -262.256723) (xy 81.369755 -262.320982) (xy 81.393312 -262.388302) (xy 81.409182 -262.457837)
			(xy 81.417168 -262.528711) (xy 81.417168 -262.600033) (xy 81.409182 -262.670907) (xy 81.393312 -262.740442)
			(xy 81.369755 -262.807762) (xy 81.33881 -262.872021) (xy 81.300864 -262.932412) (xy 81.256395 -262.988174)
			(xy 81.205962 -263.038607) (xy 81.1502 -263.083076) (xy 81.089809 -263.121022) (xy 81.02555 -263.151967)
			(xy 80.95823 -263.175524) (xy 80.888695 -263.191394) (xy 80.817821 -263.19938) (xy 80.746499 -263.19938)
			(xy 80.675625 -263.191394) (xy 80.60609 -263.175524) (xy 80.53877 -263.151967) (xy 80.474511 -263.121022)
			(xy 80.41412 -263.083076) (xy 80.358358 -263.038607) (xy 80.307925 -262.988174) (xy 80.263456 -262.932412)
			(xy 80.22551 -262.872021) (xy 80.194565 -262.807762) (xy 80.171008 -262.740442) (xy 80.155138 -262.670907)
			(xy 80.147152 -262.600033) (xy 78.612754 -262.600033) (xy 78.604768 -262.670907) (xy 78.588898 -262.740442)
			(xy 78.565341 -262.807762) (xy 78.534396 -262.872021) (xy 78.49645 -262.932412) (xy 78.451981 -262.988174)
			(xy 78.401548 -263.038607) (xy 78.345786 -263.083076) (xy 78.285395 -263.121022) (xy 78.221136 -263.151967)
			(xy 78.153816 -263.175524) (xy 78.084281 -263.191394) (xy 78.013407 -263.19938) (xy 77.942085 -263.19938)
			(xy 77.871211 -263.191394) (xy 77.801676 -263.175524) (xy 77.734356 -263.151967) (xy 77.670097 -263.121022)
			(xy 77.609706 -263.083076) (xy 77.553944 -263.038607) (xy 77.503511 -262.988174) (xy 77.459042 -262.932412)
			(xy 77.421096 -262.872021) (xy 77.390151 -262.807762) (xy 77.366594 -262.740442) (xy 77.350724 -262.670907)
			(xy 77.342738 -262.600033) (xy 53.987192 -262.600033) (xy 53.987192 -263.092184) (xy 52.335176 -263.092184)
			(xy 52.335176 -261.440168) (xy 44.61851 -261.440168) (xy 44.905422 -261.726934) (xy 44.927424 -261.749667)
			(xy 44.965937 -261.799859) (xy 44.99757 -261.854648) (xy 45.021781 -261.913098) (xy 45.038155 -261.974207)
			(xy 45.046413 -262.036931) (xy 45.046413 -262.100197) (xy 45.038155 -262.162921) (xy 45.021781 -262.22403)
			(xy 44.99757 -262.28248) (xy 44.965937 -262.337269) (xy 44.927424 -262.387461) (xy 44.882689 -262.432196)
			(xy 44.832497 -262.470709) (xy 44.777708 -262.502342) (xy 44.719258 -262.526553) (xy 44.658149 -262.542927)
			(xy 44.595425 -262.551185) (xy 44.532159 -262.551185) (xy 44.469435 -262.542927) (xy 44.408326 -262.526553)
			(xy 44.349876 -262.502342) (xy 44.295087 -262.470709) (xy 44.244895 -262.432196) (xy 44.222162 -262.410194)
			(xy 43.775884 -261.963916) (xy 41.042336 -261.963916) (xy 39.53764 -263.468612) (xy 39.53764 -266.451584)
			(xy 84.80474 -266.451584) (xy 84.80474 -266.391648) (xy 84.812563 -266.332226) (xy 84.828076 -266.274333)
			(xy 84.851012 -266.21896) (xy 84.880979 -266.167054) (xy 84.917466 -266.119504) (xy 84.959846 -266.077124)
			(xy 85.007396 -266.040637) (xy 85.059302 -266.01067) (xy 85.114675 -265.987734) (xy 85.172568 -265.972221)
			(xy 85.23199 -265.964398) (xy 85.261958 -265.963908) (xy 85.291926 -265.964398) (xy 85.351348 -265.972221)
			(xy 85.409241 -265.987734) (xy 85.464614 -266.01067) (xy 85.51652 -266.040637) (xy 85.56407 -266.077124)
			(xy 85.60645 -266.119504) (xy 85.642937 -266.167054) (xy 85.651764 -266.182344) (xy 87.319594 -266.182344)
			(xy 87.319594 -266.122408) (xy 87.327417 -266.062986) (xy 87.34293 -266.005093) (xy 87.365866 -265.94972)
			(xy 87.395833 -265.897814) (xy 87.43232 -265.850264) (xy 87.4747 -265.807884) (xy 87.52225 -265.771397)
			(xy 87.574156 -265.74143) (xy 87.629529 -265.718494) (xy 87.687422 -265.702981) (xy 87.746844 -265.695158)
			(xy 87.776812 -265.694668) (xy 87.80678 -265.695158) (xy 87.866202 -265.702981) (xy 87.924095 -265.718494)
			(xy 87.979468 -265.74143) (xy 88.031374 -265.771397) (xy 88.078924 -265.807884) (xy 88.121304 -265.850264)
			(xy 88.157791 -265.897814) (xy 88.187758 -265.94972) (xy 88.210694 -266.005093) (xy 88.226207 -266.062986)
			(xy 88.23403 -266.122408) (xy 88.23403 -266.182344) (xy 88.226207 -266.241766) (xy 88.210694 -266.299659)
			(xy 88.187758 -266.355032) (xy 88.157791 -266.406938) (xy 88.121304 -266.454488) (xy 88.078924 -266.496868)
			(xy 88.031374 -266.533355) (xy 87.979468 -266.563322) (xy 87.924095 -266.586258) (xy 87.866202 -266.601771)
			(xy 87.80678 -266.609594) (xy 87.746844 -266.609594) (xy 87.687422 -266.601771) (xy 87.629529 -266.586258)
			(xy 87.574156 -266.563322) (xy 87.52225 -266.533355) (xy 87.4747 -266.496868) (xy 87.43232 -266.454488)
			(xy 87.395833 -266.406938) (xy 87.365866 -266.355032) (xy 87.34293 -266.299659) (xy 87.327417 -266.241766)
			(xy 87.319594 -266.182344) (xy 85.651764 -266.182344) (xy 85.672904 -266.21896) (xy 85.69584 -266.274333)
			(xy 85.711353 -266.332226) (xy 85.719176 -266.391648) (xy 85.719176 -266.451584) (xy 85.711353 -266.511006)
			(xy 85.69584 -266.568899) (xy 85.672904 -266.624272) (xy 85.642937 -266.676178) (xy 85.60645 -266.723728)
			(xy 85.56407 -266.766108) (xy 85.51652 -266.802595) (xy 85.464614 -266.832562) (xy 85.409241 -266.855498)
			(xy 85.351348 -266.871011) (xy 85.291926 -266.878834) (xy 85.23199 -266.878834) (xy 85.172568 -266.871011)
			(xy 85.114675 -266.855498) (xy 85.059302 -266.832562) (xy 85.007396 -266.802595) (xy 84.959846 -266.766108)
			(xy 84.917466 -266.723728) (xy 84.880979 -266.676178) (xy 84.851012 -266.624272) (xy 84.828076 -266.568899)
			(xy 84.812563 -266.511006) (xy 84.80474 -266.451584) (xy 39.53764 -266.451584) (xy 39.53764 -267.558516)
			(xy 78.200994 -267.558516) (xy 78.200994 -267.49858) (xy 78.208817 -267.439158) (xy 78.22433 -267.381265)
			(xy 78.247266 -267.325892) (xy 78.277233 -267.273986) (xy 78.31372 -267.226436) (xy 78.3561 -267.184056)
			(xy 78.40365 -267.147569) (xy 78.455556 -267.117602) (xy 78.510929 -267.094666) (xy 78.568822 -267.079153)
			(xy 78.628244 -267.07133) (xy 78.658212 -267.07084) (xy 78.68818 -267.07133) (xy 78.747602 -267.079153)
			(xy 78.805495 -267.094666) (xy 78.860868 -267.117602) (xy 78.912774 -267.147569) (xy 78.960324 -267.184056)
			(xy 79.002704 -267.226436) (xy 79.039191 -267.273986) (xy 79.069158 -267.325892) (xy 79.092094 -267.381265)
			(xy 79.107607 -267.439158) (xy 79.11543 -267.49858) (xy 79.11543 -267.504668) (xy 80.21115 -267.504668)
			(xy 80.21115 -267.444732) (xy 80.218973 -267.38531) (xy 80.234486 -267.327417) (xy 80.257422 -267.272044)
			(xy 80.287389 -267.220138) (xy 80.323876 -267.172588) (xy 80.366256 -267.130208) (xy 80.413806 -267.093721)
			(xy 80.465712 -267.063754) (xy 80.521085 -267.040818) (xy 80.578978 -267.025305) (xy 80.6384 -267.017482)
			(xy 80.668368 -267.016992) (xy 80.698336 -267.017482) (xy 80.757758 -267.025305) (xy 80.815651 -267.040818)
			(xy 80.871024 -267.063754) (xy 80.92293 -267.093721) (xy 80.97048 -267.130208) (xy 81.01286 -267.172588)
			(xy 81.021319 -267.183612) (xy 81.901266 -267.183612) (xy 81.901266 -267.123676) (xy 81.909089 -267.064254)
			(xy 81.924602 -267.006361) (xy 81.947538 -266.950988) (xy 81.977505 -266.899082) (xy 82.013992 -266.851532)
			(xy 82.056372 -266.809152) (xy 82.103922 -266.772665) (xy 82.155828 -266.742698) (xy 82.211201 -266.719762)
			(xy 82.269094 -266.704249) (xy 82.328516 -266.696426) (xy 82.358484 -266.695936) (xy 82.388452 -266.696426)
			(xy 82.447874 -266.704249) (xy 82.505767 -266.719762) (xy 82.56114 -266.742698) (xy 82.613046 -266.772665)
			(xy 82.660596 -266.809152) (xy 82.702976 -266.851532) (xy 82.739463 -266.899082) (xy 82.76943 -266.950988)
			(xy 82.792366 -267.006361) (xy 82.807879 -267.064254) (xy 82.815702 -267.123676) (xy 82.815702 -267.183612)
			(xy 82.807879 -267.243034) (xy 82.792366 -267.300927) (xy 82.76943 -267.3563) (xy 82.739463 -267.408206)
			(xy 82.702976 -267.455756) (xy 82.660596 -267.498136) (xy 82.613046 -267.534623) (xy 82.56114 -267.56459)
			(xy 82.505767 -267.587526) (xy 82.447874 -267.603039) (xy 82.388452 -267.610862) (xy 82.328516 -267.610862)
			(xy 82.269094 -267.603039) (xy 82.211201 -267.587526) (xy 82.155828 -267.56459) (xy 82.103922 -267.534623)
			(xy 82.056372 -267.498136) (xy 82.013992 -267.455756) (xy 81.977505 -267.408206) (xy 81.947538 -267.3563)
			(xy 81.924602 -267.300927) (xy 81.909089 -267.243034) (xy 81.901266 -267.183612) (xy 81.021319 -267.183612)
			(xy 81.049347 -267.220138) (xy 81.079314 -267.272044) (xy 81.10225 -267.327417) (xy 81.117763 -267.38531)
			(xy 81.125586 -267.444732) (xy 81.125586 -267.504668) (xy 81.117763 -267.56409) (xy 81.10225 -267.621983)
			(xy 81.079314 -267.677356) (xy 81.049347 -267.729262) (xy 81.01286 -267.776812) (xy 80.97048 -267.819192)
			(xy 80.92293 -267.855679) (xy 80.871024 -267.885646) (xy 80.815651 -267.908582) (xy 80.757758 -267.924095)
			(xy 80.698336 -267.931918) (xy 80.6384 -267.931918) (xy 80.578978 -267.924095) (xy 80.521085 -267.908582)
			(xy 80.465712 -267.885646) (xy 80.413806 -267.855679) (xy 80.366256 -267.819192) (xy 80.323876 -267.776812)
			(xy 80.287389 -267.729262) (xy 80.257422 -267.677356) (xy 80.234486 -267.621983) (xy 80.218973 -267.56409)
			(xy 80.21115 -267.504668) (xy 79.11543 -267.504668) (xy 79.11543 -267.558516) (xy 79.107607 -267.617938)
			(xy 79.092094 -267.675831) (xy 79.069158 -267.731204) (xy 79.039191 -267.78311) (xy 79.002704 -267.83066)
			(xy 78.960324 -267.87304) (xy 78.912774 -267.909527) (xy 78.860868 -267.939494) (xy 78.805495 -267.96243)
			(xy 78.747602 -267.977943) (xy 78.68818 -267.985766) (xy 78.628244 -267.985766) (xy 78.568822 -267.977943)
			(xy 78.510929 -267.96243) (xy 78.455556 -267.939494) (xy 78.40365 -267.909527) (xy 78.3561 -267.87304)
			(xy 78.31372 -267.83066) (xy 78.277233 -267.78311) (xy 78.247266 -267.731204) (xy 78.22433 -267.675831)
			(xy 78.208817 -267.617938) (xy 78.200994 -267.558516) (xy 39.53764 -267.558516) (xy 39.53764 -273.581047)
			(xy 39.818567 -273.581047) (xy 39.824576 -273.465126) (xy 39.838567 -273.349897) (xy 39.860475 -273.235907)
			(xy 39.890195 -273.1237) (xy 39.927585 -273.013811) (xy 39.972468 -272.906764) (xy 40.024629 -272.803068)
			(xy 40.08382 -272.703218) (xy 40.149759 -272.607689) (xy 40.222131 -272.516938) (xy 40.300592 -272.431395)
			(xy 40.384767 -272.351469) (xy 40.474256 -272.277542) (xy 40.568632 -272.209964) (xy 40.667446 -272.149058)
			(xy 40.770226 -272.095115) (xy 40.876483 -272.048391) (xy 40.98571 -272.00911) (xy 41.097387 -271.977458)
			(xy 41.210982 -271.953585) (xy 41.325953 -271.937607) (xy 41.441752 -271.929599) (xy 41.49979 -271.929098)
			(xy 41.557828 -271.929599) (xy 41.673627 -271.937607) (xy 41.788598 -271.953585) (xy 41.902193 -271.977458)
			(xy 42.01387 -272.00911) (xy 42.123097 -272.048391) (xy 42.229354 -272.095115) (xy 42.332134 -272.149058)
			(xy 42.430948 -272.209964) (xy 42.474432 -272.241101) (xy 63.647829 -272.241101) (xy 63.653878 -272.165531)
			(xy 63.667925 -272.091033) (xy 63.689811 -272.01845) (xy 63.719288 -271.948604) (xy 63.756023 -271.882287)
			(xy 63.799598 -271.820251) (xy 63.84952 -271.763198) (xy 63.905224 -271.711774) (xy 63.966079 -271.666563)
			(xy 64.031394 -271.628076) (xy 64.10043 -271.59675) (xy 64.172405 -271.57294) (xy 64.246503 -271.556915)
			(xy 64.321884 -271.548856) (xy 64.35979 -271.548352) (xy 64.397696 -271.548856) (xy 64.473077 -271.556915)
			(xy 64.547175 -271.57294) (xy 64.61915 -271.59675) (xy 64.688186 -271.628076) (xy 64.753501 -271.666563)
			(xy 64.814356 -271.711774) (xy 64.87006 -271.763198) (xy 64.919982 -271.820251) (xy 64.963557 -271.882287)
			(xy 65.000292 -271.948604) (xy 65.029769 -272.01845) (xy 65.051655 -272.091033) (xy 65.065702 -272.165531)
			(xy 65.071751 -272.241101) (xy 66.187829 -272.241101) (xy 66.193878 -272.165531) (xy 66.207925 -272.091033)
			(xy 66.229811 -272.01845) (xy 66.259288 -271.948604) (xy 66.296023 -271.882287) (xy 66.339598 -271.820251)
			(xy 66.38952 -271.763198) (xy 66.445224 -271.711774) (xy 66.506079 -271.666563) (xy 66.571394 -271.628076)
			(xy 66.64043 -271.59675) (xy 66.712405 -271.57294) (xy 66.786503 -271.556915) (xy 66.861884 -271.548856)
			(xy 66.89979 -271.548352) (xy 66.937696 -271.548856) (xy 67.013077 -271.556915) (xy 67.087175 -271.57294)
			(xy 67.15915 -271.59675) (xy 67.228186 -271.628076) (xy 67.293501 -271.666563) (xy 67.354356 -271.711774)
			(xy 67.41006 -271.763198) (xy 67.459982 -271.820251) (xy 67.503557 -271.882287) (xy 67.540292 -271.948604)
			(xy 67.569769 -272.01845) (xy 67.591655 -272.091033) (xy 67.605702 -272.165531) (xy 67.611751 -272.241101)
			(xy 68.727829 -272.241101) (xy 68.733878 -272.165531) (xy 68.747925 -272.091033) (xy 68.769811 -272.01845)
			(xy 68.799288 -271.948604) (xy 68.836023 -271.882287) (xy 68.879598 -271.820251) (xy 68.92952 -271.763198)
			(xy 68.985224 -271.711774) (xy 69.046079 -271.666563) (xy 69.111394 -271.628076) (xy 69.18043 -271.59675)
			(xy 69.252405 -271.57294) (xy 69.326503 -271.556915) (xy 69.401884 -271.548856) (xy 69.43979 -271.548352)
			(xy 69.477696 -271.548856) (xy 69.553077 -271.556915) (xy 69.627175 -271.57294) (xy 69.69915 -271.59675)
			(xy 69.768186 -271.628076) (xy 69.833501 -271.666563) (xy 69.894356 -271.711774) (xy 69.95006 -271.763198)
			(xy 69.999982 -271.820251) (xy 70.043557 -271.882287) (xy 70.080292 -271.948604) (xy 70.109769 -272.01845)
			(xy 70.131655 -272.091033) (xy 70.145702 -272.165531) (xy 70.151751 -272.241101) (xy 71.267829 -272.241101)
			(xy 71.273878 -272.165531) (xy 71.287925 -272.091033) (xy 71.309811 -272.01845) (xy 71.339288 -271.948604)
			(xy 71.376023 -271.882287) (xy 71.419598 -271.820251) (xy 71.46952 -271.763198) (xy 71.525224 -271.711774)
			(xy 71.586079 -271.666563) (xy 71.651394 -271.628076) (xy 71.72043 -271.59675) (xy 71.792405 -271.57294)
			(xy 71.866503 -271.556915) (xy 71.941884 -271.548856) (xy 71.97979 -271.548352) (xy 72.017696 -271.548856)
			(xy 72.093077 -271.556915) (xy 72.167175 -271.57294) (xy 72.23915 -271.59675) (xy 72.308186 -271.628076)
			(xy 72.373501 -271.666563) (xy 72.434356 -271.711774) (xy 72.49006 -271.763198) (xy 72.539982 -271.820251)
			(xy 72.583557 -271.882287) (xy 72.620292 -271.948604) (xy 72.649769 -272.01845) (xy 72.671655 -272.091033)
			(xy 72.685702 -272.165531) (xy 72.691751 -272.241101) (xy 73.807829 -272.241101) (xy 73.813878 -272.165531)
			(xy 73.827925 -272.091033) (xy 73.849811 -272.01845) (xy 73.879288 -271.948604) (xy 73.916023 -271.882287)
			(xy 73.959598 -271.820251) (xy 74.00952 -271.763198) (xy 74.065224 -271.711774) (xy 74.126079 -271.666563)
			(xy 74.191394 -271.628076) (xy 74.26043 -271.59675) (xy 74.332405 -271.57294) (xy 74.406503 -271.556915)
			(xy 74.481884 -271.548856) (xy 74.51979 -271.548352) (xy 74.557696 -271.548856) (xy 74.633077 -271.556915)
			(xy 74.707175 -271.57294) (xy 74.77915 -271.59675) (xy 74.848186 -271.628076) (xy 74.913501 -271.666563)
			(xy 74.974356 -271.711774) (xy 75.03006 -271.763198) (xy 75.079982 -271.820251) (xy 75.123557 -271.882287)
			(xy 75.160292 -271.948604) (xy 75.189769 -272.01845) (xy 75.211655 -272.091033) (xy 75.225702 -272.165531)
			(xy 75.231751 -272.241101) (xy 76.347829 -272.241101) (xy 76.353878 -272.165531) (xy 76.367925 -272.091033)
			(xy 76.389811 -272.01845) (xy 76.419288 -271.948604) (xy 76.456023 -271.882287) (xy 76.499598 -271.820251)
			(xy 76.54952 -271.763198) (xy 76.605224 -271.711774) (xy 76.666079 -271.666563) (xy 76.731394 -271.628076)
			(xy 76.80043 -271.59675) (xy 76.872405 -271.57294) (xy 76.946503 -271.556915) (xy 77.021884 -271.548856)
			(xy 77.05979 -271.548352) (xy 77.097696 -271.548856) (xy 77.173077 -271.556915) (xy 77.247175 -271.57294)
			(xy 77.31915 -271.59675) (xy 77.388186 -271.628076) (xy 77.453501 -271.666563) (xy 77.514356 -271.711774)
			(xy 77.57006 -271.763198) (xy 77.619982 -271.820251) (xy 77.663557 -271.882287) (xy 77.700292 -271.948604)
			(xy 77.729769 -272.01845) (xy 77.751655 -272.091033) (xy 77.765702 -272.165531) (xy 77.771751 -272.241101)
			(xy 78.887829 -272.241101) (xy 78.893878 -272.165531) (xy 78.907925 -272.091033) (xy 78.929811 -272.01845)
			(xy 78.959288 -271.948604) (xy 78.996023 -271.882287) (xy 79.039598 -271.820251) (xy 79.08952 -271.763198)
			(xy 79.145224 -271.711774) (xy 79.206079 -271.666563) (xy 79.271394 -271.628076) (xy 79.34043 -271.59675)
			(xy 79.412405 -271.57294) (xy 79.486503 -271.556915) (xy 79.561884 -271.548856) (xy 79.59979 -271.548352)
			(xy 79.637696 -271.548856) (xy 79.713077 -271.556915) (xy 79.787175 -271.57294) (xy 79.85915 -271.59675)
			(xy 79.928186 -271.628076) (xy 79.993501 -271.666563) (xy 80.054356 -271.711774) (xy 80.11006 -271.763198)
			(xy 80.159982 -271.820251) (xy 80.203557 -271.882287) (xy 80.240292 -271.948604) (xy 80.269769 -272.01845)
			(xy 80.291655 -272.091033) (xy 80.305702 -272.165531) (xy 80.311751 -272.241101) (xy 81.427829 -272.241101)
			(xy 81.433878 -272.165531) (xy 81.447925 -272.091033) (xy 81.469811 -272.01845) (xy 81.499288 -271.948604)
			(xy 81.536023 -271.882287) (xy 81.579598 -271.820251) (xy 81.62952 -271.763198) (xy 81.685224 -271.711774)
			(xy 81.746079 -271.666563) (xy 81.811394 -271.628076) (xy 81.88043 -271.59675) (xy 81.952405 -271.57294)
			(xy 82.026503 -271.556915) (xy 82.101884 -271.548856) (xy 82.13979 -271.548352) (xy 82.177696 -271.548856)
			(xy 82.253077 -271.556915) (xy 82.327175 -271.57294) (xy 82.39915 -271.59675) (xy 82.468186 -271.628076)
			(xy 82.533501 -271.666563) (xy 82.559813 -271.686111) (xy 86.197949 -271.686111) (xy 86.203998 -271.610541)
			(xy 86.218045 -271.536043) (xy 86.239931 -271.46346) (xy 86.269408 -271.393614) (xy 86.306143 -271.327297)
			(xy 86.349718 -271.265261) (xy 86.39964 -271.208208) (xy 86.455344 -271.156784) (xy 86.516199 -271.111573)
			(xy 86.581514 -271.073086) (xy 86.65055 -271.04176) (xy 86.722525 -271.01795) (xy 86.796623 -271.001925)
			(xy 86.872004 -270.993866) (xy 86.90991 -270.993362) (xy 86.947816 -270.993866) (xy 87.023197 -271.001925)
			(xy 87.097295 -271.01795) (xy 87.16927 -271.04176) (xy 87.238306 -271.073086) (xy 87.303621 -271.111573)
			(xy 87.364476 -271.156784) (xy 87.42018 -271.208208) (xy 87.470102 -271.265261) (xy 87.513677 -271.327297)
			(xy 87.550412 -271.393614) (xy 87.579889 -271.46346) (xy 87.601775 -271.536043) (xy 87.615822 -271.610541)
			(xy 87.621871 -271.686111) (xy 88.737949 -271.686111) (xy 88.743998 -271.610541) (xy 88.758045 -271.536043)
			(xy 88.779931 -271.46346) (xy 88.809408 -271.393614) (xy 88.846143 -271.327297) (xy 88.889718 -271.265261)
			(xy 88.93964 -271.208208) (xy 88.995344 -271.156784) (xy 89.056199 -271.111573) (xy 89.121514 -271.073086)
			(xy 89.19055 -271.04176) (xy 89.262525 -271.01795) (xy 89.336623 -271.001925) (xy 89.412004 -270.993866)
			(xy 89.44991 -270.993362) (xy 89.487816 -270.993866) (xy 89.563197 -271.001925) (xy 89.637295 -271.01795)
			(xy 89.70927 -271.04176) (xy 89.778306 -271.073086) (xy 89.843621 -271.111573) (xy 89.904476 -271.156784)
			(xy 89.96018 -271.208208) (xy 90.010102 -271.265261) (xy 90.053677 -271.327297) (xy 90.090412 -271.393614)
			(xy 90.119889 -271.46346) (xy 90.141775 -271.536043) (xy 90.155822 -271.610541) (xy 90.161871 -271.686111)
			(xy 91.277949 -271.686111) (xy 91.283998 -271.610541) (xy 91.298045 -271.536043) (xy 91.319931 -271.46346)
			(xy 91.349408 -271.393614) (xy 91.386143 -271.327297) (xy 91.429718 -271.265261) (xy 91.47964 -271.208208)
			(xy 91.535344 -271.156784) (xy 91.596199 -271.111573) (xy 91.661514 -271.073086) (xy 91.73055 -271.04176)
			(xy 91.802525 -271.01795) (xy 91.876623 -271.001925) (xy 91.952004 -270.993866) (xy 91.98991 -270.993362)
			(xy 92.027816 -270.993866) (xy 92.103197 -271.001925) (xy 92.177295 -271.01795) (xy 92.24927 -271.04176)
			(xy 92.318306 -271.073086) (xy 92.383621 -271.111573) (xy 92.444476 -271.156784) (xy 92.50018 -271.208208)
			(xy 92.550102 -271.265261) (xy 92.593677 -271.327297) (xy 92.630412 -271.393614) (xy 92.659889 -271.46346)
			(xy 92.681775 -271.536043) (xy 92.695822 -271.610541) (xy 92.701871 -271.686111) (xy 92.699852 -271.761895)
			(xy 92.68979 -271.837035) (xy 92.671798 -271.91068) (xy 92.64608 -271.981996) (xy 92.612928 -272.050173)
			(xy 92.572716 -272.114441) (xy 92.525901 -272.17407) (xy 92.473013 -272.228386) (xy 92.414651 -272.276772)
			(xy 92.351476 -272.31868) (xy 92.284205 -272.353636) (xy 92.2136 -272.381243) (xy 92.140459 -272.401189)
			(xy 92.065614 -272.413248) (xy 91.98991 -272.417283) (xy 91.914206 -272.413248) (xy 91.839361 -272.401189)
			(xy 91.76622 -272.381243) (xy 91.695615 -272.353636) (xy 91.628344 -272.31868) (xy 91.565169 -272.276772)
			(xy 91.506807 -272.228386) (xy 91.453919 -272.17407) (xy 91.407104 -272.114441) (xy 91.366892 -272.050173)
			(xy 91.33374 -271.981996) (xy 91.308022 -271.91068) (xy 91.29003 -271.837035) (xy 91.279968 -271.761895)
			(xy 91.277949 -271.686111) (xy 90.161871 -271.686111) (xy 90.159852 -271.761895) (xy 90.14979 -271.837035)
			(xy 90.131798 -271.91068) (xy 90.10608 -271.981996) (xy 90.072928 -272.050173) (xy 90.032716 -272.114441)
			(xy 89.985901 -272.17407) (xy 89.933013 -272.228386) (xy 89.874651 -272.276772) (xy 89.811476 -272.31868)
			(xy 89.744205 -272.353636) (xy 89.6736 -272.381243) (xy 89.600459 -272.401189) (xy 89.525614 -272.413248)
			(xy 89.44991 -272.417283) (xy 89.374206 -272.413248) (xy 89.299361 -272.401189) (xy 89.22622 -272.381243)
			(xy 89.155615 -272.353636) (xy 89.088344 -272.31868) (xy 89.025169 -272.276772) (xy 88.966807 -272.228386)
			(xy 88.913919 -272.17407) (xy 88.867104 -272.114441) (xy 88.826892 -272.050173) (xy 88.79374 -271.981996)
			(xy 88.768022 -271.91068) (xy 88.75003 -271.837035) (xy 88.739968 -271.761895) (xy 88.737949 -271.686111)
			(xy 87.621871 -271.686111) (xy 87.619852 -271.761895) (xy 87.60979 -271.837035) (xy 87.591798 -271.91068)
			(xy 87.56608 -271.981996) (xy 87.532928 -272.050173) (xy 87.492716 -272.114441) (xy 87.445901 -272.17407)
			(xy 87.393013 -272.228386) (xy 87.334651 -272.276772) (xy 87.271476 -272.31868) (xy 87.204205 -272.353636)
			(xy 87.1336 -272.381243) (xy 87.060459 -272.401189) (xy 86.985614 -272.413248) (xy 86.90991 -272.417283)
			(xy 86.834206 -272.413248) (xy 86.759361 -272.401189) (xy 86.68622 -272.381243) (xy 86.615615 -272.353636)
			(xy 86.548344 -272.31868) (xy 86.485169 -272.276772) (xy 86.426807 -272.228386) (xy 86.373919 -272.17407)
			(xy 86.327104 -272.114441) (xy 86.286892 -272.050173) (xy 86.25374 -271.981996) (xy 86.228022 -271.91068)
			(xy 86.21003 -271.837035) (xy 86.199968 -271.761895) (xy 86.197949 -271.686111) (xy 82.559813 -271.686111)
			(xy 82.594356 -271.711774) (xy 82.65006 -271.763198) (xy 82.699982 -271.820251) (xy 82.743557 -271.882287)
			(xy 82.780292 -271.948604) (xy 82.809769 -272.01845) (xy 82.831655 -272.091033) (xy 82.845702 -272.165531)
			(xy 82.851751 -272.241101) (xy 82.849732 -272.316885) (xy 82.83967 -272.392025) (xy 82.821678 -272.46567)
			(xy 82.79596 -272.536986) (xy 82.762808 -272.605163) (xy 82.722596 -272.669431) (xy 82.675781 -272.72906)
			(xy 82.622893 -272.783376) (xy 82.564531 -272.831762) (xy 82.501356 -272.87367) (xy 82.434085 -272.908626)
			(xy 82.36348 -272.936233) (xy 82.290588 -272.956111) (xy 84.927949 -272.956111) (xy 84.933998 -272.880541)
			(xy 84.948045 -272.806043) (xy 84.969931 -272.73346) (xy 84.999408 -272.663614) (xy 85.036143 -272.597297)
			(xy 85.079718 -272.535261) (xy 85.12964 -272.478208) (xy 85.185344 -272.426784) (xy 85.246199 -272.381573)
			(xy 85.311514 -272.343086) (xy 85.38055 -272.31176) (xy 85.452525 -272.28795) (xy 85.526623 -272.271925)
			(xy 85.602004 -272.263866) (xy 85.63991 -272.263362) (xy 85.677816 -272.263866) (xy 85.753197 -272.271925)
			(xy 85.827295 -272.28795) (xy 85.89927 -272.31176) (xy 85.968306 -272.343086) (xy 86.033621 -272.381573)
			(xy 86.094476 -272.426784) (xy 86.15018 -272.478208) (xy 86.200102 -272.535261) (xy 86.243677 -272.597297)
			(xy 86.280412 -272.663614) (xy 86.309889 -272.73346) (xy 86.331775 -272.806043) (xy 86.345822 -272.880541)
			(xy 86.351871 -272.956111) (xy 87.467949 -272.956111) (xy 87.473998 -272.880541) (xy 87.488045 -272.806043)
			(xy 87.509931 -272.73346) (xy 87.539408 -272.663614) (xy 87.576143 -272.597297) (xy 87.619718 -272.535261)
			(xy 87.66964 -272.478208) (xy 87.725344 -272.426784) (xy 87.786199 -272.381573) (xy 87.851514 -272.343086)
			(xy 87.92055 -272.31176) (xy 87.992525 -272.28795) (xy 88.066623 -272.271925) (xy 88.142004 -272.263866)
			(xy 88.17991 -272.263362) (xy 88.217816 -272.263866) (xy 88.293197 -272.271925) (xy 88.367295 -272.28795)
			(xy 88.43927 -272.31176) (xy 88.508306 -272.343086) (xy 88.573621 -272.381573) (xy 88.634476 -272.426784)
			(xy 88.69018 -272.478208) (xy 88.740102 -272.535261) (xy 88.783677 -272.597297) (xy 88.820412 -272.663614)
			(xy 88.849889 -272.73346) (xy 88.871775 -272.806043) (xy 88.885822 -272.880541) (xy 88.891871 -272.956111)
			(xy 90.007949 -272.956111) (xy 90.013998 -272.880541) (xy 90.028045 -272.806043) (xy 90.049931 -272.73346)
			(xy 90.079408 -272.663614) (xy 90.116143 -272.597297) (xy 90.159718 -272.535261) (xy 90.20964 -272.478208)
			(xy 90.265344 -272.426784) (xy 90.326199 -272.381573) (xy 90.391514 -272.343086) (xy 90.46055 -272.31176)
			(xy 90.532525 -272.28795) (xy 90.606623 -272.271925) (xy 90.682004 -272.263866) (xy 90.71991 -272.263362)
			(xy 90.757816 -272.263866) (xy 90.833197 -272.271925) (xy 90.907295 -272.28795) (xy 90.97927 -272.31176)
			(xy 91.048306 -272.343086) (xy 91.113621 -272.381573) (xy 91.174476 -272.426784) (xy 91.23018 -272.478208)
			(xy 91.280102 -272.535261) (xy 91.323677 -272.597297) (xy 91.360412 -272.663614) (xy 91.389889 -272.73346)
			(xy 91.411775 -272.806043) (xy 91.425822 -272.880541) (xy 91.431871 -272.956111) (xy 91.429852 -273.031895)
			(xy 91.41979 -273.107035) (xy 91.401798 -273.18068) (xy 91.37608 -273.251996) (xy 91.342928 -273.320173)
			(xy 91.302716 -273.384441) (xy 91.255901 -273.44407) (xy 91.203013 -273.498386) (xy 91.144651 -273.546772)
			(xy 91.081476 -273.58868) (xy 91.014205 -273.623636) (xy 90.9436 -273.651243) (xy 90.870459 -273.671189)
			(xy 90.795614 -273.683248) (xy 90.71991 -273.687283) (xy 90.644206 -273.683248) (xy 90.569361 -273.671189)
			(xy 90.49622 -273.651243) (xy 90.425615 -273.623636) (xy 90.358344 -273.58868) (xy 90.295169 -273.546772)
			(xy 90.236807 -273.498386) (xy 90.183919 -273.44407) (xy 90.137104 -273.384441) (xy 90.096892 -273.320173)
			(xy 90.06374 -273.251996) (xy 90.038022 -273.18068) (xy 90.02003 -273.107035) (xy 90.009968 -273.031895)
			(xy 90.007949 -272.956111) (xy 88.891871 -272.956111) (xy 88.889852 -273.031895) (xy 88.87979 -273.107035)
			(xy 88.861798 -273.18068) (xy 88.83608 -273.251996) (xy 88.802928 -273.320173) (xy 88.762716 -273.384441)
			(xy 88.715901 -273.44407) (xy 88.663013 -273.498386) (xy 88.604651 -273.546772) (xy 88.541476 -273.58868)
			(xy 88.474205 -273.623636) (xy 88.4036 -273.651243) (xy 88.330459 -273.671189) (xy 88.255614 -273.683248)
			(xy 88.17991 -273.687283) (xy 88.104206 -273.683248) (xy 88.029361 -273.671189) (xy 87.95622 -273.651243)
			(xy 87.885615 -273.623636) (xy 87.818344 -273.58868) (xy 87.755169 -273.546772) (xy 87.696807 -273.498386)
			(xy 87.643919 -273.44407) (xy 87.597104 -273.384441) (xy 87.556892 -273.320173) (xy 87.52374 -273.251996)
			(xy 87.498022 -273.18068) (xy 87.48003 -273.107035) (xy 87.469968 -273.031895) (xy 87.467949 -272.956111)
			(xy 86.351871 -272.956111) (xy 86.349852 -273.031895) (xy 86.33979 -273.107035) (xy 86.321798 -273.18068)
			(xy 86.29608 -273.251996) (xy 86.262928 -273.320173) (xy 86.222716 -273.384441) (xy 86.175901 -273.44407)
			(xy 86.123013 -273.498386) (xy 86.064651 -273.546772) (xy 86.001476 -273.58868) (xy 85.934205 -273.623636)
			(xy 85.8636 -273.651243) (xy 85.790459 -273.671189) (xy 85.715614 -273.683248) (xy 85.63991 -273.687283)
			(xy 85.564206 -273.683248) (xy 85.489361 -273.671189) (xy 85.41622 -273.651243) (xy 85.345615 -273.623636)
			(xy 85.278344 -273.58868) (xy 85.215169 -273.546772) (xy 85.156807 -273.498386) (xy 85.103919 -273.44407)
			(xy 85.057104 -273.384441) (xy 85.016892 -273.320173) (xy 84.98374 -273.251996) (xy 84.958022 -273.18068)
			(xy 84.94003 -273.107035) (xy 84.929968 -273.031895) (xy 84.927949 -272.956111) (xy 82.290588 -272.956111)
			(xy 82.290339 -272.956179) (xy 82.215494 -272.968238) (xy 82.13979 -272.972273) (xy 82.064086 -272.968238)
			(xy 81.989241 -272.956179) (xy 81.9161 -272.936233) (xy 81.845495 -272.908626) (xy 81.778224 -272.87367)
			(xy 81.715049 -272.831762) (xy 81.656687 -272.783376) (xy 81.603799 -272.72906) (xy 81.556984 -272.669431)
			(xy 81.516772 -272.605163) (xy 81.48362 -272.536986) (xy 81.457902 -272.46567) (xy 81.43991 -272.392025)
			(xy 81.429848 -272.316885) (xy 81.427829 -272.241101) (xy 80.311751 -272.241101) (xy 80.309732 -272.316885)
			(xy 80.29967 -272.392025) (xy 80.281678 -272.46567) (xy 80.25596 -272.536986) (xy 80.222808 -272.605163)
			(xy 80.182596 -272.669431) (xy 80.135781 -272.72906) (xy 80.082893 -272.783376) (xy 80.024531 -272.831762)
			(xy 79.961356 -272.87367) (xy 79.894085 -272.908626) (xy 79.82348 -272.936233) (xy 79.750339 -272.956179)
			(xy 79.675494 -272.968238) (xy 79.59979 -272.972273) (xy 79.524086 -272.968238) (xy 79.449241 -272.956179)
			(xy 79.3761 -272.936233) (xy 79.305495 -272.908626) (xy 79.238224 -272.87367) (xy 79.175049 -272.831762)
			(xy 79.116687 -272.783376) (xy 79.063799 -272.72906) (xy 79.016984 -272.669431) (xy 78.976772 -272.605163)
			(xy 78.94362 -272.536986) (xy 78.917902 -272.46567) (xy 78.89991 -272.392025) (xy 78.889848 -272.316885)
			(xy 78.887829 -272.241101) (xy 77.771751 -272.241101) (xy 77.769732 -272.316885) (xy 77.75967 -272.392025)
			(xy 77.741678 -272.46567) (xy 77.71596 -272.536986) (xy 77.682808 -272.605163) (xy 77.642596 -272.669431)
			(xy 77.595781 -272.72906) (xy 77.542893 -272.783376) (xy 77.484531 -272.831762) (xy 77.421356 -272.87367)
			(xy 77.354085 -272.908626) (xy 77.28348 -272.936233) (xy 77.210339 -272.956179) (xy 77.135494 -272.968238)
			(xy 77.05979 -272.972273) (xy 76.984086 -272.968238) (xy 76.909241 -272.956179) (xy 76.8361 -272.936233)
			(xy 76.765495 -272.908626) (xy 76.698224 -272.87367) (xy 76.635049 -272.831762) (xy 76.576687 -272.783376)
			(xy 76.523799 -272.72906) (xy 76.476984 -272.669431) (xy 76.436772 -272.605163) (xy 76.40362 -272.536986)
			(xy 76.377902 -272.46567) (xy 76.35991 -272.392025) (xy 76.349848 -272.316885) (xy 76.347829 -272.241101)
			(xy 75.231751 -272.241101) (xy 75.229732 -272.316885) (xy 75.21967 -272.392025) (xy 75.201678 -272.46567)
			(xy 75.17596 -272.536986) (xy 75.142808 -272.605163) (xy 75.102596 -272.669431) (xy 75.055781 -272.72906)
			(xy 75.002893 -272.783376) (xy 74.944531 -272.831762) (xy 74.881356 -272.87367) (xy 74.814085 -272.908626)
			(xy 74.74348 -272.936233) (xy 74.670339 -272.956179) (xy 74.595494 -272.968238) (xy 74.51979 -272.972273)
			(xy 74.444086 -272.968238) (xy 74.369241 -272.956179) (xy 74.2961 -272.936233) (xy 74.225495 -272.908626)
			(xy 74.158224 -272.87367) (xy 74.095049 -272.831762) (xy 74.036687 -272.783376) (xy 73.983799 -272.72906)
			(xy 73.936984 -272.669431) (xy 73.896772 -272.605163) (xy 73.86362 -272.536986) (xy 73.837902 -272.46567)
			(xy 73.81991 -272.392025) (xy 73.809848 -272.316885) (xy 73.807829 -272.241101) (xy 72.691751 -272.241101)
			(xy 72.689732 -272.316885) (xy 72.67967 -272.392025) (xy 72.661678 -272.46567) (xy 72.63596 -272.536986)
			(xy 72.602808 -272.605163) (xy 72.562596 -272.669431) (xy 72.515781 -272.72906) (xy 72.462893 -272.783376)
			(xy 72.404531 -272.831762) (xy 72.341356 -272.87367) (xy 72.274085 -272.908626) (xy 72.20348 -272.936233)
			(xy 72.130339 -272.956179) (xy 72.055494 -272.968238) (xy 71.97979 -272.972273) (xy 71.904086 -272.968238)
			(xy 71.829241 -272.956179) (xy 71.7561 -272.936233) (xy 71.685495 -272.908626) (xy 71.618224 -272.87367)
			(xy 71.555049 -272.831762) (xy 71.496687 -272.783376) (xy 71.443799 -272.72906) (xy 71.396984 -272.669431)
			(xy 71.356772 -272.605163) (xy 71.32362 -272.536986) (xy 71.297902 -272.46567) (xy 71.27991 -272.392025)
			(xy 71.269848 -272.316885) (xy 71.267829 -272.241101) (xy 70.151751 -272.241101) (xy 70.149732 -272.316885)
			(xy 70.13967 -272.392025) (xy 70.121678 -272.46567) (xy 70.09596 -272.536986) (xy 70.062808 -272.605163)
			(xy 70.022596 -272.669431) (xy 69.975781 -272.72906) (xy 69.922893 -272.783376) (xy 69.864531 -272.831762)
			(xy 69.801356 -272.87367) (xy 69.734085 -272.908626) (xy 69.66348 -272.936233) (xy 69.590339 -272.956179)
			(xy 69.515494 -272.968238) (xy 69.43979 -272.972273) (xy 69.364086 -272.968238) (xy 69.289241 -272.956179)
			(xy 69.2161 -272.936233) (xy 69.145495 -272.908626) (xy 69.078224 -272.87367) (xy 69.015049 -272.831762)
			(xy 68.956687 -272.783376) (xy 68.903799 -272.72906) (xy 68.856984 -272.669431) (xy 68.816772 -272.605163)
			(xy 68.78362 -272.536986) (xy 68.757902 -272.46567) (xy 68.73991 -272.392025) (xy 68.729848 -272.316885)
			(xy 68.727829 -272.241101) (xy 67.611751 -272.241101) (xy 67.609732 -272.316885) (xy 67.59967 -272.392025)
			(xy 67.581678 -272.46567) (xy 67.55596 -272.536986) (xy 67.522808 -272.605163) (xy 67.482596 -272.669431)
			(xy 67.435781 -272.72906) (xy 67.382893 -272.783376) (xy 67.324531 -272.831762) (xy 67.261356 -272.87367)
			(xy 67.194085 -272.908626) (xy 67.12348 -272.936233) (xy 67.050339 -272.956179) (xy 66.975494 -272.968238)
			(xy 66.89979 -272.972273) (xy 66.824086 -272.968238) (xy 66.749241 -272.956179) (xy 66.6761 -272.936233)
			(xy 66.605495 -272.908626) (xy 66.538224 -272.87367) (xy 66.475049 -272.831762) (xy 66.416687 -272.783376)
			(xy 66.363799 -272.72906) (xy 66.316984 -272.669431) (xy 66.276772 -272.605163) (xy 66.24362 -272.536986)
			(xy 66.217902 -272.46567) (xy 66.19991 -272.392025) (xy 66.189848 -272.316885) (xy 66.187829 -272.241101)
			(xy 65.071751 -272.241101) (xy 65.069732 -272.316885) (xy 65.05967 -272.392025) (xy 65.041678 -272.46567)
			(xy 65.01596 -272.536986) (xy 64.982808 -272.605163) (xy 64.942596 -272.669431) (xy 64.895781 -272.72906)
			(xy 64.842893 -272.783376) (xy 64.784531 -272.831762) (xy 64.721356 -272.87367) (xy 64.654085 -272.908626)
			(xy 64.58348 -272.936233) (xy 64.510339 -272.956179) (xy 64.435494 -272.968238) (xy 64.35979 -272.972273)
			(xy 64.284086 -272.968238) (xy 64.209241 -272.956179) (xy 64.1361 -272.936233) (xy 64.065495 -272.908626)
			(xy 63.998224 -272.87367) (xy 63.935049 -272.831762) (xy 63.876687 -272.783376) (xy 63.823799 -272.72906)
			(xy 63.776984 -272.669431) (xy 63.736772 -272.605163) (xy 63.70362 -272.536986) (xy 63.677902 -272.46567)
			(xy 63.65991 -272.392025) (xy 63.649848 -272.316885) (xy 63.647829 -272.241101) (xy 42.474432 -272.241101)
			(xy 42.525324 -272.277542) (xy 42.614813 -272.351469) (xy 42.698988 -272.431395) (xy 42.777449 -272.516938)
			(xy 42.849821 -272.607689) (xy 42.91576 -272.703218) (xy 42.974951 -272.803068) (xy 43.027112 -272.906764)
			(xy 43.071995 -273.013811) (xy 43.109385 -273.1237) (xy 43.139105 -273.235907) (xy 43.161013 -273.349897)
			(xy 43.175004 -273.465126) (xy 43.181013 -273.581047) (xy 43.179009 -273.697105) (xy 43.169003 -273.812749)
			(xy 43.151043 -273.927427) (xy 43.125213 -274.040593) (xy 43.091638 -274.151707) (xy 43.06342 -274.226111)
			(xy 86.197949 -274.226111) (xy 86.203998 -274.150541) (xy 86.218045 -274.076043) (xy 86.239931 -274.00346)
			(xy 86.269408 -273.933614) (xy 86.306143 -273.867297) (xy 86.349718 -273.805261) (xy 86.39964 -273.748208)
			(xy 86.455344 -273.696784) (xy 86.516199 -273.651573) (xy 86.581514 -273.613086) (xy 86.65055 -273.58176)
			(xy 86.722525 -273.55795) (xy 86.796623 -273.541925) (xy 86.872004 -273.533866) (xy 86.90991 -273.533362)
			(xy 86.947816 -273.533866) (xy 87.023197 -273.541925) (xy 87.097295 -273.55795) (xy 87.16927 -273.58176)
			(xy 87.238306 -273.613086) (xy 87.303621 -273.651573) (xy 87.364476 -273.696784) (xy 87.42018 -273.748208)
			(xy 87.470102 -273.805261) (xy 87.513677 -273.867297) (xy 87.550412 -273.933614) (xy 87.579889 -274.00346)
			(xy 87.601775 -274.076043) (xy 87.615822 -274.150541) (xy 87.621871 -274.226111) (xy 88.737949 -274.226111)
			(xy 88.743998 -274.150541) (xy 88.758045 -274.076043) (xy 88.779931 -274.00346) (xy 88.809408 -273.933614)
			(xy 88.846143 -273.867297) (xy 88.889718 -273.805261) (xy 88.93964 -273.748208) (xy 88.995344 -273.696784)
			(xy 89.056199 -273.651573) (xy 89.121514 -273.613086) (xy 89.19055 -273.58176) (xy 89.262525 -273.55795)
			(xy 89.336623 -273.541925) (xy 89.412004 -273.533866) (xy 89.44991 -273.533362) (xy 89.487816 -273.533866)
			(xy 89.563197 -273.541925) (xy 89.637295 -273.55795) (xy 89.70927 -273.58176) (xy 89.778306 -273.613086)
			(xy 89.843621 -273.651573) (xy 89.904476 -273.696784) (xy 89.96018 -273.748208) (xy 90.010102 -273.805261)
			(xy 90.053677 -273.867297) (xy 90.090412 -273.933614) (xy 90.119889 -274.00346) (xy 90.141775 -274.076043)
			(xy 90.155822 -274.150541) (xy 90.161871 -274.226111) (xy 91.277949 -274.226111) (xy 91.283998 -274.150541)
			(xy 91.298045 -274.076043) (xy 91.319931 -274.00346) (xy 91.349408 -273.933614) (xy 91.386143 -273.867297)
			(xy 91.429718 -273.805261) (xy 91.47964 -273.748208) (xy 91.535344 -273.696784) (xy 91.596199 -273.651573)
			(xy 91.661514 -273.613086) (xy 91.73055 -273.58176) (xy 91.802525 -273.55795) (xy 91.876623 -273.541925)
			(xy 91.952004 -273.533866) (xy 91.98991 -273.533362) (xy 92.027816 -273.533866) (xy 92.103197 -273.541925)
			(xy 92.177295 -273.55795) (xy 92.24927 -273.58176) (xy 92.318306 -273.613086) (xy 92.383621 -273.651573)
			(xy 92.444476 -273.696784) (xy 92.50018 -273.748208) (xy 92.550102 -273.805261) (xy 92.593677 -273.867297)
			(xy 92.630412 -273.933614) (xy 92.659889 -274.00346) (xy 92.681775 -274.076043) (xy 92.695822 -274.150541)
			(xy 92.701871 -274.226111) (xy 92.699852 -274.301895) (xy 92.68979 -274.377035) (xy 92.671798 -274.45068)
			(xy 92.64608 -274.521996) (xy 92.612928 -274.590173) (xy 92.572716 -274.654441) (xy 92.525901 -274.71407)
			(xy 92.473013 -274.768386) (xy 92.414651 -274.816772) (xy 92.351476 -274.85868) (xy 92.284205 -274.893636)
			(xy 92.2136 -274.921243) (xy 92.177855 -274.930991) (xy 93.154757 -274.930991) (xy 93.160779 -274.814808)
			(xy 93.174802 -274.699317) (xy 93.19676 -274.585069) (xy 93.226547 -274.472608) (xy 93.264022 -274.36247)
			(xy 93.309007 -274.25518) (xy 93.361286 -274.151249) (xy 93.420611 -274.051173) (xy 93.486699 -273.955427)
			(xy 93.559235 -273.86447) (xy 93.637874 -273.778734) (xy 93.72224 -273.698627) (xy 93.811932 -273.624531)
			(xy 93.906522 -273.556801) (xy 94.00556 -273.495757) (xy 94.108573 -273.441692) (xy 94.21507 -273.394862)
			(xy 94.324545 -273.355491) (xy 94.436475 -273.323767) (xy 94.550327 -273.299841) (xy 94.665559 -273.283827)
			(xy 94.781621 -273.2758) (xy 94.83979 -273.275298) (xy 94.897959 -273.2758) (xy 95.014021 -273.283827)
			(xy 95.129253 -273.299841) (xy 95.243105 -273.323767) (xy 95.355035 -273.355491) (xy 95.46451 -273.394862)
			(xy 95.571007 -273.441692) (xy 95.67402 -273.495757) (xy 95.773058 -273.556801) (xy 95.867648 -273.624531)
			(xy 95.95734 -273.698627) (xy 96.041706 -273.778734) (xy 96.120345 -273.86447) (xy 96.192881 -273.955427)
			(xy 96.258969 -274.051173) (xy 96.318294 -274.151249) (xy 96.370573 -274.25518) (xy 96.415558 -274.36247)
			(xy 96.453033 -274.472608) (xy 96.48282 -274.585069) (xy 96.504778 -274.699317) (xy 96.518801 -274.814808)
			(xy 96.524823 -274.930991) (xy 96.522815 -275.047313) (xy 96.512786 -275.163219) (xy 96.494785 -275.278156)
			(xy 96.468897 -275.391579) (xy 96.435246 -275.502944) (xy 96.393992 -275.611723) (xy 96.345331 -275.717397)
			(xy 96.289495 -275.819461) (xy 96.226752 -275.91743) (xy 96.157398 -276.010837) (xy 96.081766 -276.099237)
			(xy 96.000215 -276.182208) (xy 95.913134 -276.259355) (xy 95.820938 -276.33031) (xy 95.724066 -276.394736)
			(xy 95.622981 -276.452325) (xy 95.518163 -276.502802) (xy 95.410112 -276.545928) (xy 95.299344 -276.581497)
			(xy 95.186385 -276.609339) (xy 95.071775 -276.629321) (xy 94.95606 -276.641348) (xy 94.83979 -276.645364)
			(xy 94.72352 -276.641348) (xy 94.607805 -276.629321) (xy 94.493195 -276.609339) (xy 94.380236 -276.581497)
			(xy 94.269468 -276.545928) (xy 94.161417 -276.502802) (xy 94.056599 -276.452325) (xy 93.955514 -276.394736)
			(xy 93.858642 -276.33031) (xy 93.766446 -276.259355) (xy 93.679365 -276.182208) (xy 93.597814 -276.099237)
			(xy 93.522182 -276.010837) (xy 93.452828 -275.91743) (xy 93.390085 -275.819461) (xy 93.334249 -275.717397)
			(xy 93.285588 -275.611723) (xy 93.244334 -275.502944) (xy 93.210683 -275.391579) (xy 93.184795 -275.278156)
			(xy 93.166794 -275.163219) (xy 93.156765 -275.047313) (xy 93.154757 -274.930991) (xy 92.177855 -274.930991)
			(xy 92.140459 -274.941189) (xy 92.065614 -274.953248) (xy 91.98991 -274.957283) (xy 91.914206 -274.953248)
			(xy 91.839361 -274.941189) (xy 91.76622 -274.921243) (xy 91.695615 -274.893636) (xy 91.628344 -274.85868)
			(xy 91.565169 -274.816772) (xy 91.506807 -274.768386) (xy 91.453919 -274.71407) (xy 91.407104 -274.654441)
			(xy 91.366892 -274.590173) (xy 91.33374 -274.521996) (xy 91.308022 -274.45068) (xy 91.29003 -274.377035)
			(xy 91.279968 -274.301895) (xy 91.277949 -274.226111) (xy 90.161871 -274.226111) (xy 90.159852 -274.301895)
			(xy 90.14979 -274.377035) (xy 90.131798 -274.45068) (xy 90.10608 -274.521996) (xy 90.072928 -274.590173)
			(xy 90.032716 -274.654441) (xy 89.985901 -274.71407) (xy 89.933013 -274.768386) (xy 89.874651 -274.816772)
			(xy 89.811476 -274.85868) (xy 89.744205 -274.893636) (xy 89.6736 -274.921243) (xy 89.600459 -274.941189)
			(xy 89.525614 -274.953248) (xy 89.44991 -274.957283) (xy 89.374206 -274.953248) (xy 89.299361 -274.941189)
			(xy 89.22622 -274.921243) (xy 89.155615 -274.893636) (xy 89.088344 -274.85868) (xy 89.025169 -274.816772)
			(xy 88.966807 -274.768386) (xy 88.913919 -274.71407) (xy 88.867104 -274.654441) (xy 88.826892 -274.590173)
			(xy 88.79374 -274.521996) (xy 88.768022 -274.45068) (xy 88.75003 -274.377035) (xy 88.739968 -274.301895)
			(xy 88.737949 -274.226111) (xy 87.621871 -274.226111) (xy 87.619852 -274.301895) (xy 87.60979 -274.377035)
			(xy 87.591798 -274.45068) (xy 87.56608 -274.521996) (xy 87.532928 -274.590173) (xy 87.492716 -274.654441)
			(xy 87.445901 -274.71407) (xy 87.393013 -274.768386) (xy 87.334651 -274.816772) (xy 87.271476 -274.85868)
			(xy 87.204205 -274.893636) (xy 87.1336 -274.921243) (xy 87.060459 -274.941189) (xy 86.985614 -274.953248)
			(xy 86.90991 -274.957283) (xy 86.834206 -274.953248) (xy 86.759361 -274.941189) (xy 86.68622 -274.921243)
			(xy 86.615615 -274.893636) (xy 86.548344 -274.85868) (xy 86.485169 -274.816772) (xy 86.426807 -274.768386)
			(xy 86.373919 -274.71407) (xy 86.327104 -274.654441) (xy 86.286892 -274.590173) (xy 86.25374 -274.521996)
			(xy 86.228022 -274.45068) (xy 86.21003 -274.377035) (xy 86.199968 -274.301895) (xy 86.197949 -274.226111)
			(xy 43.06342 -274.226111) (xy 43.050477 -274.26024) (xy 43.001926 -274.365674) (xy 42.946217 -274.467508)
			(xy 42.883615 -274.565256) (xy 42.814419 -274.658451) (xy 42.738957 -274.746651) (xy 42.65759 -274.829434)
			(xy 42.570706 -274.906407) (xy 42.525601 -274.941121) (xy 63.647829 -274.941121) (xy 63.653878 -274.865551)
			(xy 63.667925 -274.791053) (xy 63.689811 -274.71847) (xy 63.719288 -274.648624) (xy 63.756023 -274.582307)
			(xy 63.799598 -274.520271) (xy 63.84952 -274.463218) (xy 63.905224 -274.411794) (xy 63.966079 -274.366583)
			(xy 64.031394 -274.328096) (xy 64.10043 -274.29677) (xy 64.172405 -274.27296) (xy 64.246503 -274.256935)
			(xy 64.321884 -274.248876) (xy 64.35979 -274.248372) (xy 64.397696 -274.248876) (xy 64.473077 -274.256935)
			(xy 64.547175 -274.27296) (xy 64.61915 -274.29677) (xy 64.688186 -274.328096) (xy 64.753501 -274.366583)
			(xy 64.814356 -274.411794) (xy 64.87006 -274.463218) (xy 64.919982 -274.520271) (xy 64.963557 -274.582307)
			(xy 65.000292 -274.648624) (xy 65.029769 -274.71847) (xy 65.051655 -274.791053) (xy 65.065702 -274.865551)
			(xy 65.071751 -274.941121) (xy 66.187829 -274.941121) (xy 66.193878 -274.865551) (xy 66.207925 -274.791053)
			(xy 66.229811 -274.71847) (xy 66.259288 -274.648624) (xy 66.296023 -274.582307) (xy 66.339598 -274.520271)
			(xy 66.38952 -274.463218) (xy 66.445224 -274.411794) (xy 66.506079 -274.366583) (xy 66.571394 -274.328096)
			(xy 66.64043 -274.29677) (xy 66.712405 -274.27296) (xy 66.786503 -274.256935) (xy 66.861884 -274.248876)
			(xy 66.89979 -274.248372) (xy 66.937696 -274.248876) (xy 67.013077 -274.256935) (xy 67.087175 -274.27296)
			(xy 67.15915 -274.29677) (xy 67.228186 -274.328096) (xy 67.293501 -274.366583) (xy 67.354356 -274.411794)
			(xy 67.41006 -274.463218) (xy 67.459982 -274.520271) (xy 67.503557 -274.582307) (xy 67.540292 -274.648624)
			(xy 67.569769 -274.71847) (xy 67.591655 -274.791053) (xy 67.605702 -274.865551) (xy 67.611751 -274.941121)
			(xy 68.727829 -274.941121) (xy 68.733878 -274.865551) (xy 68.747925 -274.791053) (xy 68.769811 -274.71847)
			(xy 68.799288 -274.648624) (xy 68.836023 -274.582307) (xy 68.879598 -274.520271) (xy 68.92952 -274.463218)
			(xy 68.985224 -274.411794) (xy 69.046079 -274.366583) (xy 69.111394 -274.328096) (xy 69.18043 -274.29677)
			(xy 69.252405 -274.27296) (xy 69.326503 -274.256935) (xy 69.401884 -274.248876) (xy 69.43979 -274.248372)
			(xy 69.477696 -274.248876) (xy 69.553077 -274.256935) (xy 69.627175 -274.27296) (xy 69.69915 -274.29677)
			(xy 69.768186 -274.328096) (xy 69.833501 -274.366583) (xy 69.894356 -274.411794) (xy 69.95006 -274.463218)
			(xy 69.999982 -274.520271) (xy 70.043557 -274.582307) (xy 70.080292 -274.648624) (xy 70.109769 -274.71847)
			(xy 70.131655 -274.791053) (xy 70.145702 -274.865551) (xy 70.151751 -274.941121) (xy 71.267829 -274.941121)
			(xy 71.273878 -274.865551) (xy 71.287925 -274.791053) (xy 71.309811 -274.71847) (xy 71.339288 -274.648624)
			(xy 71.376023 -274.582307) (xy 71.419598 -274.520271) (xy 71.46952 -274.463218) (xy 71.525224 -274.411794)
			(xy 71.586079 -274.366583) (xy 71.651394 -274.328096) (xy 71.72043 -274.29677) (xy 71.792405 -274.27296)
			(xy 71.866503 -274.256935) (xy 71.941884 -274.248876) (xy 71.97979 -274.248372) (xy 72.017696 -274.248876)
			(xy 72.093077 -274.256935) (xy 72.167175 -274.27296) (xy 72.23915 -274.29677) (xy 72.308186 -274.328096)
			(xy 72.373501 -274.366583) (xy 72.434356 -274.411794) (xy 72.49006 -274.463218) (xy 72.539982 -274.520271)
			(xy 72.583557 -274.582307) (xy 72.620292 -274.648624) (xy 72.649769 -274.71847) (xy 72.671655 -274.791053)
			(xy 72.685702 -274.865551) (xy 72.691751 -274.941121) (xy 73.807829 -274.941121) (xy 73.813878 -274.865551)
			(xy 73.827925 -274.791053) (xy 73.849811 -274.71847) (xy 73.879288 -274.648624) (xy 73.916023 -274.582307)
			(xy 73.959598 -274.520271) (xy 74.00952 -274.463218) (xy 74.065224 -274.411794) (xy 74.126079 -274.366583)
			(xy 74.191394 -274.328096) (xy 74.26043 -274.29677) (xy 74.332405 -274.27296) (xy 74.406503 -274.256935)
			(xy 74.481884 -274.248876) (xy 74.51979 -274.248372) (xy 74.557696 -274.248876) (xy 74.633077 -274.256935)
			(xy 74.707175 -274.27296) (xy 74.77915 -274.29677) (xy 74.848186 -274.328096) (xy 74.913501 -274.366583)
			(xy 74.974356 -274.411794) (xy 75.03006 -274.463218) (xy 75.079982 -274.520271) (xy 75.123557 -274.582307)
			(xy 75.160292 -274.648624) (xy 75.189769 -274.71847) (xy 75.211655 -274.791053) (xy 75.225702 -274.865551)
			(xy 75.231751 -274.941121) (xy 76.347829 -274.941121) (xy 76.353878 -274.865551) (xy 76.367925 -274.791053)
			(xy 76.389811 -274.71847) (xy 76.419288 -274.648624) (xy 76.456023 -274.582307) (xy 76.499598 -274.520271)
			(xy 76.54952 -274.463218) (xy 76.605224 -274.411794) (xy 76.666079 -274.366583) (xy 76.731394 -274.328096)
			(xy 76.80043 -274.29677) (xy 76.872405 -274.27296) (xy 76.946503 -274.256935) (xy 77.021884 -274.248876)
			(xy 77.05979 -274.248372) (xy 77.097696 -274.248876) (xy 77.173077 -274.256935) (xy 77.247175 -274.27296)
			(xy 77.31915 -274.29677) (xy 77.388186 -274.328096) (xy 77.453501 -274.366583) (xy 77.514356 -274.411794)
			(xy 77.57006 -274.463218) (xy 77.619982 -274.520271) (xy 77.663557 -274.582307) (xy 77.700292 -274.648624)
			(xy 77.729769 -274.71847) (xy 77.751655 -274.791053) (xy 77.765702 -274.865551) (xy 77.771751 -274.941121)
			(xy 78.887829 -274.941121) (xy 78.893878 -274.865551) (xy 78.907925 -274.791053) (xy 78.929811 -274.71847)
			(xy 78.959288 -274.648624) (xy 78.996023 -274.582307) (xy 79.039598 -274.520271) (xy 79.08952 -274.463218)
			(xy 79.145224 -274.411794) (xy 79.206079 -274.366583) (xy 79.271394 -274.328096) (xy 79.34043 -274.29677)
			(xy 79.412405 -274.27296) (xy 79.486503 -274.256935) (xy 79.561884 -274.248876) (xy 79.59979 -274.248372)
			(xy 79.637696 -274.248876) (xy 79.713077 -274.256935) (xy 79.787175 -274.27296) (xy 79.85915 -274.29677)
			(xy 79.928186 -274.328096) (xy 79.993501 -274.366583) (xy 80.054356 -274.411794) (xy 80.11006 -274.463218)
			(xy 80.159982 -274.520271) (xy 80.203557 -274.582307) (xy 80.240292 -274.648624) (xy 80.269769 -274.71847)
			(xy 80.291655 -274.791053) (xy 80.305702 -274.865551) (xy 80.311751 -274.941121) (xy 81.427829 -274.941121)
			(xy 81.433878 -274.865551) (xy 81.447925 -274.791053) (xy 81.469811 -274.71847) (xy 81.499288 -274.648624)
			(xy 81.536023 -274.582307) (xy 81.579598 -274.520271) (xy 81.62952 -274.463218) (xy 81.685224 -274.411794)
			(xy 81.746079 -274.366583) (xy 81.811394 -274.328096) (xy 81.88043 -274.29677) (xy 81.952405 -274.27296)
			(xy 82.026503 -274.256935) (xy 82.101884 -274.248876) (xy 82.13979 -274.248372) (xy 82.177696 -274.248876)
			(xy 82.253077 -274.256935) (xy 82.327175 -274.27296) (xy 82.39915 -274.29677) (xy 82.468186 -274.328096)
			(xy 82.533501 -274.366583) (xy 82.594356 -274.411794) (xy 82.65006 -274.463218) (xy 82.699982 -274.520271)
			(xy 82.743557 -274.582307) (xy 82.780292 -274.648624) (xy 82.809769 -274.71847) (xy 82.831655 -274.791053)
			(xy 82.845702 -274.865551) (xy 82.851751 -274.941121) (xy 82.849732 -275.016905) (xy 82.83967 -275.092045)
			(xy 82.821678 -275.16569) (xy 82.79596 -275.237006) (xy 82.762808 -275.305183) (xy 82.722596 -275.369451)
			(xy 82.675781 -275.42908) (xy 82.622893 -275.483396) (xy 82.607556 -275.496111) (xy 84.927949 -275.496111)
			(xy 84.933998 -275.420541) (xy 84.948045 -275.346043) (xy 84.969931 -275.27346) (xy 84.999408 -275.203614)
			(xy 85.036143 -275.137297) (xy 85.079718 -275.075261) (xy 85.12964 -275.018208) (xy 85.185344 -274.966784)
			(xy 85.246199 -274.921573) (xy 85.311514 -274.883086) (xy 85.38055 -274.85176) (xy 85.452525 -274.82795)
			(xy 85.526623 -274.811925) (xy 85.602004 -274.803866) (xy 85.63991 -274.803362) (xy 85.677816 -274.803866)
			(xy 85.753197 -274.811925) (xy 85.827295 -274.82795) (xy 85.89927 -274.85176) (xy 85.968306 -274.883086)
			(xy 86.033621 -274.921573) (xy 86.094476 -274.966784) (xy 86.15018 -275.018208) (xy 86.200102 -275.075261)
			(xy 86.243677 -275.137297) (xy 86.280412 -275.203614) (xy 86.309889 -275.27346) (xy 86.331775 -275.346043)
			(xy 86.345822 -275.420541) (xy 86.351871 -275.496111) (xy 87.467949 -275.496111) (xy 87.473998 -275.420541)
			(xy 87.488045 -275.346043) (xy 87.509931 -275.27346) (xy 87.539408 -275.203614) (xy 87.576143 -275.137297)
			(xy 87.619718 -275.075261) (xy 87.66964 -275.018208) (xy 87.725344 -274.966784) (xy 87.786199 -274.921573)
			(xy 87.851514 -274.883086) (xy 87.92055 -274.85176) (xy 87.992525 -274.82795) (xy 88.066623 -274.811925)
			(xy 88.142004 -274.803866) (xy 88.17991 -274.803362) (xy 88.217816 -274.803866) (xy 88.293197 -274.811925)
			(xy 88.367295 -274.82795) (xy 88.43927 -274.85176) (xy 88.508306 -274.883086) (xy 88.573621 -274.921573)
			(xy 88.634476 -274.966784) (xy 88.69018 -275.018208) (xy 88.740102 -275.075261) (xy 88.783677 -275.137297)
			(xy 88.820412 -275.203614) (xy 88.849889 -275.27346) (xy 88.871775 -275.346043) (xy 88.885822 -275.420541)
			(xy 88.891871 -275.496111) (xy 90.007949 -275.496111) (xy 90.013998 -275.420541) (xy 90.028045 -275.346043)
			(xy 90.049931 -275.27346) (xy 90.079408 -275.203614) (xy 90.116143 -275.137297) (xy 90.159718 -275.075261)
			(xy 90.20964 -275.018208) (xy 90.265344 -274.966784) (xy 90.326199 -274.921573) (xy 90.391514 -274.883086)
			(xy 90.46055 -274.85176) (xy 90.532525 -274.82795) (xy 90.606623 -274.811925) (xy 90.682004 -274.803866)
			(xy 90.71991 -274.803362) (xy 90.757816 -274.803866) (xy 90.833197 -274.811925) (xy 90.907295 -274.82795)
			(xy 90.97927 -274.85176) (xy 91.048306 -274.883086) (xy 91.113621 -274.921573) (xy 91.174476 -274.966784)
			(xy 91.23018 -275.018208) (xy 91.280102 -275.075261) (xy 91.323677 -275.137297) (xy 91.360412 -275.203614)
			(xy 91.389889 -275.27346) (xy 91.411775 -275.346043) (xy 91.425822 -275.420541) (xy 91.431871 -275.496111)
			(xy 91.429852 -275.571895) (xy 91.41979 -275.647035) (xy 91.401798 -275.72068) (xy 91.37608 -275.791996)
			(xy 91.342928 -275.860173) (xy 91.302716 -275.924441) (xy 91.255901 -275.98407) (xy 91.203013 -276.038386)
			(xy 91.144651 -276.086772) (xy 91.081476 -276.12868) (xy 91.014205 -276.163636) (xy 90.9436 -276.191243)
			(xy 90.870459 -276.211189) (xy 90.795614 -276.223248) (xy 90.71991 -276.227283) (xy 90.644206 -276.223248)
			(xy 90.569361 -276.211189) (xy 90.49622 -276.191243) (xy 90.425615 -276.163636) (xy 90.358344 -276.12868)
			(xy 90.295169 -276.086772) (xy 90.236807 -276.038386) (xy 90.183919 -275.98407) (xy 90.137104 -275.924441)
			(xy 90.096892 -275.860173) (xy 90.06374 -275.791996) (xy 90.038022 -275.72068) (xy 90.02003 -275.647035)
			(xy 90.009968 -275.571895) (xy 90.007949 -275.496111) (xy 88.891871 -275.496111) (xy 88.889852 -275.571895)
			(xy 88.87979 -275.647035) (xy 88.861798 -275.72068) (xy 88.83608 -275.791996) (xy 88.802928 -275.860173)
			(xy 88.762716 -275.924441) (xy 88.715901 -275.98407) (xy 88.663013 -276.038386) (xy 88.604651 -276.086772)
			(xy 88.541476 -276.12868) (xy 88.474205 -276.163636) (xy 88.4036 -276.191243) (xy 88.330459 -276.211189)
			(xy 88.255614 -276.223248) (xy 88.17991 -276.227283) (xy 88.104206 -276.223248) (xy 88.029361 -276.211189)
			(xy 87.95622 -276.191243) (xy 87.885615 -276.163636) (xy 87.818344 -276.12868) (xy 87.755169 -276.086772)
			(xy 87.696807 -276.038386) (xy 87.643919 -275.98407) (xy 87.597104 -275.924441) (xy 87.556892 -275.860173)
			(xy 87.52374 -275.791996) (xy 87.498022 -275.72068) (xy 87.48003 -275.647035) (xy 87.469968 -275.571895)
			(xy 87.467949 -275.496111) (xy 86.351871 -275.496111) (xy 86.349852 -275.571895) (xy 86.33979 -275.647035)
			(xy 86.321798 -275.72068) (xy 86.29608 -275.791996) (xy 86.262928 -275.860173) (xy 86.222716 -275.924441)
			(xy 86.175901 -275.98407) (xy 86.123013 -276.038386) (xy 86.064651 -276.086772) (xy 86.001476 -276.12868)
			(xy 85.934205 -276.163636) (xy 85.8636 -276.191243) (xy 85.790459 -276.211189) (xy 85.715614 -276.223248)
			(xy 85.63991 -276.227283) (xy 85.564206 -276.223248) (xy 85.489361 -276.211189) (xy 85.41622 -276.191243)
			(xy 85.345615 -276.163636) (xy 85.278344 -276.12868) (xy 85.215169 -276.086772) (xy 85.156807 -276.038386)
			(xy 85.103919 -275.98407) (xy 85.057104 -275.924441) (xy 85.016892 -275.860173) (xy 84.98374 -275.791996)
			(xy 84.958022 -275.72068) (xy 84.94003 -275.647035) (xy 84.929968 -275.571895) (xy 84.927949 -275.496111)
			(xy 82.607556 -275.496111) (xy 82.564531 -275.531782) (xy 82.501356 -275.57369) (xy 82.434085 -275.608646)
			(xy 82.36348 -275.636253) (xy 82.290339 -275.656199) (xy 82.215494 -275.668258) (xy 82.13979 -275.672293)
			(xy 82.064086 -275.668258) (xy 81.989241 -275.656199) (xy 81.9161 -275.636253) (xy 81.845495 -275.608646)
			(xy 81.778224 -275.57369) (xy 81.715049 -275.531782) (xy 81.656687 -275.483396) (xy 81.603799 -275.42908)
			(xy 81.556984 -275.369451) (xy 81.516772 -275.305183) (xy 81.48362 -275.237006) (xy 81.457902 -275.16569)
			(xy 81.43991 -275.092045) (xy 81.429848 -275.016905) (xy 81.427829 -274.941121) (xy 80.311751 -274.941121)
			(xy 80.309732 -275.016905) (xy 80.29967 -275.092045) (xy 80.281678 -275.16569) (xy 80.25596 -275.237006)
			(xy 80.222808 -275.305183) (xy 80.182596 -275.369451) (xy 80.135781 -275.42908) (xy 80.082893 -275.483396)
			(xy 80.024531 -275.531782) (xy 79.961356 -275.57369) (xy 79.894085 -275.608646) (xy 79.82348 -275.636253)
			(xy 79.750339 -275.656199) (xy 79.675494 -275.668258) (xy 79.59979 -275.672293) (xy 79.524086 -275.668258)
			(xy 79.449241 -275.656199) (xy 79.3761 -275.636253) (xy 79.305495 -275.608646) (xy 79.238224 -275.57369)
			(xy 79.175049 -275.531782) (xy 79.116687 -275.483396) (xy 79.063799 -275.42908) (xy 79.016984 -275.369451)
			(xy 78.976772 -275.305183) (xy 78.94362 -275.237006) (xy 78.917902 -275.16569) (xy 78.89991 -275.092045)
			(xy 78.889848 -275.016905) (xy 78.887829 -274.941121) (xy 77.771751 -274.941121) (xy 77.769732 -275.016905)
			(xy 77.75967 -275.092045) (xy 77.741678 -275.16569) (xy 77.71596 -275.237006) (xy 77.682808 -275.305183)
			(xy 77.642596 -275.369451) (xy 77.595781 -275.42908) (xy 77.542893 -275.483396) (xy 77.484531 -275.531782)
			(xy 77.421356 -275.57369) (xy 77.354085 -275.608646) (xy 77.28348 -275.636253) (xy 77.210339 -275.656199)
			(xy 77.135494 -275.668258) (xy 77.05979 -275.672293) (xy 76.984086 -275.668258) (xy 76.909241 -275.656199)
			(xy 76.8361 -275.636253) (xy 76.765495 -275.608646) (xy 76.698224 -275.57369) (xy 76.635049 -275.531782)
			(xy 76.576687 -275.483396) (xy 76.523799 -275.42908) (xy 76.476984 -275.369451) (xy 76.436772 -275.305183)
			(xy 76.40362 -275.237006) (xy 76.377902 -275.16569) (xy 76.35991 -275.092045) (xy 76.349848 -275.016905)
			(xy 76.347829 -274.941121) (xy 75.231751 -274.941121) (xy 75.229732 -275.016905) (xy 75.21967 -275.092045)
			(xy 75.201678 -275.16569) (xy 75.17596 -275.237006) (xy 75.142808 -275.305183) (xy 75.102596 -275.369451)
			(xy 75.055781 -275.42908) (xy 75.002893 -275.483396) (xy 74.944531 -275.531782) (xy 74.881356 -275.57369)
			(xy 74.814085 -275.608646) (xy 74.74348 -275.636253) (xy 74.670339 -275.656199) (xy 74.595494 -275.668258)
			(xy 74.51979 -275.672293) (xy 74.444086 -275.668258) (xy 74.369241 -275.656199) (xy 74.2961 -275.636253)
			(xy 74.225495 -275.608646) (xy 74.158224 -275.57369) (xy 74.095049 -275.531782) (xy 74.036687 -275.483396)
			(xy 73.983799 -275.42908) (xy 73.936984 -275.369451) (xy 73.896772 -275.305183) (xy 73.86362 -275.237006)
			(xy 73.837902 -275.16569) (xy 73.81991 -275.092045) (xy 73.809848 -275.016905) (xy 73.807829 -274.941121)
			(xy 72.691751 -274.941121) (xy 72.689732 -275.016905) (xy 72.67967 -275.092045) (xy 72.661678 -275.16569)
			(xy 72.63596 -275.237006) (xy 72.602808 -275.305183) (xy 72.562596 -275.369451) (xy 72.515781 -275.42908)
			(xy 72.462893 -275.483396) (xy 72.404531 -275.531782) (xy 72.341356 -275.57369) (xy 72.274085 -275.608646)
			(xy 72.20348 -275.636253) (xy 72.130339 -275.656199) (xy 72.055494 -275.668258) (xy 71.97979 -275.672293)
			(xy 71.904086 -275.668258) (xy 71.829241 -275.656199) (xy 71.7561 -275.636253) (xy 71.685495 -275.608646)
			(xy 71.618224 -275.57369) (xy 71.555049 -275.531782) (xy 71.496687 -275.483396) (xy 71.443799 -275.42908)
			(xy 71.396984 -275.369451) (xy 71.356772 -275.305183) (xy 71.32362 -275.237006) (xy 71.297902 -275.16569)
			(xy 71.27991 -275.092045) (xy 71.269848 -275.016905) (xy 71.267829 -274.941121) (xy 70.151751 -274.941121)
			(xy 70.149732 -275.016905) (xy 70.13967 -275.092045) (xy 70.121678 -275.16569) (xy 70.09596 -275.237006)
			(xy 70.062808 -275.305183) (xy 70.022596 -275.369451) (xy 69.975781 -275.42908) (xy 69.922893 -275.483396)
			(xy 69.864531 -275.531782) (xy 69.801356 -275.57369) (xy 69.734085 -275.608646) (xy 69.66348 -275.636253)
			(xy 69.590339 -275.656199) (xy 69.515494 -275.668258) (xy 69.43979 -275.672293) (xy 69.364086 -275.668258)
			(xy 69.289241 -275.656199) (xy 69.2161 -275.636253) (xy 69.145495 -275.608646) (xy 69.078224 -275.57369)
			(xy 69.015049 -275.531782) (xy 68.956687 -275.483396) (xy 68.903799 -275.42908) (xy 68.856984 -275.369451)
			(xy 68.816772 -275.305183) (xy 68.78362 -275.237006) (xy 68.757902 -275.16569) (xy 68.73991 -275.092045)
			(xy 68.729848 -275.016905) (xy 68.727829 -274.941121) (xy 67.611751 -274.941121) (xy 67.609732 -275.016905)
			(xy 67.59967 -275.092045) (xy 67.581678 -275.16569) (xy 67.55596 -275.237006) (xy 67.522808 -275.305183)
			(xy 67.482596 -275.369451) (xy 67.435781 -275.42908) (xy 67.382893 -275.483396) (xy 67.324531 -275.531782)
			(xy 67.261356 -275.57369) (xy 67.194085 -275.608646) (xy 67.12348 -275.636253) (xy 67.050339 -275.656199)
			(xy 66.975494 -275.668258) (xy 66.89979 -275.672293) (xy 66.824086 -275.668258) (xy 66.749241 -275.656199)
			(xy 66.6761 -275.636253) (xy 66.605495 -275.608646) (xy 66.538224 -275.57369) (xy 66.475049 -275.531782)
			(xy 66.416687 -275.483396) (xy 66.363799 -275.42908) (xy 66.316984 -275.369451) (xy 66.276772 -275.305183)
			(xy 66.24362 -275.237006) (xy 66.217902 -275.16569) (xy 66.19991 -275.092045) (xy 66.189848 -275.016905)
			(xy 66.187829 -274.941121) (xy 65.071751 -274.941121) (xy 65.069732 -275.016905) (xy 65.05967 -275.092045)
			(xy 65.041678 -275.16569) (xy 65.01596 -275.237006) (xy 64.982808 -275.305183) (xy 64.942596 -275.369451)
			(xy 64.895781 -275.42908) (xy 64.842893 -275.483396) (xy 64.784531 -275.531782) (xy 64.721356 -275.57369)
			(xy 64.654085 -275.608646) (xy 64.58348 -275.636253) (xy 64.510339 -275.656199) (xy 64.435494 -275.668258)
			(xy 64.35979 -275.672293) (xy 64.284086 -275.668258) (xy 64.209241 -275.656199) (xy 64.1361 -275.636253)
			(xy 64.065495 -275.608646) (xy 63.998224 -275.57369) (xy 63.935049 -275.531782) (xy 63.876687 -275.483396)
			(xy 63.823799 -275.42908) (xy 63.776984 -275.369451) (xy 63.736772 -275.305183) (xy 63.70362 -275.237006)
			(xy 63.677902 -275.16569) (xy 63.65991 -275.092045) (xy 63.649848 -275.016905) (xy 63.647829 -274.941121)
			(xy 42.525601 -274.941121) (xy 42.478719 -274.977202) (xy 42.382066 -275.041482) (xy 42.281209 -275.09894)
			(xy 42.176629 -275.149304) (xy 42.068822 -275.192332) (xy 41.958305 -275.22782) (xy 41.845602 -275.255599)
			(xy 41.731251 -275.275536) (xy 41.615797 -275.287537) (xy 41.49979 -275.291543) (xy 41.383783 -275.287537)
			(xy 41.268329 -275.275536) (xy 41.153978 -275.255599) (xy 41.041275 -275.22782) (xy 40.930758 -275.192332)
			(xy 40.822951 -275.149304) (xy 40.718371 -275.09894) (xy 40.617514 -275.041482) (xy 40.520861 -274.977202)
			(xy 40.428874 -274.906407) (xy 40.34199 -274.829434) (xy 40.260623 -274.746651) (xy 40.185161 -274.658451)
			(xy 40.115965 -274.565256) (xy 40.053363 -274.467508) (xy 39.997654 -274.365674) (xy 39.949103 -274.26024)
			(xy 39.907942 -274.151707) (xy 39.874367 -274.040593) (xy 39.848537 -273.927427) (xy 39.830577 -273.812749)
			(xy 39.820571 -273.697105) (xy 39.818567 -273.581047) (xy 39.53764 -273.581047) (xy 39.53764 -275.875242)
			(xy 44.185074 -280.522676) (xy 88.405952 -280.522676) (xy 88.405952 -280.46274) (xy 88.413775 -280.403318)
			(xy 88.429288 -280.345425) (xy 88.452224 -280.290052) (xy 88.482191 -280.238146) (xy 88.518678 -280.190596)
			(xy 88.561058 -280.148216) (xy 88.608608 -280.111729) (xy 88.660514 -280.081762) (xy 88.715887 -280.058826)
			(xy 88.77378 -280.043313) (xy 88.833202 -280.03549) (xy 88.86317 -280.035) (xy 88.893138 -280.03549)
			(xy 88.95256 -280.043313) (xy 89.010453 -280.058826) (xy 89.065826 -280.081762) (xy 89.117732 -280.111729)
			(xy 89.165282 -280.148216) (xy 89.207662 -280.190596) (xy 89.244149 -280.238146) (xy 89.274116 -280.290052)
			(xy 89.297052 -280.345425) (xy 89.312565 -280.403318) (xy 89.320388 -280.46274) (xy 89.320388 -280.522676)
			(xy 89.312565 -280.582098) (xy 89.297052 -280.639991) (xy 89.274116 -280.695364) (xy 89.244149 -280.74727)
			(xy 89.207662 -280.79482) (xy 89.165282 -280.8372) (xy 89.117732 -280.873687) (xy 89.065826 -280.903654)
			(xy 89.010453 -280.92659) (xy 88.95256 -280.942103) (xy 88.893138 -280.949926) (xy 88.833202 -280.949926)
			(xy 88.77378 -280.942103) (xy 88.715887 -280.92659) (xy 88.660514 -280.903654) (xy 88.608608 -280.873687)
			(xy 88.561058 -280.8372) (xy 88.518678 -280.79482) (xy 88.482191 -280.74727) (xy 88.452224 -280.695364)
			(xy 88.429288 -280.639991) (xy 88.413775 -280.582098) (xy 88.405952 -280.522676) (xy 44.185074 -280.522676)
			(xy 44.260008 -280.59761) (xy 44.260008 -281.15666) (xy 86.943928 -281.15666) (xy 86.943928 -281.096724)
			(xy 86.951751 -281.037302) (xy 86.967264 -280.979409) (xy 86.9902 -280.924036) (xy 87.020167 -280.87213)
			(xy 87.056654 -280.82458) (xy 87.099034 -280.7822) (xy 87.146584 -280.745713) (xy 87.19849 -280.715746)
			(xy 87.253863 -280.69281) (xy 87.311756 -280.677297) (xy 87.371178 -280.669474) (xy 87.401146 -280.668984)
			(xy 87.431114 -280.669474) (xy 87.490536 -280.677297) (xy 87.548429 -280.69281) (xy 87.603802 -280.715746)
			(xy 87.655708 -280.745713) (xy 87.703258 -280.7822) (xy 87.745638 -280.82458) (xy 87.782125 -280.87213)
			(xy 87.812092 -280.924036) (xy 87.835028 -280.979409) (xy 87.850541 -281.037302) (xy 87.858364 -281.096724)
			(xy 87.858364 -281.15666) (xy 87.850541 -281.216082) (xy 87.835028 -281.273975) (xy 87.812092 -281.329348)
			(xy 87.782125 -281.381254) (xy 87.745638 -281.428804) (xy 87.703258 -281.471184) (xy 87.655708 -281.507671)
			(xy 87.603802 -281.537638) (xy 87.548429 -281.560574) (xy 87.490536 -281.576087) (xy 87.431114 -281.58391)
			(xy 87.371178 -281.58391) (xy 87.311756 -281.576087) (xy 87.253863 -281.560574) (xy 87.19849 -281.537638)
			(xy 87.146584 -281.507671) (xy 87.099034 -281.471184) (xy 87.056654 -281.428804) (xy 87.020167 -281.381254)
			(xy 86.9902 -281.329348) (xy 86.967264 -281.273975) (xy 86.951751 -281.216082) (xy 86.943928 -281.15666)
			(xy 44.260008 -281.15666) (xy 44.260008 -281.86786) (xy 85.270068 -281.86786) (xy 85.270068 -281.807924)
			(xy 85.277891 -281.748502) (xy 85.293404 -281.690609) (xy 85.31634 -281.635236) (xy 85.346307 -281.58333)
			(xy 85.382794 -281.53578) (xy 85.425174 -281.4934) (xy 85.472724 -281.456913) (xy 85.52463 -281.426946)
			(xy 85.580003 -281.40401) (xy 85.637896 -281.388497) (xy 85.697318 -281.380674) (xy 85.727286 -281.380184)
			(xy 85.757254 -281.380674) (xy 85.816676 -281.388497) (xy 85.874569 -281.40401) (xy 85.929942 -281.426946)
			(xy 85.981848 -281.456913) (xy 86.029398 -281.4934) (xy 86.071778 -281.53578) (xy 86.108265 -281.58333)
			(xy 86.138232 -281.635236) (xy 86.161168 -281.690609) (xy 86.176681 -281.748502) (xy 86.184504 -281.807924)
			(xy 86.184504 -281.86786) (xy 86.176681 -281.927282) (xy 86.161168 -281.985175) (xy 86.138232 -282.040548)
			(xy 86.108265 -282.092454) (xy 86.071778 -282.140004) (xy 86.029398 -282.182384) (xy 85.981848 -282.218871)
			(xy 85.929942 -282.248838) (xy 85.874569 -282.271774) (xy 85.816676 -282.287287) (xy 85.757254 -282.29511)
			(xy 85.697318 -282.29511) (xy 85.637896 -282.287287) (xy 85.580003 -282.271774) (xy 85.52463 -282.248838)
			(xy 85.472724 -282.218871) (xy 85.425174 -282.182384) (xy 85.382794 -282.140004) (xy 85.346307 -282.092454)
			(xy 85.31634 -282.040548) (xy 85.293404 -281.985175) (xy 85.277891 -281.927282) (xy 85.270068 -281.86786)
			(xy 44.260008 -281.86786) (xy 44.260008 -283.51632) (xy 83.850462 -283.51632) (xy 83.850462 -283.456384)
			(xy 83.858285 -283.396962) (xy 83.873798 -283.339069) (xy 83.896734 -283.283696) (xy 83.926701 -283.23179)
			(xy 83.963188 -283.18424) (xy 84.005568 -283.14186) (xy 84.053118 -283.105373) (xy 84.105024 -283.075406)
			(xy 84.160397 -283.05247) (xy 84.21829 -283.036957) (xy 84.277712 -283.029134) (xy 84.30768 -283.028644)
			(xy 84.337648 -283.029134) (xy 84.39707 -283.036957) (xy 84.454963 -283.05247) (xy 84.510336 -283.075406)
			(xy 84.562242 -283.105373) (xy 84.609792 -283.14186) (xy 84.652172 -283.18424) (xy 84.688659 -283.23179)
			(xy 84.718626 -283.283696) (xy 84.741562 -283.339069) (xy 84.757075 -283.396962) (xy 84.764898 -283.456384)
			(xy 84.764898 -283.51632) (xy 84.757075 -283.575742) (xy 84.741562 -283.633635) (xy 84.718626 -283.689008)
			(xy 84.688659 -283.740914) (xy 84.652172 -283.788464) (xy 84.609792 -283.830844) (xy 84.562242 -283.867331)
			(xy 84.510336 -283.897298) (xy 84.454963 -283.920234) (xy 84.39707 -283.935747) (xy 84.337648 -283.94357)
			(xy 84.277712 -283.94357) (xy 84.21829 -283.935747) (xy 84.160397 -283.920234) (xy 84.105024 -283.897298)
			(xy 84.053118 -283.867331) (xy 84.005568 -283.830844) (xy 83.963188 -283.788464) (xy 83.926701 -283.740914)
			(xy 83.896734 -283.689008) (xy 83.873798 -283.633635) (xy 83.858285 -283.575742) (xy 83.850462 -283.51632)
			(xy 44.260008 -283.51632) (xy 44.260008 -284.379416) (xy 51.251612 -284.379416) (xy 52.903628 -284.379416)
			(xy 52.903628 -284.786828) (xy 83.105988 -284.786828) (xy 83.105988 -284.726892) (xy 83.113811 -284.66747)
			(xy 83.129324 -284.609577) (xy 83.15226 -284.554204) (xy 83.182227 -284.502298) (xy 83.218714 -284.454748)
			(xy 83.261094 -284.412368) (xy 83.308644 -284.375881) (xy 83.36055 -284.345914) (xy 83.415923 -284.322978)
			(xy 83.473816 -284.307465) (xy 83.533238 -284.299642) (xy 83.563206 -284.299152) (xy 83.593174 -284.299642)
			(xy 83.652596 -284.307465) (xy 83.710489 -284.322978) (xy 83.765862 -284.345914) (xy 83.817768 -284.375881)
			(xy 83.865318 -284.412368) (xy 83.907698 -284.454748) (xy 83.944185 -284.502298) (xy 83.974152 -284.554204)
			(xy 83.997088 -284.609577) (xy 84.012601 -284.66747) (xy 84.020424 -284.726892) (xy 84.020424 -284.786828)
			(xy 84.012601 -284.84625) (xy 83.997088 -284.904143) (xy 83.974152 -284.959516) (xy 83.944185 -285.011422)
			(xy 83.907698 -285.058972) (xy 83.865318 -285.101352) (xy 83.817768 -285.137839) (xy 83.765862 -285.167806)
			(xy 83.710489 -285.190742) (xy 83.652596 -285.206255) (xy 83.593174 -285.214078) (xy 83.533238 -285.214078)
			(xy 83.473816 -285.206255) (xy 83.415923 -285.190742) (xy 83.36055 -285.167806) (xy 83.308644 -285.137839)
			(xy 83.261094 -285.101352) (xy 83.218714 -285.058972) (xy 83.182227 -285.011422) (xy 83.15226 -284.959516)
			(xy 83.129324 -284.904143) (xy 83.113811 -284.84625) (xy 83.105988 -284.786828) (xy 52.903628 -284.786828)
			(xy 52.903628 -285.624117) (xy 63.182746 -285.624117) (xy 63.182746 -285.552795) (xy 63.190732 -285.481921)
			(xy 63.206602 -285.412386) (xy 63.230159 -285.345066) (xy 63.261104 -285.280807) (xy 63.29905 -285.220416)
			(xy 63.343519 -285.164654) (xy 63.393952 -285.114221) (xy 63.449714 -285.069752) (xy 63.510105 -285.031806)
			(xy 63.574364 -285.000861) (xy 63.641684 -284.977304) (xy 63.711219 -284.961434) (xy 63.782093 -284.953448)
			(xy 63.817754 -284.952948) (xy 63.853415 -284.953448) (xy 63.924289 -284.961434) (xy 63.993824 -284.977304)
			(xy 64.061144 -285.000861) (xy 64.125403 -285.031806) (xy 64.185794 -285.069752) (xy 64.241556 -285.114221)
			(xy 64.291989 -285.164654) (xy 64.336458 -285.220416) (xy 64.374404 -285.280807) (xy 64.405349 -285.345066)
			(xy 64.428906 -285.412386) (xy 64.444776 -285.481921) (xy 64.452762 -285.552795) (xy 64.452762 -285.624117)
			(xy 65.714618 -285.624117) (xy 65.714618 -285.552795) (xy 65.722604 -285.481921) (xy 65.738474 -285.412386)
			(xy 65.762031 -285.345066) (xy 65.792976 -285.280807) (xy 65.830922 -285.220416) (xy 65.875391 -285.164654)
			(xy 65.925824 -285.114221) (xy 65.981586 -285.069752) (xy 66.041977 -285.031806) (xy 66.106236 -285.000861)
			(xy 66.173556 -284.977304) (xy 66.243091 -284.961434) (xy 66.313965 -284.953448) (xy 66.349626 -284.952948)
			(xy 66.385287 -284.953448) (xy 66.456161 -284.961434) (xy 66.525696 -284.977304) (xy 66.593016 -285.000861)
			(xy 66.657275 -285.031806) (xy 66.717666 -285.069752) (xy 66.773428 -285.114221) (xy 66.823861 -285.164654)
			(xy 66.86833 -285.220416) (xy 66.906276 -285.280807) (xy 66.937221 -285.345066) (xy 66.960778 -285.412386)
			(xy 66.976648 -285.481921) (xy 66.984634 -285.552795) (xy 66.984634 -285.587541) (xy 67.938642 -285.587541)
			(xy 67.938642 -285.516219) (xy 67.946628 -285.445345) (xy 67.962498 -285.37581) (xy 67.986055 -285.30849)
			(xy 68.017 -285.244231) (xy 68.054946 -285.18384) (xy 68.099415 -285.128078) (xy 68.149848 -285.077645)
			(xy 68.20561 -285.033176) (xy 68.266001 -284.99523) (xy 68.33026 -284.964285) (xy 68.39758 -284.940728)
			(xy 68.467115 -284.924858) (xy 68.537989 -284.916872) (xy 68.57365 -284.916372) (xy 68.609311 -284.916872)
			(xy 68.680185 -284.924858) (xy 68.74972 -284.940728) (xy 68.81704 -284.964285) (xy 68.881299 -284.99523)
			(xy 68.94169 -285.033176) (xy 68.997452 -285.077645) (xy 69.047885 -285.128078) (xy 69.092354 -285.18384)
			(xy 69.1303 -285.244231) (xy 69.161245 -285.30849) (xy 69.184802 -285.37581) (xy 69.200672 -285.445345)
			(xy 69.208658 -285.516219) (xy 69.208658 -285.551219) (xy 70.234802 -285.551219) (xy 70.234802 -285.479897)
			(xy 70.242788 -285.409023) (xy 70.258658 -285.339488) (xy 70.282215 -285.272168) (xy 70.31316 -285.207909)
			(xy 70.351106 -285.147518) (xy 70.395575 -285.091756) (xy 70.446008 -285.041323) (xy 70.50177 -284.996854)
			(xy 70.562161 -284.958908) (xy 70.62642 -284.927963) (xy 70.69374 -284.904406) (xy 70.763275 -284.888536)
			(xy 70.834149 -284.88055) (xy 70.86981 -284.88005) (xy 70.905471 -284.88055) (xy 70.976345 -284.888536)
			(xy 71.04588 -284.904406) (xy 71.1132 -284.927963) (xy 71.177459 -284.958908) (xy 71.23785 -284.996854)
			(xy 71.293612 -285.041323) (xy 71.344045 -285.091756) (xy 71.388514 -285.147518) (xy 71.42646 -285.207909)
			(xy 71.457405 -285.272168) (xy 71.480962 -285.339488) (xy 71.496832 -285.409023) (xy 71.504818 -285.479897)
			(xy 71.504818 -285.515151) (xy 72.609194 -285.515151) (xy 72.609194 -285.443829) (xy 72.61718 -285.372955)
			(xy 72.63305 -285.30342) (xy 72.656607 -285.2361) (xy 72.687552 -285.171841) (xy 72.725498 -285.11145)
			(xy 72.769967 -285.055688) (xy 72.8204 -285.005255) (xy 72.876162 -284.960786) (xy 72.936553 -284.92284)
			(xy 73.000812 -284.891895) (xy 73.068132 -284.868338) (xy 73.137667 -284.852468) (xy 73.208541 -284.844482)
			(xy 73.244202 -284.843982) (xy 73.279863 -284.844482) (xy 73.350737 -284.852468) (xy 73.420272 -284.868338)
			(xy 73.487592 -284.891895) (xy 73.551851 -284.92284) (xy 73.612242 -284.960786) (xy 73.668004 -285.005255)
			(xy 73.718437 -285.055688) (xy 73.762906 -285.11145) (xy 73.800852 -285.171841) (xy 73.831797 -285.2361)
			(xy 73.855354 -285.30342) (xy 73.871224 -285.372955) (xy 73.87921 -285.443829) (xy 73.87921 -285.515151)
			(xy 73.871224 -285.586025) (xy 73.855354 -285.65556) (xy 73.831797 -285.72288) (xy 73.800852 -285.787139)
			(xy 73.762906 -285.84753) (xy 73.718437 -285.903292) (xy 73.668004 -285.953725) (xy 73.612242 -285.998194)
			(xy 73.551851 -286.03614) (xy 73.487592 -286.067085) (xy 73.420272 -286.090642) (xy 73.350737 -286.106512)
			(xy 73.279863 -286.114498) (xy 73.208541 -286.114498) (xy 73.137667 -286.106512) (xy 73.068132 -286.090642)
			(xy 73.000812 -286.067085) (xy 72.936553 -286.03614) (xy 72.876162 -285.998194) (xy 72.8204 -285.953725)
			(xy 72.769967 -285.903292) (xy 72.725498 -285.84753) (xy 72.687552 -285.787139) (xy 72.656607 -285.72288)
			(xy 72.63305 -285.65556) (xy 72.61718 -285.586025) (xy 72.609194 -285.515151) (xy 71.504818 -285.515151)
			(xy 71.504818 -285.551219) (xy 71.496832 -285.622093) (xy 71.480962 -285.691628) (xy 71.457405 -285.758948)
			(xy 71.42646 -285.823207) (xy 71.388514 -285.883598) (xy 71.344045 -285.93936) (xy 71.293612 -285.989793)
			(xy 71.23785 -286.034262) (xy 71.177459 -286.072208) (xy 71.1132 -286.103153) (xy 71.04588 -286.12671)
			(xy 71.042681 -286.12744) (xy 82.488514 -286.12744) (xy 82.488514 -286.067504) (xy 82.496337 -286.008082)
			(xy 82.51185 -285.950189) (xy 82.534786 -285.894816) (xy 82.564753 -285.84291) (xy 82.60124 -285.79536)
			(xy 82.64362 -285.75298) (xy 82.69117 -285.716493) (xy 82.743076 -285.686526) (xy 82.798449 -285.66359)
			(xy 82.856342 -285.648077) (xy 82.915764 -285.640254) (xy 82.945732 -285.639764) (xy 82.9757 -285.640254)
			(xy 83.035122 -285.648077) (xy 83.093015 -285.66359) (xy 83.148388 -285.686526) (xy 83.200294 -285.716493)
			(xy 83.247844 -285.75298) (xy 83.290224 -285.79536) (xy 83.326711 -285.84291) (xy 83.356678 -285.894816)
			(xy 83.379614 -285.950189) (xy 83.395127 -286.008082) (xy 83.40295 -286.067504) (xy 83.40295 -286.12744)
			(xy 83.395127 -286.186862) (xy 83.379614 -286.244755) (xy 83.356678 -286.300128) (xy 83.326711 -286.352034)
			(xy 83.290224 -286.399584) (xy 83.247844 -286.441964) (xy 83.200294 -286.478451) (xy 83.148388 -286.508418)
			(xy 83.093015 -286.531354) (xy 83.035122 -286.546867) (xy 82.9757 -286.55469) (xy 82.915764 -286.55469)
			(xy 82.856342 -286.546867) (xy 82.798449 -286.531354) (xy 82.743076 -286.508418) (xy 82.69117 -286.478451)
			(xy 82.64362 -286.441964) (xy 82.60124 -286.399584) (xy 82.564753 -286.352034) (xy 82.534786 -286.300128)
			(xy 82.51185 -286.244755) (xy 82.496337 -286.186862) (xy 82.488514 -286.12744) (xy 71.042681 -286.12744)
			(xy 70.976345 -286.14258) (xy 70.905471 -286.150566) (xy 70.834149 -286.150566) (xy 70.763275 -286.14258)
			(xy 70.69374 -286.12671) (xy 70.62642 -286.103153) (xy 70.562161 -286.072208) (xy 70.50177 -286.034262)
			(xy 70.446008 -285.989793) (xy 70.395575 -285.93936) (xy 70.351106 -285.883598) (xy 70.31316 -285.823207)
			(xy 70.282215 -285.758948) (xy 70.258658 -285.691628) (xy 70.242788 -285.622093) (xy 70.234802 -285.551219)
			(xy 69.208658 -285.551219) (xy 69.208658 -285.587541) (xy 69.200672 -285.658415) (xy 69.184802 -285.72795)
			(xy 69.161245 -285.79527) (xy 69.1303 -285.859529) (xy 69.092354 -285.91992) (xy 69.047885 -285.975682)
			(xy 68.997452 -286.026115) (xy 68.94169 -286.070584) (xy 68.881299 -286.10853) (xy 68.81704 -286.139475)
			(xy 68.74972 -286.163032) (xy 68.680185 -286.178902) (xy 68.609311 -286.186888) (xy 68.537989 -286.186888)
			(xy 68.467115 -286.178902) (xy 68.39758 -286.163032) (xy 68.33026 -286.139475) (xy 68.266001 -286.10853)
			(xy 68.20561 -286.070584) (xy 68.149848 -286.026115) (xy 68.099415 -285.975682) (xy 68.054946 -285.91992)
			(xy 68.017 -285.859529) (xy 67.986055 -285.79527) (xy 67.962498 -285.72795) (xy 67.946628 -285.658415)
			(xy 67.938642 -285.587541) (xy 66.984634 -285.587541) (xy 66.984634 -285.624117) (xy 66.976648 -285.694991)
			(xy 66.960778 -285.764526) (xy 66.937221 -285.831846) (xy 66.906276 -285.896105) (xy 66.86833 -285.956496)
			(xy 66.823861 -286.012258) (xy 66.773428 -286.062691) (xy 66.717666 -286.10716) (xy 66.657275 -286.145106)
			(xy 66.593016 -286.176051) (xy 66.525696 -286.199608) (xy 66.456161 -286.215478) (xy 66.385287 -286.223464)
			(xy 66.313965 -286.223464) (xy 66.243091 -286.215478) (xy 66.173556 -286.199608) (xy 66.106236 -286.176051)
			(xy 66.041977 -286.145106) (xy 65.981586 -286.10716) (xy 65.925824 -286.062691) (xy 65.875391 -286.012258)
			(xy 65.830922 -285.956496) (xy 65.792976 -285.896105) (xy 65.762031 -285.831846) (xy 65.738474 -285.764526)
			(xy 65.722604 -285.694991) (xy 65.714618 -285.624117) (xy 64.452762 -285.624117) (xy 64.444776 -285.694991)
			(xy 64.428906 -285.764526) (xy 64.405349 -285.831846) (xy 64.374404 -285.896105) (xy 64.336458 -285.956496)
			(xy 64.291989 -286.012258) (xy 64.241556 -286.062691) (xy 64.185794 -286.10716) (xy 64.125403 -286.145106)
			(xy 64.061144 -286.176051) (xy 63.993824 -286.199608) (xy 63.924289 -286.215478) (xy 63.853415 -286.223464)
			(xy 63.782093 -286.223464) (xy 63.711219 -286.215478) (xy 63.641684 -286.199608) (xy 63.574364 -286.176051)
			(xy 63.510105 -286.145106) (xy 63.449714 -286.10716) (xy 63.393952 -286.062691) (xy 63.343519 -286.012258)
			(xy 63.29905 -285.956496) (xy 63.261104 -285.896105) (xy 63.230159 -285.831846) (xy 63.206602 -285.764526)
			(xy 63.190732 -285.694991) (xy 63.182746 -285.624117) (xy 52.903628 -285.624117) (xy 52.903628 -286.031432)
			(xy 51.251612 -286.031432) (xy 51.251612 -284.379416) (xy 44.260008 -284.379416) (xy 44.260008 -286.760411)
			(xy 86.399122 -286.760411) (xy 86.401115 -286.560283) (xy 86.411112 -286.360394) (xy 86.429099 -286.161066)
			(xy 86.455047 -285.962617) (xy 86.488914 -285.765365) (xy 86.530646 -285.569626) (xy 86.580175 -285.375713)
			(xy 86.637424 -285.183938) (xy 86.702299 -284.994606) (xy 86.774698 -284.808022) (xy 86.854504 -284.624483)
			(xy 86.941589 -284.444285) (xy 87.035814 -284.267715) (xy 87.137028 -284.095056) (xy 87.245069 -283.926586)
			(xy 87.359764 -283.762572) (xy 87.48093 -283.603279) (xy 87.608371 -283.448962) (xy 87.741885 -283.299866)
			(xy 87.881257 -283.156232) (xy 88.026264 -283.01829) (xy 88.176675 -282.886259) (xy 88.332247 -282.760352)
			(xy 88.492732 -282.64077) (xy 88.657873 -282.527705) (xy 88.827405 -282.421337) (xy 89.001058 -282.321838)
			(xy 89.178552 -282.229366) (xy 89.359604 -282.14407) (xy 89.543924 -282.066086) (xy 89.731216 -281.995538)
			(xy 89.921181 -281.932541) (xy 90.113514 -281.877195) (xy 90.307908 -281.829588) (xy 90.504051 -281.789797)
			(xy 90.701628 -281.757885) (xy 90.900325 -281.733904) (xy 91.099821 -281.717891) (xy 91.299799 -281.709874)
			(xy 91.399868 -281.709368) (xy 91.499937 -281.709864) (xy 91.699915 -281.717861) (xy 91.899414 -281.733853)
			(xy 92.098112 -281.757814) (xy 92.295693 -281.789706) (xy 92.49184 -281.829477) (xy 92.686239 -281.877064)
			(xy 92.878578 -281.932391) (xy 93.068549 -281.995369) (xy 93.255848 -282.065897) (xy 93.440176 -282.143863)
			(xy 93.621237 -282.229141) (xy 93.79874 -282.321594) (xy 93.972403 -282.421076) (xy 94.141946 -282.527426)
			(xy 94.307099 -282.640475) (xy 94.467596 -282.76004) (xy 94.623181 -282.885932) (xy 94.773605 -283.017947)
			(xy 94.918626 -283.155875) (xy 95.058012 -283.299495) (xy 95.191541 -283.448576) (xy 95.318999 -283.602881)
			(xy 95.44018 -283.762162) (xy 95.554892 -283.926163) (xy 95.66295 -284.094623) (xy 95.764182 -284.267272)
			(xy 95.858425 -284.443832) (xy 95.945528 -284.624022) (xy 96.025353 -284.807552) (xy 96.09777 -284.994129)
			(xy 96.162665 -285.183454) (xy 96.219933 -285.375224) (xy 96.269483 -285.569131) (xy 96.311234 -285.764866)
			(xy 96.345121 -285.962115) (xy 96.371089 -286.160561) (xy 96.389096 -286.359888) (xy 96.399114 -286.559775)
			(xy 96.401127 -286.759903) (xy 96.395131 -286.959951) (xy 96.381135 -287.1596) (xy 96.359164 -287.358528)
			(xy 96.32925 -287.556418) (xy 96.291443 -287.752953) (xy 96.245804 -287.947818) (xy 96.192404 -288.140701)
			(xy 96.13133 -288.331293) (xy 96.062679 -288.519288) (xy 95.986561 -288.704387) (xy 95.903099 -288.886292)
			(xy 95.812426 -289.064711) (xy 95.714687 -289.239361) (xy 95.610038 -289.40996) (xy 95.498648 -289.576235)
			(xy 95.380694 -289.73792) (xy 95.256365 -289.894757) (xy 95.125862 -290.046494) (xy 94.989391 -290.192888)
			(xy 94.847173 -290.333704) (xy 94.699435 -290.468718) (xy 94.546413 -290.597713) (xy 94.388353 -290.720482)
			(xy 94.225507 -290.836829) (xy 94.058137 -290.946567) (xy 93.88651 -291.049521) (xy 93.710902 -291.145526)
			(xy 93.531592 -291.234428) (xy 93.34887 -291.316084) (xy 93.163027 -291.390365) (xy 92.97436 -291.457151)
			(xy 92.783173 -291.516334) (xy 92.589771 -291.567821) (xy 92.394464 -291.611529) (xy 92.197564 -291.647388)
			(xy 91.999387 -291.67534) (xy 91.800251 -291.69534) (xy 91.600474 -291.707358) (xy 91.400376 -291.711372)
			(xy 91.200278 -291.707378) (xy 91.000499 -291.695381) (xy 90.801361 -291.675401) (xy 90.603182 -291.647469)
			(xy 90.406278 -291.61163) (xy 90.210967 -291.567942) (xy 90.017559 -291.516475) (xy 89.826366 -291.457311)
			(xy 89.637693 -291.390544) (xy 89.451842 -291.316282) (xy 89.269111 -291.234644) (xy 89.089793 -291.145761)
			(xy 88.914175 -291.049774) (xy 88.742537 -290.946837) (xy 88.575156 -290.837116) (xy 88.412298 -290.720785)
			(xy 88.254226 -290.598032) (xy 88.101191 -290.469053) (xy 87.953439 -290.334055) (xy 87.811206 -290.193252)
			(xy 87.674721 -290.046872) (xy 87.544202 -289.895149) (xy 87.419858 -289.738325) (xy 87.301888 -289.576651)
			(xy 87.19048 -289.410387) (xy 87.085814 -289.239799) (xy 86.988057 -289.06516) (xy 86.897366 -288.886749)
			(xy 86.813885 -288.704853) (xy 86.737749 -288.519762) (xy 86.669079 -288.331773) (xy 86.607986 -288.141188)
			(xy 86.554566 -287.94831) (xy 86.508906 -287.75345) (xy 86.47108 -287.556919) (xy 86.441146 -287.359032)
			(xy 86.419154 -287.160106) (xy 86.405139 -286.960459) (xy 86.399122 -286.760411) (xy 44.260008 -286.760411)
			(xy 44.260008 -287.651698) (xy 43.616755 -288.294927) (xy 63.182746 -288.294927) (xy 63.182746 -288.223605)
			(xy 63.190732 -288.152731) (xy 63.206602 -288.083196) (xy 63.230159 -288.015876) (xy 63.261104 -287.951617)
			(xy 63.29905 -287.891226) (xy 63.343519 -287.835464) (xy 63.393952 -287.785031) (xy 63.449714 -287.740562)
			(xy 63.510105 -287.702616) (xy 63.574364 -287.671671) (xy 63.641684 -287.648114) (xy 63.711219 -287.632244)
			(xy 63.782093 -287.624258) (xy 63.817754 -287.623758) (xy 63.853415 -287.624258) (xy 63.924289 -287.632244)
			(xy 63.993824 -287.648114) (xy 64.061144 -287.671671) (xy 64.125403 -287.702616) (xy 64.185794 -287.740562)
			(xy 64.241556 -287.785031) (xy 64.291989 -287.835464) (xy 64.336458 -287.891226) (xy 64.374404 -287.951617)
			(xy 64.405349 -288.015876) (xy 64.428906 -288.083196) (xy 64.444776 -288.152731) (xy 64.452762 -288.223605)
			(xy 64.452762 -288.294927) (xy 65.714618 -288.294927) (xy 65.714618 -288.223605) (xy 65.722604 -288.152731)
			(xy 65.738474 -288.083196) (xy 65.762031 -288.015876) (xy 65.792976 -287.951617) (xy 65.830922 -287.891226)
			(xy 65.875391 -287.835464) (xy 65.925824 -287.785031) (xy 65.981586 -287.740562) (xy 66.041977 -287.702616)
			(xy 66.106236 -287.671671) (xy 66.173556 -287.648114) (xy 66.243091 -287.632244) (xy 66.313965 -287.624258)
			(xy 66.349626 -287.623758) (xy 66.385287 -287.624258) (xy 66.456161 -287.632244) (xy 66.525696 -287.648114)
			(xy 66.593016 -287.671671) (xy 66.657275 -287.702616) (xy 66.717666 -287.740562) (xy 66.773428 -287.785031)
			(xy 66.823861 -287.835464) (xy 66.86833 -287.891226) (xy 66.906276 -287.951617) (xy 66.937221 -288.015876)
			(xy 66.960778 -288.083196) (xy 66.976648 -288.152731) (xy 66.984634 -288.223605) (xy 66.984634 -288.258351)
			(xy 67.938642 -288.258351) (xy 67.938642 -288.187029) (xy 67.946628 -288.116155) (xy 67.962498 -288.04662)
			(xy 67.986055 -287.9793) (xy 68.017 -287.915041) (xy 68.054946 -287.85465) (xy 68.099415 -287.798888)
			(xy 68.149848 -287.748455) (xy 68.20561 -287.703986) (xy 68.266001 -287.66604) (xy 68.33026 -287.635095)
			(xy 68.39758 -287.611538) (xy 68.467115 -287.595668) (xy 68.537989 -287.587682) (xy 68.57365 -287.587182)
			(xy 68.609311 -287.587682) (xy 68.680185 -287.595668) (xy 68.74972 -287.611538) (xy 68.81704 -287.635095)
			(xy 68.881299 -287.66604) (xy 68.94169 -287.703986) (xy 68.997452 -287.748455) (xy 69.047885 -287.798888)
			(xy 69.092354 -287.85465) (xy 69.1303 -287.915041) (xy 69.161245 -287.9793) (xy 69.184802 -288.04662)
			(xy 69.200672 -288.116155) (xy 69.208658 -288.187029) (xy 69.208658 -288.222029) (xy 70.234802 -288.222029)
			(xy 70.234802 -288.150707) (xy 70.242788 -288.079833) (xy 70.258658 -288.010298) (xy 70.282215 -287.942978)
			(xy 70.31316 -287.878719) (xy 70.351106 -287.818328) (xy 70.395575 -287.762566) (xy 70.446008 -287.712133)
			(xy 70.50177 -287.667664) (xy 70.562161 -287.629718) (xy 70.62642 -287.598773) (xy 70.69374 -287.575216)
			(xy 70.763275 -287.559346) (xy 70.834149 -287.55136) (xy 70.86981 -287.55086) (xy 70.905471 -287.55136)
			(xy 70.976345 -287.559346) (xy 71.04588 -287.575216) (xy 71.1132 -287.598773) (xy 71.177459 -287.629718)
			(xy 71.23785 -287.667664) (xy 71.293612 -287.712133) (xy 71.344045 -287.762566) (xy 71.388514 -287.818328)
			(xy 71.42646 -287.878719) (xy 71.457405 -287.942978) (xy 71.480962 -288.010298) (xy 71.496832 -288.079833)
			(xy 71.504818 -288.150707) (xy 71.504818 -288.185961) (xy 72.609194 -288.185961) (xy 72.609194 -288.114639)
			(xy 72.61718 -288.043765) (xy 72.63305 -287.97423) (xy 72.656607 -287.90691) (xy 72.687552 -287.842651)
			(xy 72.725498 -287.78226) (xy 72.769967 -287.726498) (xy 72.8204 -287.676065) (xy 72.876162 -287.631596)
			(xy 72.936553 -287.59365) (xy 73.000812 -287.562705) (xy 73.068132 -287.539148) (xy 73.137667 -287.523278)
			(xy 73.208541 -287.515292) (xy 73.244202 -287.514792) (xy 73.279863 -287.515292) (xy 73.350737 -287.523278)
			(xy 73.420272 -287.539148) (xy 73.487592 -287.562705) (xy 73.551851 -287.59365) (xy 73.612242 -287.631596)
			(xy 73.668004 -287.676065) (xy 73.718437 -287.726498) (xy 73.762906 -287.78226) (xy 73.800852 -287.842651)
			(xy 73.831797 -287.90691) (xy 73.855354 -287.97423) (xy 73.871224 -288.043765) (xy 73.87921 -288.114639)
			(xy 73.87921 -288.185961) (xy 73.871224 -288.256835) (xy 73.855354 -288.32637) (xy 73.831797 -288.39369)
			(xy 73.800852 -288.457949) (xy 73.762906 -288.51834) (xy 73.718437 -288.574102) (xy 73.668004 -288.624535)
			(xy 73.612242 -288.669004) (xy 73.551851 -288.70695) (xy 73.487592 -288.737895) (xy 73.420272 -288.761452)
			(xy 73.350737 -288.777322) (xy 73.279863 -288.785308) (xy 73.208541 -288.785308) (xy 73.137667 -288.777322)
			(xy 73.068132 -288.761452) (xy 73.000812 -288.737895) (xy 72.936553 -288.70695) (xy 72.876162 -288.669004)
			(xy 72.8204 -288.624535) (xy 72.769967 -288.574102) (xy 72.725498 -288.51834) (xy 72.687552 -288.457949)
			(xy 72.656607 -288.39369) (xy 72.63305 -288.32637) (xy 72.61718 -288.256835) (xy 72.609194 -288.185961)
			(xy 71.504818 -288.185961) (xy 71.504818 -288.222029) (xy 71.496832 -288.292903) (xy 71.480962 -288.362438)
			(xy 71.457405 -288.429758) (xy 71.42646 -288.494017) (xy 71.388514 -288.554408) (xy 71.344045 -288.61017)
			(xy 71.293612 -288.660603) (xy 71.23785 -288.705072) (xy 71.177459 -288.743018) (xy 71.1132 -288.773963)
			(xy 71.04588 -288.79752) (xy 70.976345 -288.81339) (xy 70.905471 -288.821376) (xy 70.834149 -288.821376)
			(xy 70.763275 -288.81339) (xy 70.69374 -288.79752) (xy 70.62642 -288.773963) (xy 70.562161 -288.743018)
			(xy 70.50177 -288.705072) (xy 70.446008 -288.660603) (xy 70.395575 -288.61017) (xy 70.351106 -288.554408)
			(xy 70.31316 -288.494017) (xy 70.282215 -288.429758) (xy 70.258658 -288.362438) (xy 70.242788 -288.292903)
			(xy 70.234802 -288.222029) (xy 69.208658 -288.222029) (xy 69.208658 -288.258351) (xy 69.200672 -288.329225)
			(xy 69.184802 -288.39876) (xy 69.161245 -288.46608) (xy 69.1303 -288.530339) (xy 69.092354 -288.59073)
			(xy 69.047885 -288.646492) (xy 68.997452 -288.696925) (xy 68.94169 -288.741394) (xy 68.881299 -288.77934)
			(xy 68.81704 -288.810285) (xy 68.74972 -288.833842) (xy 68.680185 -288.849712) (xy 68.609311 -288.857698)
			(xy 68.537989 -288.857698) (xy 68.467115 -288.849712) (xy 68.39758 -288.833842) (xy 68.33026 -288.810285)
			(xy 68.266001 -288.77934) (xy 68.20561 -288.741394) (xy 68.149848 -288.696925) (xy 68.099415 -288.646492)
			(xy 68.054946 -288.59073) (xy 68.017 -288.530339) (xy 67.986055 -288.46608) (xy 67.962498 -288.39876)
			(xy 67.946628 -288.329225) (xy 67.938642 -288.258351) (xy 66.984634 -288.258351) (xy 66.984634 -288.294927)
			(xy 66.976648 -288.365801) (xy 66.960778 -288.435336) (xy 66.937221 -288.502656) (xy 66.906276 -288.566915)
			(xy 66.86833 -288.627306) (xy 66.823861 -288.683068) (xy 66.773428 -288.733501) (xy 66.717666 -288.77797)
			(xy 66.657275 -288.815916) (xy 66.593016 -288.846861) (xy 66.525696 -288.870418) (xy 66.456161 -288.886288)
			(xy 66.385287 -288.894274) (xy 66.313965 -288.894274) (xy 66.243091 -288.886288) (xy 66.173556 -288.870418)
			(xy 66.106236 -288.846861) (xy 66.041977 -288.815916) (xy 65.981586 -288.77797) (xy 65.925824 -288.733501)
			(xy 65.875391 -288.683068) (xy 65.830922 -288.627306) (xy 65.792976 -288.566915) (xy 65.762031 -288.502656)
			(xy 65.738474 -288.435336) (xy 65.722604 -288.365801) (xy 65.714618 -288.294927) (xy 64.452762 -288.294927)
			(xy 64.444776 -288.365801) (xy 64.428906 -288.435336) (xy 64.405349 -288.502656) (xy 64.374404 -288.566915)
			(xy 64.336458 -288.627306) (xy 64.291989 -288.683068) (xy 64.241556 -288.733501) (xy 64.185794 -288.77797)
			(xy 64.125403 -288.815916) (xy 64.061144 -288.846861) (xy 63.993824 -288.870418) (xy 63.924289 -288.886288)
			(xy 63.853415 -288.894274) (xy 63.782093 -288.894274) (xy 63.711219 -288.886288) (xy 63.641684 -288.870418)
			(xy 63.574364 -288.846861) (xy 63.510105 -288.815916) (xy 63.449714 -288.77797) (xy 63.393952 -288.733501)
			(xy 63.343519 -288.683068) (xy 63.29905 -288.627306) (xy 63.261104 -288.566915) (xy 63.230159 -288.502656)
			(xy 63.206602 -288.435336) (xy 63.190732 -288.365801) (xy 63.182746 -288.294927) (xy 43.616755 -288.294927)
			(xy 40.948384 -290.963197) (xy 63.182746 -290.963197) (xy 63.182746 -290.891875) (xy 63.190732 -290.821001)
			(xy 63.206602 -290.751466) (xy 63.230159 -290.684146) (xy 63.261104 -290.619887) (xy 63.29905 -290.559496)
			(xy 63.343519 -290.503734) (xy 63.393952 -290.453301) (xy 63.449714 -290.408832) (xy 63.510105 -290.370886)
			(xy 63.574364 -290.339941) (xy 63.641684 -290.316384) (xy 63.711219 -290.300514) (xy 63.782093 -290.292528)
			(xy 63.817754 -290.292028) (xy 63.853415 -290.292528) (xy 63.924289 -290.300514) (xy 63.993824 -290.316384)
			(xy 64.061144 -290.339941) (xy 64.125403 -290.370886) (xy 64.185794 -290.408832) (xy 64.241556 -290.453301)
			(xy 64.291989 -290.503734) (xy 64.336458 -290.559496) (xy 64.374404 -290.619887) (xy 64.405349 -290.684146)
			(xy 64.428906 -290.751466) (xy 64.444776 -290.821001) (xy 64.452762 -290.891875) (xy 64.452762 -290.963197)
			(xy 65.714618 -290.963197) (xy 65.714618 -290.891875) (xy 65.722604 -290.821001) (xy 65.738474 -290.751466)
			(xy 65.762031 -290.684146) (xy 65.792976 -290.619887) (xy 65.830922 -290.559496) (xy 65.875391 -290.503734)
			(xy 65.925824 -290.453301) (xy 65.981586 -290.408832) (xy 66.041977 -290.370886) (xy 66.106236 -290.339941)
			(xy 66.173556 -290.316384) (xy 66.243091 -290.300514) (xy 66.313965 -290.292528) (xy 66.349626 -290.292028)
			(xy 66.385287 -290.292528) (xy 66.456161 -290.300514) (xy 66.525696 -290.316384) (xy 66.593016 -290.339941)
			(xy 66.657275 -290.370886) (xy 66.717666 -290.408832) (xy 66.773428 -290.453301) (xy 66.823861 -290.503734)
			(xy 66.86833 -290.559496) (xy 66.906276 -290.619887) (xy 66.937221 -290.684146) (xy 66.960778 -290.751466)
			(xy 66.976648 -290.821001) (xy 66.984634 -290.891875) (xy 66.984634 -290.926621) (xy 67.938642 -290.926621)
			(xy 67.938642 -290.855299) (xy 67.946628 -290.784425) (xy 67.962498 -290.71489) (xy 67.986055 -290.64757)
			(xy 68.017 -290.583311) (xy 68.054946 -290.52292) (xy 68.099415 -290.467158) (xy 68.149848 -290.416725)
			(xy 68.20561 -290.372256) (xy 68.266001 -290.33431) (xy 68.33026 -290.303365) (xy 68.39758 -290.279808)
			(xy 68.467115 -290.263938) (xy 68.537989 -290.255952) (xy 68.57365 -290.255452) (xy 68.609311 -290.255952)
			(xy 68.680185 -290.263938) (xy 68.74972 -290.279808) (xy 68.81704 -290.303365) (xy 68.881299 -290.33431)
			(xy 68.94169 -290.372256) (xy 68.997452 -290.416725) (xy 69.047885 -290.467158) (xy 69.092354 -290.52292)
			(xy 69.1303 -290.583311) (xy 69.161245 -290.64757) (xy 69.184802 -290.71489) (xy 69.200672 -290.784425)
			(xy 69.208658 -290.855299) (xy 69.208658 -290.890299) (xy 70.234802 -290.890299) (xy 70.234802 -290.818977)
			(xy 70.242788 -290.748103) (xy 70.258658 -290.678568) (xy 70.282215 -290.611248) (xy 70.31316 -290.546989)
			(xy 70.351106 -290.486598) (xy 70.395575 -290.430836) (xy 70.446008 -290.380403) (xy 70.50177 -290.335934)
			(xy 70.562161 -290.297988) (xy 70.62642 -290.267043) (xy 70.69374 -290.243486) (xy 70.763275 -290.227616)
			(xy 70.834149 -290.21963) (xy 70.86981 -290.21913) (xy 70.905471 -290.21963) (xy 70.976345 -290.227616)
			(xy 71.04588 -290.243486) (xy 71.1132 -290.267043) (xy 71.177459 -290.297988) (xy 71.23785 -290.335934)
			(xy 71.293612 -290.380403) (xy 71.344045 -290.430836) (xy 71.388514 -290.486598) (xy 71.42646 -290.546989)
			(xy 71.457405 -290.611248) (xy 71.480962 -290.678568) (xy 71.496832 -290.748103) (xy 71.504818 -290.818977)
			(xy 71.504818 -290.854231) (xy 72.609194 -290.854231) (xy 72.609194 -290.782909) (xy 72.61718 -290.712035)
			(xy 72.63305 -290.6425) (xy 72.656607 -290.57518) (xy 72.687552 -290.510921) (xy 72.725498 -290.45053)
			(xy 72.769967 -290.394768) (xy 72.8204 -290.344335) (xy 72.876162 -290.299866) (xy 72.936553 -290.26192)
			(xy 73.000812 -290.230975) (xy 73.068132 -290.207418) (xy 73.137667 -290.191548) (xy 73.208541 -290.183562)
			(xy 73.244202 -290.183062) (xy 73.279863 -290.183562) (xy 73.350737 -290.191548) (xy 73.420272 -290.207418)
			(xy 73.487592 -290.230975) (xy 73.551851 -290.26192) (xy 73.612242 -290.299866) (xy 73.668004 -290.344335)
			(xy 73.718437 -290.394768) (xy 73.762906 -290.45053) (xy 73.800852 -290.510921) (xy 73.831797 -290.57518)
			(xy 73.855354 -290.6425) (xy 73.871224 -290.712035) (xy 73.87921 -290.782909) (xy 73.87921 -290.854231)
			(xy 73.871224 -290.925105) (xy 73.855354 -290.99464) (xy 73.831797 -291.06196) (xy 73.800852 -291.126219)
			(xy 73.762906 -291.18661) (xy 73.718437 -291.242372) (xy 73.668004 -291.292805) (xy 73.612242 -291.337274)
			(xy 73.551851 -291.37522) (xy 73.487592 -291.406165) (xy 73.420272 -291.429722) (xy 73.350737 -291.445592)
			(xy 73.279863 -291.453578) (xy 73.208541 -291.453578) (xy 73.137667 -291.445592) (xy 73.068132 -291.429722)
			(xy 73.000812 -291.406165) (xy 72.936553 -291.37522) (xy 72.876162 -291.337274) (xy 72.8204 -291.292805)
			(xy 72.769967 -291.242372) (xy 72.725498 -291.18661) (xy 72.687552 -291.126219) (xy 72.656607 -291.06196)
			(xy 72.63305 -290.99464) (xy 72.61718 -290.925105) (xy 72.609194 -290.854231) (xy 71.504818 -290.854231)
			(xy 71.504818 -290.890299) (xy 71.496832 -290.961173) (xy 71.480962 -291.030708) (xy 71.457405 -291.098028)
			(xy 71.42646 -291.162287) (xy 71.388514 -291.222678) (xy 71.344045 -291.27844) (xy 71.293612 -291.328873)
			(xy 71.23785 -291.373342) (xy 71.177459 -291.411288) (xy 71.1132 -291.442233) (xy 71.04588 -291.46579)
			(xy 70.976345 -291.48166) (xy 70.905471 -291.489646) (xy 70.834149 -291.489646) (xy 70.763275 -291.48166)
			(xy 70.69374 -291.46579) (xy 70.62642 -291.442233) (xy 70.562161 -291.411288) (xy 70.50177 -291.373342)
			(xy 70.446008 -291.328873) (xy 70.395575 -291.27844) (xy 70.351106 -291.222678) (xy 70.31316 -291.162287)
			(xy 70.282215 -291.098028) (xy 70.258658 -291.030708) (xy 70.242788 -290.961173) (xy 70.234802 -290.890299)
			(xy 69.208658 -290.890299) (xy 69.208658 -290.926621) (xy 69.200672 -290.997495) (xy 69.184802 -291.06703)
			(xy 69.161245 -291.13435) (xy 69.1303 -291.198609) (xy 69.092354 -291.259) (xy 69.047885 -291.314762)
			(xy 68.997452 -291.365195) (xy 68.94169 -291.409664) (xy 68.881299 -291.44761) (xy 68.81704 -291.478555)
			(xy 68.74972 -291.502112) (xy 68.680185 -291.517982) (xy 68.609311 -291.525968) (xy 68.537989 -291.525968)
			(xy 68.467115 -291.517982) (xy 68.39758 -291.502112) (xy 68.33026 -291.478555) (xy 68.266001 -291.44761)
			(xy 68.20561 -291.409664) (xy 68.149848 -291.365195) (xy 68.099415 -291.314762) (xy 68.054946 -291.259)
			(xy 68.017 -291.198609) (xy 67.986055 -291.13435) (xy 67.962498 -291.06703) (xy 67.946628 -290.997495)
			(xy 67.938642 -290.926621) (xy 66.984634 -290.926621) (xy 66.984634 -290.963197) (xy 66.976648 -291.034071)
			(xy 66.960778 -291.103606) (xy 66.937221 -291.170926) (xy 66.906276 -291.235185) (xy 66.86833 -291.295576)
			(xy 66.823861 -291.351338) (xy 66.773428 -291.401771) (xy 66.717666 -291.44624) (xy 66.657275 -291.484186)
			(xy 66.593016 -291.515131) (xy 66.525696 -291.538688) (xy 66.456161 -291.554558) (xy 66.385287 -291.562544)
			(xy 66.313965 -291.562544) (xy 66.243091 -291.554558) (xy 66.173556 -291.538688) (xy 66.106236 -291.515131)
			(xy 66.041977 -291.484186) (xy 65.981586 -291.44624) (xy 65.925824 -291.401771) (xy 65.875391 -291.351338)
			(xy 65.830922 -291.295576) (xy 65.792976 -291.235185) (xy 65.762031 -291.170926) (xy 65.738474 -291.103606)
			(xy 65.722604 -291.034071) (xy 65.714618 -290.963197) (xy 64.452762 -290.963197) (xy 64.444776 -291.034071)
			(xy 64.428906 -291.103606) (xy 64.405349 -291.170926) (xy 64.374404 -291.235185) (xy 64.336458 -291.295576)
			(xy 64.291989 -291.351338) (xy 64.241556 -291.401771) (xy 64.185794 -291.44624) (xy 64.125403 -291.484186)
			(xy 64.061144 -291.515131) (xy 63.993824 -291.538688) (xy 63.924289 -291.554558) (xy 63.853415 -291.562544)
			(xy 63.782093 -291.562544) (xy 63.711219 -291.554558) (xy 63.641684 -291.538688) (xy 63.574364 -291.515131)
			(xy 63.510105 -291.484186) (xy 63.449714 -291.44624) (xy 63.393952 -291.401771) (xy 63.343519 -291.351338)
			(xy 63.29905 -291.295576) (xy 63.261104 -291.235185) (xy 63.230159 -291.170926) (xy 63.206602 -291.103606)
			(xy 63.190732 -291.034071) (xy 63.182746 -290.963197) (xy 40.948384 -290.963197) (xy 37.542724 -294.368728)
			(xy 30.081982 -294.368728) (xy 29.294836 -295.156128) (xy 29.294836 -295.245532) (xy 78.92464 -295.245532)
			(xy 78.92464 -295.185596) (xy 78.932463 -295.126174) (xy 78.947976 -295.068281) (xy 78.970912 -295.012908)
			(xy 79.000879 -294.961002) (xy 79.037366 -294.913452) (xy 79.079746 -294.871072) (xy 79.127296 -294.834585)
			(xy 79.179202 -294.804618) (xy 79.234575 -294.781682) (xy 79.292468 -294.766169) (xy 79.35189 -294.758346)
			(xy 79.381858 -294.757856) (xy 79.411826 -294.758346) (xy 79.471248 -294.766169) (xy 79.529141 -294.781682)
			(xy 79.584514 -294.804618) (xy 79.63642 -294.834585) (xy 79.68397 -294.871072) (xy 79.72635 -294.913452)
			(xy 79.762837 -294.961002) (xy 79.792804 -295.012908) (xy 79.81574 -295.068281) (xy 79.831253 -295.126174)
			(xy 79.839076 -295.185596) (xy 79.839076 -295.245532) (xy 79.831253 -295.304954) (xy 79.81574 -295.362847)
			(xy 79.792804 -295.41822) (xy 79.762837 -295.470126) (xy 79.72635 -295.517676) (xy 79.68397 -295.560056)
			(xy 79.63642 -295.596543) (xy 79.584514 -295.62651) (xy 79.529141 -295.649446) (xy 79.471248 -295.664959)
			(xy 79.411826 -295.672782) (xy 79.35189 -295.672782) (xy 79.292468 -295.664959) (xy 79.234575 -295.649446)
			(xy 79.179202 -295.62651) (xy 79.127296 -295.596543) (xy 79.079746 -295.560056) (xy 79.037366 -295.517676)
			(xy 79.000879 -295.470126) (xy 78.970912 -295.41822) (xy 78.947976 -295.362847) (xy 78.932463 -295.304954)
			(xy 78.92464 -295.245532) (xy 29.294836 -295.245532) (xy 29.294836 -297.922184) (xy 78.968074 -297.922184)
			(xy 78.968074 -297.862248) (xy 78.975897 -297.802826) (xy 78.99141 -297.744933) (xy 79.014346 -297.68956)
			(xy 79.044313 -297.637654) (xy 79.0808 -297.590104) (xy 79.12318 -297.547724) (xy 79.17073 -297.511237)
			(xy 79.222636 -297.48127) (xy 79.278009 -297.458334) (xy 79.335902 -297.442821) (xy 79.395324 -297.434998)
			(xy 79.425292 -297.434508) (xy 79.45526 -297.434998) (xy 79.514682 -297.442821) (xy 79.572575 -297.458334)
			(xy 79.627948 -297.48127) (xy 79.679854 -297.511237) (xy 79.727404 -297.547724) (xy 79.769784 -297.590104)
			(xy 79.806271 -297.637654) (xy 79.836238 -297.68956) (xy 79.859174 -297.744933) (xy 79.874687 -297.802826)
			(xy 79.88251 -297.862248) (xy 79.88251 -297.878264) (xy 81.762599 -297.878264) (xy 81.768699 -297.822827)
			(xy 81.782805 -297.76887) (xy 81.804617 -297.717541) (xy 81.833671 -297.669935) (xy 81.869346 -297.627067)
			(xy 81.910883 -297.58985) (xy 81.957396 -297.559077) (xy 82.007893 -297.535405) (xy 82.0613 -297.519337)
			(xy 82.116476 -297.511217) (xy 82.144362 -297.510708) (xy 82.172248 -297.511217) (xy 82.227424 -297.519337)
			(xy 82.280831 -297.535405) (xy 82.331328 -297.559077) (xy 82.377841 -297.58985) (xy 82.419378 -297.627067)
			(xy 82.455053 -297.669935) (xy 82.484107 -297.717541) (xy 82.505919 -297.76887) (xy 82.520025 -297.822827)
			(xy 82.526125 -297.878264) (xy 82.524088 -297.933998) (xy 82.513958 -297.988841) (xy 82.495951 -298.041625)
			(xy 82.47045 -298.091225) (xy 82.437999 -298.136583) (xy 82.39929 -298.176732) (xy 82.355147 -298.210818)
			(xy 82.306512 -298.238114) (xy 82.254421 -298.258037) (xy 82.199984 -298.270163) (xy 82.144362 -298.274234)
			(xy 82.08874 -298.270163) (xy 82.034303 -298.258037) (xy 81.982212 -298.238114) (xy 81.933577 -298.210818)
			(xy 81.889434 -298.176732) (xy 81.850725 -298.136583) (xy 81.818274 -298.091225) (xy 81.792773 -298.041625)
			(xy 81.774766 -297.988841) (xy 81.764636 -297.933998) (xy 81.762599 -297.878264) (xy 79.88251 -297.878264)
			(xy 79.88251 -297.922184) (xy 79.874687 -297.981606) (xy 79.859174 -298.039499) (xy 79.836238 -298.094872)
			(xy 79.806271 -298.146778) (xy 79.769784 -298.194328) (xy 79.727404 -298.236708) (xy 79.679854 -298.273195)
			(xy 79.627948 -298.303162) (xy 79.572575 -298.326098) (xy 79.514682 -298.341611) (xy 79.45526 -298.349434)
			(xy 79.395324 -298.349434) (xy 79.335902 -298.341611) (xy 79.278009 -298.326098) (xy 79.222636 -298.303162)
			(xy 79.17073 -298.273195) (xy 79.12318 -298.236708) (xy 79.0808 -298.194328) (xy 79.044313 -298.146778)
			(xy 79.014346 -298.094872) (xy 78.99141 -298.039499) (xy 78.975897 -297.981606) (xy 78.968074 -297.922184)
			(xy 29.294836 -297.922184) (xy 29.294836 -299.709582) (xy 97.794046 -299.709582) (xy 97.794046 -299.649646)
			(xy 97.801869 -299.590224) (xy 97.817382 -299.532331) (xy 97.840318 -299.476958) (xy 97.870285 -299.425052)
			(xy 97.906772 -299.377502) (xy 97.949152 -299.335122) (xy 97.996702 -299.298635) (xy 98.048608 -299.268668)
			(xy 98.103981 -299.245732) (xy 98.161874 -299.230219) (xy 98.221296 -299.222396) (xy 98.251264 -299.221906)
			(xy 98.281232 -299.222396) (xy 98.340654 -299.230219) (xy 98.398547 -299.245732) (xy 98.45392 -299.268668)
			(xy 98.505826 -299.298635) (xy 98.553376 -299.335122) (xy 98.595756 -299.377502) (xy 98.632243 -299.425052)
			(xy 98.66221 -299.476958) (xy 98.685146 -299.532331) (xy 98.700659 -299.590224) (xy 98.708482 -299.649646)
			(xy 98.708482 -299.709582) (xy 98.700659 -299.769004) (xy 98.685146 -299.826897) (xy 98.66221 -299.88227)
			(xy 98.632243 -299.934176) (xy 98.595756 -299.981726) (xy 98.553376 -300.024106) (xy 98.505826 -300.060593)
			(xy 98.45392 -300.09056) (xy 98.398547 -300.113496) (xy 98.340654 -300.129009) (xy 98.281232 -300.136832)
			(xy 98.221296 -300.136832) (xy 98.161874 -300.129009) (xy 98.103981 -300.113496) (xy 98.048608 -300.09056)
			(xy 97.996702 -300.060593) (xy 97.949152 -300.024106) (xy 97.906772 -299.981726) (xy 97.870285 -299.934176)
			(xy 97.840318 -299.88227) (xy 97.817382 -299.826897) (xy 97.801869 -299.769004) (xy 97.794046 -299.709582)
			(xy 29.294836 -299.709582) (xy 29.294836 -300.887231) (xy 70.02322 -300.887231) (xy 70.02322 -300.815909)
			(xy 70.031206 -300.745035) (xy 70.047076 -300.6755) (xy 70.070633 -300.60818) (xy 70.101578 -300.543921)
			(xy 70.139524 -300.48353) (xy 70.183993 -300.427768) (xy 70.234426 -300.377335) (xy 70.290188 -300.332866)
			(xy 70.350579 -300.29492) (xy 70.414838 -300.263975) (xy 70.482158 -300.240418) (xy 70.551693 -300.224548)
			(xy 70.622567 -300.216562) (xy 70.658228 -300.216062) (xy 70.693889 -300.216562) (xy 70.764763 -300.224548)
			(xy 70.834298 -300.240418) (xy 70.901618 -300.263975) (xy 70.965877 -300.29492) (xy 71.026268 -300.332866)
			(xy 71.08203 -300.377335) (xy 71.132463 -300.427768) (xy 71.176932 -300.48353) (xy 71.214878 -300.543921)
			(xy 71.245823 -300.60818) (xy 71.26938 -300.6755) (xy 71.28525 -300.745035) (xy 71.293236 -300.815909)
			(xy 71.293236 -300.850909) (xy 72.192126 -300.850909) (xy 72.192126 -300.779587) (xy 72.200112 -300.708713)
			(xy 72.215982 -300.639178) (xy 72.239539 -300.571858) (xy 72.270484 -300.507599) (xy 72.30843 -300.447208)
			(xy 72.352899 -300.391446) (xy 72.403332 -300.341013) (xy 72.459094 -300.296544) (xy 72.519485 -300.258598)
			(xy 72.583744 -300.227653) (xy 72.651064 -300.204096) (xy 72.720599 -300.188226) (xy 72.791473 -300.18024)
			(xy 72.827134 -300.17974) (xy 72.862795 -300.18024) (xy 72.933669 -300.188226) (xy 73.003204 -300.204096)
			(xy 73.070524 -300.227653) (xy 73.134783 -300.258598) (xy 73.195174 -300.296544) (xy 73.250936 -300.341013)
			(xy 73.301369 -300.391446) (xy 73.345838 -300.447208) (xy 73.383784 -300.507599) (xy 73.414729 -300.571858)
			(xy 73.438286 -300.639178) (xy 73.454156 -300.708713) (xy 73.462142 -300.779587) (xy 73.462142 -300.850909)
			(xy 73.456017 -300.905265) (xy 74.216506 -300.905265) (xy 74.216506 -300.833943) (xy 74.224492 -300.763069)
			(xy 74.240362 -300.693534) (xy 74.263919 -300.626214) (xy 74.294864 -300.561955) (xy 74.33281 -300.501564)
			(xy 74.377279 -300.445802) (xy 74.427712 -300.395369) (xy 74.483474 -300.3509) (xy 74.543865 -300.312954)
			(xy 74.608124 -300.282009) (xy 74.675444 -300.258452) (xy 74.744979 -300.242582) (xy 74.815853 -300.234596)
			(xy 74.851514 -300.234096) (xy 74.887175 -300.234596) (xy 74.958049 -300.242582) (xy 75.027584 -300.258452)
			(xy 75.094904 -300.282009) (xy 75.159163 -300.312954) (xy 75.219554 -300.3509) (xy 75.275316 -300.395369)
			(xy 75.325749 -300.445802) (xy 75.370218 -300.501564) (xy 75.408164 -300.561955) (xy 75.439109 -300.626214)
			(xy 75.462666 -300.693534) (xy 75.478536 -300.763069) (xy 75.486522 -300.833943) (xy 75.486522 -300.905265)
			(xy 76.367378 -300.905265) (xy 76.367378 -300.833943) (xy 76.375364 -300.763069) (xy 76.391234 -300.693534)
			(xy 76.414791 -300.626214) (xy 76.445736 -300.561955) (xy 76.483682 -300.501564) (xy 76.528151 -300.445802)
			(xy 76.578584 -300.395369) (xy 76.634346 -300.3509) (xy 76.694737 -300.312954) (xy 76.758996 -300.282009)
			(xy 76.826316 -300.258452) (xy 76.895851 -300.242582) (xy 76.966725 -300.234596) (xy 77.002386 -300.234096)
			(xy 77.038047 -300.234596) (xy 77.108921 -300.242582) (xy 77.178456 -300.258452) (xy 77.245776 -300.282009)
			(xy 77.310035 -300.312954) (xy 77.370426 -300.3509) (xy 77.426188 -300.395369) (xy 77.476621 -300.445802)
			(xy 77.52109 -300.501564) (xy 77.559036 -300.561955) (xy 77.589981 -300.626214) (xy 77.613538 -300.693534)
			(xy 77.629408 -300.763069) (xy 77.637394 -300.833943) (xy 77.637394 -300.905011) (xy 78.596736 -300.905011)
			(xy 78.596736 -300.833689) (xy 78.604722 -300.762815) (xy 78.620592 -300.69328) (xy 78.644149 -300.62596)
			(xy 78.675094 -300.561701) (xy 78.71304 -300.50131) (xy 78.757509 -300.445548) (xy 78.807942 -300.395115)
			(xy 78.863704 -300.350646) (xy 78.924095 -300.3127) (xy 78.988354 -300.281755) (xy 79.055674 -300.258198)
			(xy 79.125209 -300.242328) (xy 79.196083 -300.234342) (xy 79.231744 -300.233842) (xy 79.267405 -300.234342)
			(xy 79.338279 -300.242328) (xy 79.407814 -300.258198) (xy 79.475134 -300.281755) (xy 79.539393 -300.3127)
			(xy 79.599784 -300.350646) (xy 79.655546 -300.395115) (xy 79.705979 -300.445548) (xy 79.750448 -300.50131)
			(xy 79.788394 -300.561701) (xy 79.819339 -300.62596) (xy 79.842896 -300.69328) (xy 79.858766 -300.762815)
			(xy 79.863014 -300.800512) (xy 96.894886 -300.800512) (xy 96.894886 -300.740576) (xy 96.902709 -300.681154)
			(xy 96.918222 -300.623261) (xy 96.941158 -300.567888) (xy 96.971125 -300.515982) (xy 97.007612 -300.468432)
			(xy 97.049992 -300.426052) (xy 97.097542 -300.389565) (xy 97.149448 -300.359598) (xy 97.204821 -300.336662)
			(xy 97.262714 -300.321149) (xy 97.322136 -300.313326) (xy 97.352104 -300.312836) (xy 97.382072 -300.313326)
			(xy 97.441494 -300.321149) (xy 97.499387 -300.336662) (xy 97.55476 -300.359598) (xy 97.606666 -300.389565)
			(xy 97.654216 -300.426052) (xy 97.696596 -300.468432) (xy 97.733083 -300.515982) (xy 97.76305 -300.567888)
			(xy 97.785986 -300.623261) (xy 97.801499 -300.681154) (xy 97.809322 -300.740576) (xy 97.809322 -300.800512)
			(xy 97.801499 -300.859934) (xy 97.785986 -300.917827) (xy 97.76305 -300.9732) (xy 97.733083 -301.025106)
			(xy 97.696596 -301.072656) (xy 97.654216 -301.115036) (xy 97.606666 -301.151523) (xy 97.55476 -301.18149)
			(xy 97.499387 -301.204426) (xy 97.441494 -301.219939) (xy 97.382072 -301.227762) (xy 97.322136 -301.227762)
			(xy 97.262714 -301.219939) (xy 97.204821 -301.204426) (xy 97.149448 -301.18149) (xy 97.097542 -301.151523)
			(xy 97.049992 -301.115036) (xy 97.007612 -301.072656) (xy 96.971125 -301.025106) (xy 96.941158 -300.9732)
			(xy 96.918222 -300.917827) (xy 96.902709 -300.859934) (xy 96.894886 -300.800512) (xy 79.863014 -300.800512)
			(xy 79.866752 -300.833689) (xy 79.866752 -300.905011) (xy 79.858766 -300.975885) (xy 79.842896 -301.04542)
			(xy 79.819339 -301.11274) (xy 79.788394 -301.176999) (xy 79.750448 -301.23739) (xy 79.705979 -301.293152)
			(xy 79.655546 -301.343585) (xy 79.599784 -301.388054) (xy 79.539393 -301.426) (xy 79.475134 -301.456945)
			(xy 79.407814 -301.480502) (xy 79.338279 -301.496372) (xy 79.267405 -301.504358) (xy 79.196083 -301.504358)
			(xy 79.125209 -301.496372) (xy 79.055674 -301.480502) (xy 78.988354 -301.456945) (xy 78.924095 -301.426)
			(xy 78.863704 -301.388054) (xy 78.807942 -301.343585) (xy 78.757509 -301.293152) (xy 78.71304 -301.23739)
			(xy 78.675094 -301.176999) (xy 78.644149 -301.11274) (xy 78.620592 -301.04542) (xy 78.604722 -300.975885)
			(xy 78.596736 -300.905011) (xy 77.637394 -300.905011) (xy 77.637394 -300.905265) (xy 77.629408 -300.976139)
			(xy 77.613538 -301.045674) (xy 77.589981 -301.112994) (xy 77.559036 -301.177253) (xy 77.52109 -301.237644)
			(xy 77.476621 -301.293406) (xy 77.426188 -301.343839) (xy 77.370426 -301.388308) (xy 77.310035 -301.426254)
			(xy 77.245776 -301.457199) (xy 77.178456 -301.480756) (xy 77.108921 -301.496626) (xy 77.038047 -301.504612)
			(xy 76.966725 -301.504612) (xy 76.895851 -301.496626) (xy 76.826316 -301.480756) (xy 76.758996 -301.457199)
			(xy 76.694737 -301.426254) (xy 76.634346 -301.388308) (xy 76.578584 -301.343839) (xy 76.528151 -301.293406)
			(xy 76.483682 -301.237644) (xy 76.445736 -301.177253) (xy 76.414791 -301.112994) (xy 76.391234 -301.045674)
			(xy 76.375364 -300.976139) (xy 76.367378 -300.905265) (xy 75.486522 -300.905265) (xy 75.478536 -300.976139)
			(xy 75.462666 -301.045674) (xy 75.439109 -301.112994) (xy 75.408164 -301.177253) (xy 75.370218 -301.237644)
			(xy 75.325749 -301.293406) (xy 75.275316 -301.343839) (xy 75.219554 -301.388308) (xy 75.159163 -301.426254)
			(xy 75.094904 -301.457199) (xy 75.027584 -301.480756) (xy 74.958049 -301.496626) (xy 74.887175 -301.504612)
			(xy 74.815853 -301.504612) (xy 74.744979 -301.496626) (xy 74.675444 -301.480756) (xy 74.608124 -301.457199)
			(xy 74.543865 -301.426254) (xy 74.483474 -301.388308) (xy 74.427712 -301.343839) (xy 74.377279 -301.293406)
			(xy 74.33281 -301.237644) (xy 74.294864 -301.177253) (xy 74.263919 -301.112994) (xy 74.240362 -301.045674)
			(xy 74.224492 -300.976139) (xy 74.216506 -300.905265) (xy 73.456017 -300.905265) (xy 73.454156 -300.921783)
			(xy 73.438286 -300.991318) (xy 73.414729 -301.058638) (xy 73.383784 -301.122897) (xy 73.345838 -301.183288)
			(xy 73.301369 -301.23905) (xy 73.250936 -301.289483) (xy 73.195174 -301.333952) (xy 73.134783 -301.371898)
			(xy 73.070524 -301.402843) (xy 73.003204 -301.4264) (xy 72.933669 -301.44227) (xy 72.862795 -301.450256)
			(xy 72.791473 -301.450256) (xy 72.720599 -301.44227) (xy 72.651064 -301.4264) (xy 72.583744 -301.402843)
			(xy 72.519485 -301.371898) (xy 72.459094 -301.333952) (xy 72.403332 -301.289483) (xy 72.352899 -301.23905)
			(xy 72.30843 -301.183288) (xy 72.270484 -301.122897) (xy 72.239539 -301.058638) (xy 72.215982 -300.991318)
			(xy 72.200112 -300.921783) (xy 72.192126 -300.850909) (xy 71.293236 -300.850909) (xy 71.293236 -300.887231)
			(xy 71.28525 -300.958105) (xy 71.26938 -301.02764) (xy 71.245823 -301.09496) (xy 71.214878 -301.159219)
			(xy 71.176932 -301.21961) (xy 71.132463 -301.275372) (xy 71.08203 -301.325805) (xy 71.026268 -301.370274)
			(xy 70.965877 -301.40822) (xy 70.901618 -301.439165) (xy 70.834298 -301.462722) (xy 70.764763 -301.478592)
			(xy 70.693889 -301.486578) (xy 70.622567 -301.486578) (xy 70.551693 -301.478592) (xy 70.482158 -301.462722)
			(xy 70.414838 -301.439165) (xy 70.350579 -301.40822) (xy 70.290188 -301.370274) (xy 70.234426 -301.325805)
			(xy 70.183993 -301.275372) (xy 70.139524 -301.21961) (xy 70.101578 -301.159219) (xy 70.070633 -301.09496)
			(xy 70.047076 -301.02764) (xy 70.031206 -300.958105) (xy 70.02322 -300.887231) (xy 29.294836 -300.887231)
			(xy 29.294836 -302.850143) (xy 70.02322 -302.850143) (xy 70.02322 -302.778821) (xy 70.031206 -302.707947)
			(xy 70.047076 -302.638412) (xy 70.070633 -302.571092) (xy 70.101578 -302.506833) (xy 70.139524 -302.446442)
			(xy 70.183993 -302.39068) (xy 70.234426 -302.340247) (xy 70.290188 -302.295778) (xy 70.350579 -302.257832)
			(xy 70.414838 -302.226887) (xy 70.482158 -302.20333) (xy 70.551693 -302.18746) (xy 70.622567 -302.179474)
			(xy 70.658228 -302.178974) (xy 70.693889 -302.179474) (xy 70.764763 -302.18746) (xy 70.834298 -302.20333)
			(xy 70.901618 -302.226887) (xy 70.965877 -302.257832) (xy 71.026268 -302.295778) (xy 71.08203 -302.340247)
			(xy 71.132463 -302.39068) (xy 71.176932 -302.446442) (xy 71.214878 -302.506833) (xy 71.245823 -302.571092)
			(xy 71.26938 -302.638412) (xy 71.28525 -302.707947) (xy 71.293236 -302.778821) (xy 71.293236 -302.813821)
			(xy 72.192126 -302.813821) (xy 72.192126 -302.742499) (xy 72.200112 -302.671625) (xy 72.215982 -302.60209)
			(xy 72.239539 -302.53477) (xy 72.270484 -302.470511) (xy 72.30843 -302.41012) (xy 72.352899 -302.354358)
			(xy 72.403332 -302.303925) (xy 72.459094 -302.259456) (xy 72.519485 -302.22151) (xy 72.583744 -302.190565)
			(xy 72.651064 -302.167008) (xy 72.720599 -302.151138) (xy 72.791473 -302.143152) (xy 72.827134 -302.142652)
			(xy 72.862795 -302.143152) (xy 72.933669 -302.151138) (xy 73.003204 -302.167008) (xy 73.070524 -302.190565)
			(xy 73.134783 -302.22151) (xy 73.195174 -302.259456) (xy 73.250936 -302.303925) (xy 73.301369 -302.354358)
			(xy 73.345838 -302.41012) (xy 73.383784 -302.470511) (xy 73.414729 -302.53477) (xy 73.438286 -302.60209)
			(xy 73.454156 -302.671625) (xy 73.462142 -302.742499) (xy 73.462142 -302.813821) (xy 73.456017 -302.868177)
			(xy 74.216506 -302.868177) (xy 74.216506 -302.796855) (xy 74.224492 -302.725981) (xy 74.240362 -302.656446)
			(xy 74.263919 -302.589126) (xy 74.294864 -302.524867) (xy 74.33281 -302.464476) (xy 74.377279 -302.408714)
			(xy 74.427712 -302.358281) (xy 74.483474 -302.313812) (xy 74.543865 -302.275866) (xy 74.608124 -302.244921)
			(xy 74.675444 -302.221364) (xy 74.744979 -302.205494) (xy 74.815853 -302.197508) (xy 74.851514 -302.197008)
			(xy 74.887175 -302.197508) (xy 74.958049 -302.205494) (xy 75.027584 -302.221364) (xy 75.094904 -302.244921)
			(xy 75.159163 -302.275866) (xy 75.219554 -302.313812) (xy 75.275316 -302.358281) (xy 75.325749 -302.408714)
			(xy 75.370218 -302.464476) (xy 75.408164 -302.524867) (xy 75.439109 -302.589126) (xy 75.462666 -302.656446)
			(xy 75.478536 -302.725981) (xy 75.486522 -302.796855) (xy 75.486522 -302.868177) (xy 76.367378 -302.868177)
			(xy 76.367378 -302.796855) (xy 76.375364 -302.725981) (xy 76.391234 -302.656446) (xy 76.414791 -302.589126)
			(xy 76.445736 -302.524867) (xy 76.483682 -302.464476) (xy 76.528151 -302.408714) (xy 76.578584 -302.358281)
			(xy 76.634346 -302.313812) (xy 76.694737 -302.275866) (xy 76.758996 -302.244921) (xy 76.826316 -302.221364)
			(xy 76.895851 -302.205494) (xy 76.966725 -302.197508) (xy 77.002386 -302.197008) (xy 77.038047 -302.197508)
			(xy 77.108921 -302.205494) (xy 77.178456 -302.221364) (xy 77.245776 -302.244921) (xy 77.310035 -302.275866)
			(xy 77.370426 -302.313812) (xy 77.426188 -302.358281) (xy 77.476621 -302.408714) (xy 77.52109 -302.464476)
			(xy 77.559036 -302.524867) (xy 77.589981 -302.589126) (xy 77.613538 -302.656446) (xy 77.629408 -302.725981)
			(xy 77.637394 -302.796855) (xy 77.637394 -302.867923) (xy 78.596736 -302.867923) (xy 78.596736 -302.796601)
			(xy 78.604722 -302.725727) (xy 78.620592 -302.656192) (xy 78.644149 -302.588872) (xy 78.675094 -302.524613)
			(xy 78.71304 -302.464222) (xy 78.757509 -302.40846) (xy 78.807942 -302.358027) (xy 78.863704 -302.313558)
			(xy 78.924095 -302.275612) (xy 78.988354 -302.244667) (xy 79.055674 -302.22111) (xy 79.125209 -302.20524)
			(xy 79.196083 -302.197254) (xy 79.231744 -302.196754) (xy 79.267405 -302.197254) (xy 79.338279 -302.20524)
			(xy 79.407814 -302.22111) (xy 79.44345 -302.23358) (xy 95.893872 -302.23358) (xy 95.893872 -302.173644)
			(xy 95.901695 -302.114222) (xy 95.917208 -302.056329) (xy 95.940144 -302.000956) (xy 95.970111 -301.94905)
			(xy 96.006598 -301.9015) (xy 96.048978 -301.85912) (xy 96.096528 -301.822633) (xy 96.148434 -301.792666)
			(xy 96.203807 -301.76973) (xy 96.2617 -301.754217) (xy 96.321122 -301.746394) (xy 96.35109 -301.745904)
			(xy 96.381058 -301.746394) (xy 96.44048 -301.754217) (xy 96.498373 -301.76973) (xy 96.553746 -301.792666)
			(xy 96.605652 -301.822633) (xy 96.653202 -301.85912) (xy 96.695582 -301.9015) (xy 96.732069 -301.94905)
			(xy 96.762036 -302.000956) (xy 96.784972 -302.056329) (xy 96.800485 -302.114222) (xy 96.808308 -302.173644)
			(xy 96.808308 -302.23358) (xy 96.800485 -302.293002) (xy 96.784972 -302.350895) (xy 96.762036 -302.406268)
			(xy 96.732069 -302.458174) (xy 96.695582 -302.505724) (xy 96.653202 -302.548104) (xy 96.605652 -302.584591)
			(xy 96.553746 -302.614558) (xy 96.498373 -302.637494) (xy 96.44048 -302.653007) (xy 96.381058 -302.66083)
			(xy 96.321122 -302.66083) (xy 96.2617 -302.653007) (xy 96.203807 -302.637494) (xy 96.148434 -302.614558)
			(xy 96.096528 -302.584591) (xy 96.048978 -302.548104) (xy 96.006598 -302.505724) (xy 95.970111 -302.458174)
			(xy 95.940144 -302.406268) (xy 95.917208 -302.350895) (xy 95.901695 -302.293002) (xy 95.893872 -302.23358)
			(xy 79.44345 -302.23358) (xy 79.475134 -302.244667) (xy 79.539393 -302.275612) (xy 79.599784 -302.313558)
			(xy 79.655546 -302.358027) (xy 79.705979 -302.40846) (xy 79.750448 -302.464222) (xy 79.788394 -302.524613)
			(xy 79.819339 -302.588872) (xy 79.842896 -302.656192) (xy 79.858766 -302.725727) (xy 79.866752 -302.796601)
			(xy 79.866752 -302.867923) (xy 79.858766 -302.938797) (xy 79.842896 -303.008332) (xy 79.819339 -303.075652)
			(xy 79.788394 -303.139911) (xy 79.750448 -303.200302) (xy 79.705979 -303.256064) (xy 79.655546 -303.306497)
			(xy 79.599784 -303.350966) (xy 79.539393 -303.388912) (xy 79.475134 -303.419857) (xy 79.407814 -303.443414)
			(xy 79.338279 -303.459284) (xy 79.267405 -303.46727) (xy 79.196083 -303.46727) (xy 79.125209 -303.459284)
			(xy 79.055674 -303.443414) (xy 78.988354 -303.419857) (xy 78.924095 -303.388912) (xy 78.863704 -303.350966)
			(xy 78.807942 -303.306497) (xy 78.757509 -303.256064) (xy 78.71304 -303.200302) (xy 78.675094 -303.139911)
			(xy 78.644149 -303.075652) (xy 78.620592 -303.008332) (xy 78.604722 -302.938797) (xy 78.596736 -302.867923)
			(xy 77.637394 -302.867923) (xy 77.637394 -302.868177) (xy 77.629408 -302.939051) (xy 77.613538 -303.008586)
			(xy 77.589981 -303.075906) (xy 77.559036 -303.140165) (xy 77.52109 -303.200556) (xy 77.476621 -303.256318)
			(xy 77.426188 -303.306751) (xy 77.370426 -303.35122) (xy 77.310035 -303.389166) (xy 77.245776 -303.420111)
			(xy 77.178456 -303.443668) (xy 77.108921 -303.459538) (xy 77.038047 -303.467524) (xy 76.966725 -303.467524)
			(xy 76.895851 -303.459538) (xy 76.826316 -303.443668) (xy 76.758996 -303.420111) (xy 76.694737 -303.389166)
			(xy 76.634346 -303.35122) (xy 76.578584 -303.306751) (xy 76.528151 -303.256318) (xy 76.483682 -303.200556)
			(xy 76.445736 -303.140165) (xy 76.414791 -303.075906) (xy 76.391234 -303.008586) (xy 76.375364 -302.939051)
			(xy 76.367378 -302.868177) (xy 75.486522 -302.868177) (xy 75.478536 -302.939051) (xy 75.462666 -303.008586)
			(xy 75.439109 -303.075906) (xy 75.408164 -303.140165) (xy 75.370218 -303.200556) (xy 75.325749 -303.256318)
			(xy 75.275316 -303.306751) (xy 75.219554 -303.35122) (xy 75.159163 -303.389166) (xy 75.094904 -303.420111)
			(xy 75.027584 -303.443668) (xy 74.958049 -303.459538) (xy 74.887175 -303.467524) (xy 74.815853 -303.467524)
			(xy 74.744979 -303.459538) (xy 74.675444 -303.443668) (xy 74.608124 -303.420111) (xy 74.543865 -303.389166)
			(xy 74.483474 -303.35122) (xy 74.427712 -303.306751) (xy 74.377279 -303.256318) (xy 74.33281 -303.200556)
			(xy 74.294864 -303.140165) (xy 74.263919 -303.075906) (xy 74.240362 -303.008586) (xy 74.224492 -302.939051)
			(xy 74.216506 -302.868177) (xy 73.456017 -302.868177) (xy 73.454156 -302.884695) (xy 73.438286 -302.95423)
			(xy 73.414729 -303.02155) (xy 73.383784 -303.085809) (xy 73.345838 -303.1462) (xy 73.301369 -303.201962)
			(xy 73.250936 -303.252395) (xy 73.195174 -303.296864) (xy 73.134783 -303.33481) (xy 73.070524 -303.365755)
			(xy 73.003204 -303.389312) (xy 72.933669 -303.405182) (xy 72.862795 -303.413168) (xy 72.791473 -303.413168)
			(xy 72.720599 -303.405182) (xy 72.651064 -303.389312) (xy 72.583744 -303.365755) (xy 72.519485 -303.33481)
			(xy 72.459094 -303.296864) (xy 72.403332 -303.252395) (xy 72.352899 -303.201962) (xy 72.30843 -303.1462)
			(xy 72.270484 -303.085809) (xy 72.239539 -303.02155) (xy 72.215982 -302.95423) (xy 72.200112 -302.884695)
			(xy 72.192126 -302.813821) (xy 71.293236 -302.813821) (xy 71.293236 -302.850143) (xy 71.28525 -302.921017)
			(xy 71.26938 -302.990552) (xy 71.245823 -303.057872) (xy 71.214878 -303.122131) (xy 71.176932 -303.182522)
			(xy 71.132463 -303.238284) (xy 71.08203 -303.288717) (xy 71.026268 -303.333186) (xy 70.965877 -303.371132)
			(xy 70.901618 -303.402077) (xy 70.834298 -303.425634) (xy 70.764763 -303.441504) (xy 70.693889 -303.44949)
			(xy 70.622567 -303.44949) (xy 70.551693 -303.441504) (xy 70.482158 -303.425634) (xy 70.414838 -303.402077)
			(xy 70.350579 -303.371132) (xy 70.290188 -303.333186) (xy 70.234426 -303.288717) (xy 70.183993 -303.238284)
			(xy 70.139524 -303.182522) (xy 70.101578 -303.122131) (xy 70.070633 -303.057872) (xy 70.047076 -302.990552)
			(xy 70.031206 -302.921017) (xy 70.02322 -302.850143) (xy 29.294836 -302.850143) (xy 29.294836 -303.559714)
			(xy 95.16667 -303.559714) (xy 95.16667 -303.499778) (xy 95.174493 -303.440356) (xy 95.190006 -303.382463)
			(xy 95.212942 -303.32709) (xy 95.242909 -303.275184) (xy 95.279396 -303.227634) (xy 95.321776 -303.185254)
			(xy 95.369326 -303.148767) (xy 95.421232 -303.1188) (xy 95.476605 -303.095864) (xy 95.534498 -303.080351)
			(xy 95.59392 -303.072528) (xy 95.623888 -303.072038) (xy 95.653856 -303.072528) (xy 95.713278 -303.080351)
			(xy 95.771171 -303.095864) (xy 95.826544 -303.1188) (xy 95.87845 -303.148767) (xy 95.926 -303.185254)
			(xy 95.96838 -303.227634) (xy 96.004867 -303.275184) (xy 96.034834 -303.32709) (xy 96.05777 -303.382463)
			(xy 96.073283 -303.440356) (xy 96.081106 -303.499778) (xy 96.081106 -303.559714) (xy 96.073283 -303.619136)
			(xy 96.05777 -303.677029) (xy 96.034834 -303.732402) (xy 96.004867 -303.784308) (xy 95.96838 -303.831858)
			(xy 95.926 -303.874238) (xy 95.87845 -303.910725) (xy 95.826544 -303.940692) (xy 95.771171 -303.963628)
			(xy 95.713278 -303.979141) (xy 95.653856 -303.986964) (xy 95.59392 -303.986964) (xy 95.534498 -303.979141)
			(xy 95.476605 -303.963628) (xy 95.421232 -303.940692) (xy 95.369326 -303.910725) (xy 95.321776 -303.874238)
			(xy 95.279396 -303.831858) (xy 95.242909 -303.784308) (xy 95.212942 -303.732402) (xy 95.190006 -303.677029)
			(xy 95.174493 -303.619136) (xy 95.16667 -303.559714) (xy 29.294836 -303.559714) (xy 29.294836 -304.993649)
			(xy 70.02322 -304.993649) (xy 70.02322 -304.922327) (xy 70.031206 -304.851453) (xy 70.047076 -304.781918)
			(xy 70.070633 -304.714598) (xy 70.101578 -304.650339) (xy 70.139524 -304.589948) (xy 70.183993 -304.534186)
			(xy 70.234426 -304.483753) (xy 70.290188 -304.439284) (xy 70.350579 -304.401338) (xy 70.414838 -304.370393)
			(xy 70.482158 -304.346836) (xy 70.551693 -304.330966) (xy 70.622567 -304.32298) (xy 70.658228 -304.32248)
			(xy 70.693889 -304.32298) (xy 70.764763 -304.330966) (xy 70.834298 -304.346836) (xy 70.901618 -304.370393)
			(xy 70.965877 -304.401338) (xy 71.026268 -304.439284) (xy 71.08203 -304.483753) (xy 71.132463 -304.534186)
			(xy 71.176932 -304.589948) (xy 71.214878 -304.650339) (xy 71.245823 -304.714598) (xy 71.26938 -304.781918)
			(xy 71.28525 -304.851453) (xy 71.293236 -304.922327) (xy 71.293236 -304.957327) (xy 72.192126 -304.957327)
			(xy 72.192126 -304.886005) (xy 72.200112 -304.815131) (xy 72.215982 -304.745596) (xy 72.239539 -304.678276)
			(xy 72.270484 -304.614017) (xy 72.30843 -304.553626) (xy 72.352899 -304.497864) (xy 72.403332 -304.447431)
			(xy 72.459094 -304.402962) (xy 72.519485 -304.365016) (xy 72.583744 -304.334071) (xy 72.651064 -304.310514)
			(xy 72.720599 -304.294644) (xy 72.791473 -304.286658) (xy 72.827134 -304.286158) (xy 72.862795 -304.286658)
			(xy 72.933669 -304.294644) (xy 73.003204 -304.310514) (xy 73.070524 -304.334071) (xy 73.134783 -304.365016)
			(xy 73.195174 -304.402962) (xy 73.250936 -304.447431) (xy 73.301369 -304.497864) (xy 73.345838 -304.553626)
			(xy 73.383784 -304.614017) (xy 73.414729 -304.678276) (xy 73.438286 -304.745596) (xy 73.454156 -304.815131)
			(xy 73.462142 -304.886005) (xy 73.462142 -304.957327) (xy 73.456017 -305.011683) (xy 74.216506 -305.011683)
			(xy 74.216506 -304.940361) (xy 74.224492 -304.869487) (xy 74.240362 -304.799952) (xy 74.263919 -304.732632)
			(xy 74.294864 -304.668373) (xy 74.33281 -304.607982) (xy 74.377279 -304.55222) (xy 74.427712 -304.501787)
			(xy 74.483474 -304.457318) (xy 74.543865 -304.419372) (xy 74.608124 -304.388427) (xy 74.675444 -304.36487)
			(xy 74.744979 -304.349) (xy 74.815853 -304.341014) (xy 74.851514 -304.340514) (xy 74.887175 -304.341014)
			(xy 74.958049 -304.349) (xy 75.027584 -304.36487) (xy 75.094904 -304.388427) (xy 75.159163 -304.419372)
			(xy 75.219554 -304.457318) (xy 75.275316 -304.501787) (xy 75.325749 -304.55222) (xy 75.370218 -304.607982)
			(xy 75.408164 -304.668373) (xy 75.439109 -304.732632) (xy 75.462666 -304.799952) (xy 75.478536 -304.869487)
			(xy 75.486522 -304.940361) (xy 75.486522 -305.011683) (xy 76.367378 -305.011683) (xy 76.367378 -304.940361)
			(xy 76.375364 -304.869487) (xy 76.391234 -304.799952) (xy 76.414791 -304.732632) (xy 76.445736 -304.668373)
			(xy 76.483682 -304.607982) (xy 76.528151 -304.55222) (xy 76.578584 -304.501787) (xy 76.634346 -304.457318)
			(xy 76.694737 -304.419372) (xy 76.758996 -304.388427) (xy 76.826316 -304.36487) (xy 76.895851 -304.349)
			(xy 76.966725 -304.341014) (xy 77.002386 -304.340514) (xy 77.038047 -304.341014) (xy 77.108921 -304.349)
			(xy 77.178456 -304.36487) (xy 77.245776 -304.388427) (xy 77.310035 -304.419372) (xy 77.370426 -304.457318)
			(xy 77.426188 -304.501787) (xy 77.476621 -304.55222) (xy 77.52109 -304.607982) (xy 77.559036 -304.668373)
			(xy 77.589981 -304.732632) (xy 77.613538 -304.799952) (xy 77.629408 -304.869487) (xy 77.637394 -304.940361)
			(xy 77.637394 -305.011429) (xy 78.596736 -305.011429) (xy 78.596736 -304.940107) (xy 78.604722 -304.869233)
			(xy 78.620592 -304.799698) (xy 78.644149 -304.732378) (xy 78.675094 -304.668119) (xy 78.71304 -304.607728)
			(xy 78.757509 -304.551966) (xy 78.807942 -304.501533) (xy 78.863704 -304.457064) (xy 78.924095 -304.419118)
			(xy 78.988354 -304.388173) (xy 79.055674 -304.364616) (xy 79.125209 -304.348746) (xy 79.196083 -304.34076)
			(xy 79.231744 -304.34026) (xy 79.267405 -304.34076) (xy 79.338279 -304.348746) (xy 79.407814 -304.364616)
			(xy 79.475134 -304.388173) (xy 79.539393 -304.419118) (xy 79.599784 -304.457064) (xy 79.655546 -304.501533)
			(xy 79.705979 -304.551966) (xy 79.750448 -304.607728) (xy 79.788394 -304.668119) (xy 79.819339 -304.732378)
			(xy 79.842896 -304.799698) (xy 79.847892 -304.821586) (xy 94.455978 -304.821586) (xy 94.455978 -304.76165)
			(xy 94.463801 -304.702228) (xy 94.479314 -304.644335) (xy 94.50225 -304.588962) (xy 94.532217 -304.537056)
			(xy 94.568704 -304.489506) (xy 94.611084 -304.447126) (xy 94.658634 -304.410639) (xy 94.71054 -304.380672)
			(xy 94.765913 -304.357736) (xy 94.823806 -304.342223) (xy 94.883228 -304.3344) (xy 94.913196 -304.33391)
			(xy 94.943164 -304.3344) (xy 95.002586 -304.342223) (xy 95.060479 -304.357736) (xy 95.115852 -304.380672)
			(xy 95.167758 -304.410639) (xy 95.215308 -304.447126) (xy 95.257688 -304.489506) (xy 95.294175 -304.537056)
			(xy 95.324142 -304.588962) (xy 95.347078 -304.644335) (xy 95.362591 -304.702228) (xy 95.370414 -304.76165)
			(xy 95.370414 -304.821586) (xy 95.362591 -304.881008) (xy 95.347078 -304.938901) (xy 95.324142 -304.994274)
			(xy 95.294175 -305.04618) (xy 95.257688 -305.09373) (xy 95.215308 -305.13611) (xy 95.167758 -305.172597)
			(xy 95.115852 -305.202564) (xy 95.060479 -305.2255) (xy 95.002586 -305.241013) (xy 94.943164 -305.248836)
			(xy 94.883228 -305.248836) (xy 94.823806 -305.241013) (xy 94.765913 -305.2255) (xy 94.71054 -305.202564)
			(xy 94.658634 -305.172597) (xy 94.611084 -305.13611) (xy 94.568704 -305.09373) (xy 94.532217 -305.04618)
			(xy 94.50225 -304.994274) (xy 94.479314 -304.938901) (xy 94.463801 -304.881008) (xy 94.455978 -304.821586)
			(xy 79.847892 -304.821586) (xy 79.858766 -304.869233) (xy 79.866752 -304.940107) (xy 79.866752 -305.011429)
			(xy 79.858766 -305.082303) (xy 79.842896 -305.151838) (xy 79.819339 -305.219158) (xy 79.788394 -305.283417)
			(xy 79.750448 -305.343808) (xy 79.705979 -305.39957) (xy 79.655546 -305.450003) (xy 79.599784 -305.494472)
			(xy 79.539393 -305.532418) (xy 79.475134 -305.563363) (xy 79.407814 -305.58692) (xy 79.338279 -305.60279)
			(xy 79.267405 -305.610776) (xy 79.196083 -305.610776) (xy 79.125209 -305.60279) (xy 79.055674 -305.58692)
			(xy 78.988354 -305.563363) (xy 78.924095 -305.532418) (xy 78.863704 -305.494472) (xy 78.807942 -305.450003)
			(xy 78.757509 -305.39957) (xy 78.71304 -305.343808) (xy 78.675094 -305.283417) (xy 78.644149 -305.219158)
			(xy 78.620592 -305.151838) (xy 78.604722 -305.082303) (xy 78.596736 -305.011429) (xy 77.637394 -305.011429)
			(xy 77.637394 -305.011683) (xy 77.629408 -305.082557) (xy 77.613538 -305.152092) (xy 77.589981 -305.219412)
			(xy 77.559036 -305.283671) (xy 77.52109 -305.344062) (xy 77.476621 -305.399824) (xy 77.426188 -305.450257)
			(xy 77.370426 -305.494726) (xy 77.310035 -305.532672) (xy 77.245776 -305.563617) (xy 77.178456 -305.587174)
			(xy 77.108921 -305.603044) (xy 77.038047 -305.61103) (xy 76.966725 -305.61103) (xy 76.895851 -305.603044)
			(xy 76.826316 -305.587174) (xy 76.758996 -305.563617) (xy 76.694737 -305.532672) (xy 76.634346 -305.494726)
			(xy 76.578584 -305.450257) (xy 76.528151 -305.399824) (xy 76.483682 -305.344062) (xy 76.445736 -305.283671)
			(xy 76.414791 -305.219412) (xy 76.391234 -305.152092) (xy 76.375364 -305.082557) (xy 76.367378 -305.011683)
			(xy 75.486522 -305.011683) (xy 75.478536 -305.082557) (xy 75.462666 -305.152092) (xy 75.439109 -305.219412)
			(xy 75.408164 -305.283671) (xy 75.370218 -305.344062) (xy 75.325749 -305.399824) (xy 75.275316 -305.450257)
			(xy 75.219554 -305.494726) (xy 75.159163 -305.532672) (xy 75.094904 -305.563617) (xy 75.027584 -305.587174)
			(xy 74.958049 -305.603044) (xy 74.887175 -305.61103) (xy 74.815853 -305.61103) (xy 74.744979 -305.603044)
			(xy 74.675444 -305.587174) (xy 74.608124 -305.563617) (xy 74.543865 -305.532672) (xy 74.483474 -305.494726)
			(xy 74.427712 -305.450257) (xy 74.377279 -305.399824) (xy 74.33281 -305.344062) (xy 74.294864 -305.283671)
			(xy 74.263919 -305.219412) (xy 74.240362 -305.152092) (xy 74.224492 -305.082557) (xy 74.216506 -305.011683)
			(xy 73.456017 -305.011683) (xy 73.454156 -305.028201) (xy 73.438286 -305.097736) (xy 73.414729 -305.165056)
			(xy 73.383784 -305.229315) (xy 73.345838 -305.289706) (xy 73.301369 -305.345468) (xy 73.250936 -305.395901)
			(xy 73.195174 -305.44037) (xy 73.134783 -305.478316) (xy 73.070524 -305.509261) (xy 73.003204 -305.532818)
			(xy 72.933669 -305.548688) (xy 72.862795 -305.556674) (xy 72.791473 -305.556674) (xy 72.720599 -305.548688)
			(xy 72.651064 -305.532818) (xy 72.583744 -305.509261) (xy 72.519485 -305.478316) (xy 72.459094 -305.44037)
			(xy 72.403332 -305.395901) (xy 72.352899 -305.345468) (xy 72.30843 -305.289706) (xy 72.270484 -305.229315)
			(xy 72.239539 -305.165056) (xy 72.215982 -305.097736) (xy 72.200112 -305.028201) (xy 72.192126 -304.957327)
			(xy 71.293236 -304.957327) (xy 71.293236 -304.993649) (xy 71.28525 -305.064523) (xy 71.26938 -305.134058)
			(xy 71.245823 -305.201378) (xy 71.214878 -305.265637) (xy 71.176932 -305.326028) (xy 71.132463 -305.38179)
			(xy 71.08203 -305.432223) (xy 71.026268 -305.476692) (xy 70.965877 -305.514638) (xy 70.901618 -305.545583)
			(xy 70.834298 -305.56914) (xy 70.764763 -305.58501) (xy 70.693889 -305.592996) (xy 70.622567 -305.592996)
			(xy 70.551693 -305.58501) (xy 70.482158 -305.56914) (xy 70.414838 -305.545583) (xy 70.350579 -305.514638)
			(xy 70.290188 -305.476692) (xy 70.234426 -305.432223) (xy 70.183993 -305.38179) (xy 70.139524 -305.326028)
			(xy 70.101578 -305.265637) (xy 70.070633 -305.201378) (xy 70.047076 -305.134058) (xy 70.031206 -305.064523)
			(xy 70.02322 -304.993649) (xy 29.294836 -304.993649) (xy 29.294836 -305.557428) (xy 51.27498 -305.557428)
			(xy 52.926996 -305.557428) (xy 52.926996 -306.030118) (xy 93.909624 -306.030118) (xy 93.909624 -305.970182)
			(xy 93.917447 -305.91076) (xy 93.93296 -305.852867) (xy 93.955896 -305.797494) (xy 93.985863 -305.745588)
			(xy 94.02235 -305.698038) (xy 94.06473 -305.655658) (xy 94.11228 -305.619171) (xy 94.164186 -305.589204)
			(xy 94.219559 -305.566268) (xy 94.277452 -305.550755) (xy 94.336874 -305.542932) (xy 94.366842 -305.542442)
			(xy 94.39681 -305.542932) (xy 94.456232 -305.550755) (xy 94.514125 -305.566268) (xy 94.569498 -305.589204)
			(xy 94.621404 -305.619171) (xy 94.668954 -305.655658) (xy 94.711334 -305.698038) (xy 94.747821 -305.745588)
			(xy 94.777788 -305.797494) (xy 94.800724 -305.852867) (xy 94.816237 -305.91076) (xy 94.82406 -305.970182)
			(xy 94.82406 -306.030118) (xy 94.816237 -306.08954) (xy 94.800724 -306.147433) (xy 94.777788 -306.202806)
			(xy 94.747821 -306.254712) (xy 94.711334 -306.302262) (xy 94.668954 -306.344642) (xy 94.621404 -306.381129)
			(xy 94.569498 -306.411096) (xy 94.514125 -306.434032) (xy 94.456232 -306.449545) (xy 94.39681 -306.457368)
			(xy 94.336874 -306.457368) (xy 94.277452 -306.449545) (xy 94.219559 -306.434032) (xy 94.164186 -306.411096)
			(xy 94.11228 -306.381129) (xy 94.06473 -306.344642) (xy 94.02235 -306.302262) (xy 93.985863 -306.254712)
			(xy 93.955896 -306.202806) (xy 93.93296 -306.147433) (xy 93.917447 -306.08954) (xy 93.909624 -306.030118)
			(xy 52.926996 -306.030118) (xy 52.926996 -307.208936) (xy 51.27498 -307.208936) (xy 51.27498 -305.557428)
			(xy 29.294836 -305.557428) (xy 29.294836 -318.031047) (xy 39.818567 -318.031047) (xy 39.824576 -317.915126)
			(xy 39.838567 -317.799897) (xy 39.860475 -317.685907) (xy 39.890195 -317.5737) (xy 39.927585 -317.463811)
			(xy 39.972468 -317.356764) (xy 40.024629 -317.253068) (xy 40.08382 -317.153218) (xy 40.149759 -317.057689)
			(xy 40.222131 -316.966938) (xy 40.300592 -316.881395) (xy 40.384767 -316.801469) (xy 40.474256 -316.727542)
			(xy 40.568632 -316.659964) (xy 40.667446 -316.599058) (xy 40.770226 -316.545115) (xy 40.876483 -316.498391)
			(xy 40.98571 -316.45911) (xy 41.097387 -316.427458) (xy 41.210982 -316.403585) (xy 41.325953 -316.387607)
			(xy 41.441752 -316.379599) (xy 41.49979 -316.379098) (xy 41.557828 -316.379599) (xy 41.673627 -316.387607)
			(xy 41.788598 -316.403585) (xy 41.902193 -316.427458) (xy 42.01387 -316.45911) (xy 42.123097 -316.498391)
			(xy 42.229354 -316.545115) (xy 42.332134 -316.599058) (xy 42.430948 -316.659964) (xy 42.474432 -316.691101)
			(xy 63.647829 -316.691101) (xy 63.653878 -316.615531) (xy 63.667925 -316.541033) (xy 63.689811 -316.46845)
			(xy 63.719288 -316.398604) (xy 63.756023 -316.332287) (xy 63.799598 -316.270251) (xy 63.84952 -316.213198)
			(xy 63.905224 -316.161774) (xy 63.966079 -316.116563) (xy 64.031394 -316.078076) (xy 64.10043 -316.04675)
			(xy 64.172405 -316.02294) (xy 64.246503 -316.006915) (xy 64.321884 -315.998856) (xy 64.35979 -315.998352)
			(xy 64.397696 -315.998856) (xy 64.473077 -316.006915) (xy 64.547175 -316.02294) (xy 64.61915 -316.04675)
			(xy 64.688186 -316.078076) (xy 64.753501 -316.116563) (xy 64.814356 -316.161774) (xy 64.87006 -316.213198)
			(xy 64.919982 -316.270251) (xy 64.963557 -316.332287) (xy 65.000292 -316.398604) (xy 65.029769 -316.46845)
			(xy 65.051655 -316.541033) (xy 65.065702 -316.615531) (xy 65.071751 -316.691101) (xy 66.187829 -316.691101)
			(xy 66.193878 -316.615531) (xy 66.207925 -316.541033) (xy 66.229811 -316.46845) (xy 66.259288 -316.398604)
			(xy 66.296023 -316.332287) (xy 66.339598 -316.270251) (xy 66.38952 -316.213198) (xy 66.445224 -316.161774)
			(xy 66.506079 -316.116563) (xy 66.571394 -316.078076) (xy 66.64043 -316.04675) (xy 66.712405 -316.02294)
			(xy 66.786503 -316.006915) (xy 66.861884 -315.998856) (xy 66.89979 -315.998352) (xy 66.937696 -315.998856)
			(xy 67.013077 -316.006915) (xy 67.087175 -316.02294) (xy 67.15915 -316.04675) (xy 67.228186 -316.078076)
			(xy 67.293501 -316.116563) (xy 67.354356 -316.161774) (xy 67.41006 -316.213198) (xy 67.459982 -316.270251)
			(xy 67.503557 -316.332287) (xy 67.540292 -316.398604) (xy 67.569769 -316.46845) (xy 67.591655 -316.541033)
			(xy 67.605702 -316.615531) (xy 67.611751 -316.691101) (xy 68.727829 -316.691101) (xy 68.733878 -316.615531)
			(xy 68.747925 -316.541033) (xy 68.769811 -316.46845) (xy 68.799288 -316.398604) (xy 68.836023 -316.332287)
			(xy 68.879598 -316.270251) (xy 68.92952 -316.213198) (xy 68.985224 -316.161774) (xy 69.046079 -316.116563)
			(xy 69.111394 -316.078076) (xy 69.18043 -316.04675) (xy 69.252405 -316.02294) (xy 69.326503 -316.006915)
			(xy 69.401884 -315.998856) (xy 69.43979 -315.998352) (xy 69.477696 -315.998856) (xy 69.553077 -316.006915)
			(xy 69.627175 -316.02294) (xy 69.69915 -316.04675) (xy 69.768186 -316.078076) (xy 69.833501 -316.116563)
			(xy 69.894356 -316.161774) (xy 69.95006 -316.213198) (xy 69.999982 -316.270251) (xy 70.043557 -316.332287)
			(xy 70.080292 -316.398604) (xy 70.109769 -316.46845) (xy 70.131655 -316.541033) (xy 70.145702 -316.615531)
			(xy 70.151751 -316.691101) (xy 71.267829 -316.691101) (xy 71.273878 -316.615531) (xy 71.287925 -316.541033)
			(xy 71.309811 -316.46845) (xy 71.339288 -316.398604) (xy 71.376023 -316.332287) (xy 71.419598 -316.270251)
			(xy 71.46952 -316.213198) (xy 71.525224 -316.161774) (xy 71.586079 -316.116563) (xy 71.651394 -316.078076)
			(xy 71.72043 -316.04675) (xy 71.792405 -316.02294) (xy 71.866503 -316.006915) (xy 71.941884 -315.998856)
			(xy 71.97979 -315.998352) (xy 72.017696 -315.998856) (xy 72.093077 -316.006915) (xy 72.167175 -316.02294)
			(xy 72.23915 -316.04675) (xy 72.308186 -316.078076) (xy 72.373501 -316.116563) (xy 72.434356 -316.161774)
			(xy 72.49006 -316.213198) (xy 72.539982 -316.270251) (xy 72.583557 -316.332287) (xy 72.620292 -316.398604)
			(xy 72.649769 -316.46845) (xy 72.671655 -316.541033) (xy 72.685702 -316.615531) (xy 72.691751 -316.691101)
			(xy 73.807829 -316.691101) (xy 73.813878 -316.615531) (xy 73.827925 -316.541033) (xy 73.849811 -316.46845)
			(xy 73.879288 -316.398604) (xy 73.916023 -316.332287) (xy 73.959598 -316.270251) (xy 74.00952 -316.213198)
			(xy 74.065224 -316.161774) (xy 74.126079 -316.116563) (xy 74.191394 -316.078076) (xy 74.26043 -316.04675)
			(xy 74.332405 -316.02294) (xy 74.406503 -316.006915) (xy 74.481884 -315.998856) (xy 74.51979 -315.998352)
			(xy 74.557696 -315.998856) (xy 74.633077 -316.006915) (xy 74.707175 -316.02294) (xy 74.77915 -316.04675)
			(xy 74.848186 -316.078076) (xy 74.913501 -316.116563) (xy 74.974356 -316.161774) (xy 75.03006 -316.213198)
			(xy 75.079982 -316.270251) (xy 75.123557 -316.332287) (xy 75.160292 -316.398604) (xy 75.189769 -316.46845)
			(xy 75.211655 -316.541033) (xy 75.225702 -316.615531) (xy 75.231751 -316.691101) (xy 76.347829 -316.691101)
			(xy 76.353878 -316.615531) (xy 76.367925 -316.541033) (xy 76.389811 -316.46845) (xy 76.419288 -316.398604)
			(xy 76.456023 -316.332287) (xy 76.499598 -316.270251) (xy 76.54952 -316.213198) (xy 76.605224 -316.161774)
			(xy 76.666079 -316.116563) (xy 76.731394 -316.078076) (xy 76.80043 -316.04675) (xy 76.872405 -316.02294)
			(xy 76.946503 -316.006915) (xy 77.021884 -315.998856) (xy 77.05979 -315.998352) (xy 77.097696 -315.998856)
			(xy 77.173077 -316.006915) (xy 77.247175 -316.02294) (xy 77.31915 -316.04675) (xy 77.388186 -316.078076)
			(xy 77.453501 -316.116563) (xy 77.514356 -316.161774) (xy 77.57006 -316.213198) (xy 77.619982 -316.270251)
			(xy 77.663557 -316.332287) (xy 77.700292 -316.398604) (xy 77.729769 -316.46845) (xy 77.751655 -316.541033)
			(xy 77.765702 -316.615531) (xy 77.771751 -316.691101) (xy 78.887829 -316.691101) (xy 78.893878 -316.615531)
			(xy 78.907925 -316.541033) (xy 78.929811 -316.46845) (xy 78.959288 -316.398604) (xy 78.996023 -316.332287)
			(xy 79.039598 -316.270251) (xy 79.08952 -316.213198) (xy 79.145224 -316.161774) (xy 79.206079 -316.116563)
			(xy 79.271394 -316.078076) (xy 79.34043 -316.04675) (xy 79.412405 -316.02294) (xy 79.486503 -316.006915)
			(xy 79.561884 -315.998856) (xy 79.59979 -315.998352) (xy 79.637696 -315.998856) (xy 79.713077 -316.006915)
			(xy 79.787175 -316.02294) (xy 79.85915 -316.04675) (xy 79.928186 -316.078076) (xy 79.993501 -316.116563)
			(xy 80.054356 -316.161774) (xy 80.11006 -316.213198) (xy 80.159982 -316.270251) (xy 80.203557 -316.332287)
			(xy 80.240292 -316.398604) (xy 80.269769 -316.46845) (xy 80.291655 -316.541033) (xy 80.305702 -316.615531)
			(xy 80.311751 -316.691101) (xy 81.427829 -316.691101) (xy 81.433878 -316.615531) (xy 81.447925 -316.541033)
			(xy 81.469811 -316.46845) (xy 81.499288 -316.398604) (xy 81.536023 -316.332287) (xy 81.579598 -316.270251)
			(xy 81.62952 -316.213198) (xy 81.685224 -316.161774) (xy 81.746079 -316.116563) (xy 81.811394 -316.078076)
			(xy 81.88043 -316.04675) (xy 81.952405 -316.02294) (xy 82.026503 -316.006915) (xy 82.101884 -315.998856)
			(xy 82.13979 -315.998352) (xy 82.177696 -315.998856) (xy 82.253077 -316.006915) (xy 82.327175 -316.02294)
			(xy 82.39915 -316.04675) (xy 82.468186 -316.078076) (xy 82.533501 -316.116563) (xy 82.559813 -316.136111)
			(xy 86.197949 -316.136111) (xy 86.203998 -316.060541) (xy 86.218045 -315.986043) (xy 86.239931 -315.91346)
			(xy 86.269408 -315.843614) (xy 86.306143 -315.777297) (xy 86.349718 -315.715261) (xy 86.39964 -315.658208)
			(xy 86.455344 -315.606784) (xy 86.516199 -315.561573) (xy 86.581514 -315.523086) (xy 86.65055 -315.49176)
			(xy 86.722525 -315.46795) (xy 86.796623 -315.451925) (xy 86.872004 -315.443866) (xy 86.90991 -315.443362)
			(xy 86.947816 -315.443866) (xy 87.023197 -315.451925) (xy 87.097295 -315.46795) (xy 87.16927 -315.49176)
			(xy 87.238306 -315.523086) (xy 87.303621 -315.561573) (xy 87.364476 -315.606784) (xy 87.42018 -315.658208)
			(xy 87.470102 -315.715261) (xy 87.513677 -315.777297) (xy 87.550412 -315.843614) (xy 87.579889 -315.91346)
			(xy 87.601775 -315.986043) (xy 87.615822 -316.060541) (xy 87.621871 -316.136111) (xy 88.737949 -316.136111)
			(xy 88.743998 -316.060541) (xy 88.758045 -315.986043) (xy 88.779931 -315.91346) (xy 88.809408 -315.843614)
			(xy 88.846143 -315.777297) (xy 88.889718 -315.715261) (xy 88.93964 -315.658208) (xy 88.995344 -315.606784)
			(xy 89.056199 -315.561573) (xy 89.121514 -315.523086) (xy 89.19055 -315.49176) (xy 89.262525 -315.46795)
			(xy 89.336623 -315.451925) (xy 89.412004 -315.443866) (xy 89.44991 -315.443362) (xy 89.487816 -315.443866)
			(xy 89.563197 -315.451925) (xy 89.637295 -315.46795) (xy 89.70927 -315.49176) (xy 89.778306 -315.523086)
			(xy 89.843621 -315.561573) (xy 89.904476 -315.606784) (xy 89.96018 -315.658208) (xy 90.010102 -315.715261)
			(xy 90.053677 -315.777297) (xy 90.090412 -315.843614) (xy 90.119889 -315.91346) (xy 90.141775 -315.986043)
			(xy 90.155822 -316.060541) (xy 90.161871 -316.136111) (xy 91.277949 -316.136111) (xy 91.283998 -316.060541)
			(xy 91.298045 -315.986043) (xy 91.319931 -315.91346) (xy 91.349408 -315.843614) (xy 91.386143 -315.777297)
			(xy 91.429718 -315.715261) (xy 91.47964 -315.658208) (xy 91.535344 -315.606784) (xy 91.596199 -315.561573)
			(xy 91.661514 -315.523086) (xy 91.73055 -315.49176) (xy 91.802525 -315.46795) (xy 91.876623 -315.451925)
			(xy 91.952004 -315.443866) (xy 91.98991 -315.443362) (xy 92.027816 -315.443866) (xy 92.103197 -315.451925)
			(xy 92.177295 -315.46795) (xy 92.24927 -315.49176) (xy 92.318306 -315.523086) (xy 92.383621 -315.561573)
			(xy 92.444476 -315.606784) (xy 92.50018 -315.658208) (xy 92.550102 -315.715261) (xy 92.593677 -315.777297)
			(xy 92.630412 -315.843614) (xy 92.659889 -315.91346) (xy 92.681775 -315.986043) (xy 92.695822 -316.060541)
			(xy 92.701871 -316.136111) (xy 92.699852 -316.211895) (xy 92.68979 -316.287035) (xy 92.671798 -316.36068)
			(xy 92.64608 -316.431996) (xy 92.612928 -316.500173) (xy 92.572716 -316.564441) (xy 92.525901 -316.62407)
			(xy 92.473013 -316.678386) (xy 92.414651 -316.726772) (xy 92.351476 -316.76868) (xy 92.284205 -316.803636)
			(xy 92.2136 -316.831243) (xy 92.140459 -316.851189) (xy 92.065614 -316.863248) (xy 91.98991 -316.867283)
			(xy 91.914206 -316.863248) (xy 91.839361 -316.851189) (xy 91.76622 -316.831243) (xy 91.695615 -316.803636)
			(xy 91.628344 -316.76868) (xy 91.565169 -316.726772) (xy 91.506807 -316.678386) (xy 91.453919 -316.62407)
			(xy 91.407104 -316.564441) (xy 91.366892 -316.500173) (xy 91.33374 -316.431996) (xy 91.308022 -316.36068)
			(xy 91.29003 -316.287035) (xy 91.279968 -316.211895) (xy 91.277949 -316.136111) (xy 90.161871 -316.136111)
			(xy 90.159852 -316.211895) (xy 90.14979 -316.287035) (xy 90.131798 -316.36068) (xy 90.10608 -316.431996)
			(xy 90.072928 -316.500173) (xy 90.032716 -316.564441) (xy 89.985901 -316.62407) (xy 89.933013 -316.678386)
			(xy 89.874651 -316.726772) (xy 89.811476 -316.76868) (xy 89.744205 -316.803636) (xy 89.6736 -316.831243)
			(xy 89.600459 -316.851189) (xy 89.525614 -316.863248) (xy 89.44991 -316.867283) (xy 89.374206 -316.863248)
			(xy 89.299361 -316.851189) (xy 89.22622 -316.831243) (xy 89.155615 -316.803636) (xy 89.088344 -316.76868)
			(xy 89.025169 -316.726772) (xy 88.966807 -316.678386) (xy 88.913919 -316.62407) (xy 88.867104 -316.564441)
			(xy 88.826892 -316.500173) (xy 88.79374 -316.431996) (xy 88.768022 -316.36068) (xy 88.75003 -316.287035)
			(xy 88.739968 -316.211895) (xy 88.737949 -316.136111) (xy 87.621871 -316.136111) (xy 87.619852 -316.211895)
			(xy 87.60979 -316.287035) (xy 87.591798 -316.36068) (xy 87.56608 -316.431996) (xy 87.532928 -316.500173)
			(xy 87.492716 -316.564441) (xy 87.445901 -316.62407) (xy 87.393013 -316.678386) (xy 87.334651 -316.726772)
			(xy 87.271476 -316.76868) (xy 87.204205 -316.803636) (xy 87.1336 -316.831243) (xy 87.060459 -316.851189)
			(xy 86.985614 -316.863248) (xy 86.90991 -316.867283) (xy 86.834206 -316.863248) (xy 86.759361 -316.851189)
			(xy 86.68622 -316.831243) (xy 86.615615 -316.803636) (xy 86.548344 -316.76868) (xy 86.485169 -316.726772)
			(xy 86.426807 -316.678386) (xy 86.373919 -316.62407) (xy 86.327104 -316.564441) (xy 86.286892 -316.500173)
			(xy 86.25374 -316.431996) (xy 86.228022 -316.36068) (xy 86.21003 -316.287035) (xy 86.199968 -316.211895)
			(xy 86.197949 -316.136111) (xy 82.559813 -316.136111) (xy 82.594356 -316.161774) (xy 82.65006 -316.213198)
			(xy 82.699982 -316.270251) (xy 82.743557 -316.332287) (xy 82.780292 -316.398604) (xy 82.809769 -316.46845)
			(xy 82.831655 -316.541033) (xy 82.845702 -316.615531) (xy 82.851751 -316.691101) (xy 82.849732 -316.766885)
			(xy 82.83967 -316.842025) (xy 82.821678 -316.91567) (xy 82.79596 -316.986986) (xy 82.762808 -317.055163)
			(xy 82.722596 -317.119431) (xy 82.675781 -317.17906) (xy 82.622893 -317.233376) (xy 82.564531 -317.281762)
			(xy 82.501356 -317.32367) (xy 82.434085 -317.358626) (xy 82.36348 -317.386233) (xy 82.290588 -317.406111)
			(xy 84.927949 -317.406111) (xy 84.933998 -317.330541) (xy 84.948045 -317.256043) (xy 84.969931 -317.18346)
			(xy 84.999408 -317.113614) (xy 85.036143 -317.047297) (xy 85.079718 -316.985261) (xy 85.12964 -316.928208)
			(xy 85.185344 -316.876784) (xy 85.246199 -316.831573) (xy 85.311514 -316.793086) (xy 85.38055 -316.76176)
			(xy 85.452525 -316.73795) (xy 85.526623 -316.721925) (xy 85.602004 -316.713866) (xy 85.63991 -316.713362)
			(xy 85.677816 -316.713866) (xy 85.753197 -316.721925) (xy 85.827295 -316.73795) (xy 85.89927 -316.76176)
			(xy 85.968306 -316.793086) (xy 86.033621 -316.831573) (xy 86.094476 -316.876784) (xy 86.15018 -316.928208)
			(xy 86.200102 -316.985261) (xy 86.243677 -317.047297) (xy 86.280412 -317.113614) (xy 86.309889 -317.18346)
			(xy 86.331775 -317.256043) (xy 86.345822 -317.330541) (xy 86.351871 -317.406111) (xy 87.467949 -317.406111)
			(xy 87.473998 -317.330541) (xy 87.488045 -317.256043) (xy 87.509931 -317.18346) (xy 87.539408 -317.113614)
			(xy 87.576143 -317.047297) (xy 87.619718 -316.985261) (xy 87.66964 -316.928208) (xy 87.725344 -316.876784)
			(xy 87.786199 -316.831573) (xy 87.851514 -316.793086) (xy 87.92055 -316.76176) (xy 87.992525 -316.73795)
			(xy 88.066623 -316.721925) (xy 88.142004 -316.713866) (xy 88.17991 -316.713362) (xy 88.217816 -316.713866)
			(xy 88.293197 -316.721925) (xy 88.367295 -316.73795) (xy 88.43927 -316.76176) (xy 88.508306 -316.793086)
			(xy 88.573621 -316.831573) (xy 88.634476 -316.876784) (xy 88.69018 -316.928208) (xy 88.740102 -316.985261)
			(xy 88.783677 -317.047297) (xy 88.820412 -317.113614) (xy 88.849889 -317.18346) (xy 88.871775 -317.256043)
			(xy 88.885822 -317.330541) (xy 88.891871 -317.406111) (xy 90.007949 -317.406111) (xy 90.013998 -317.330541)
			(xy 90.028045 -317.256043) (xy 90.049931 -317.18346) (xy 90.079408 -317.113614) (xy 90.116143 -317.047297)
			(xy 90.159718 -316.985261) (xy 90.20964 -316.928208) (xy 90.265344 -316.876784) (xy 90.326199 -316.831573)
			(xy 90.391514 -316.793086) (xy 90.46055 -316.76176) (xy 90.532525 -316.73795) (xy 90.606623 -316.721925)
			(xy 90.682004 -316.713866) (xy 90.71991 -316.713362) (xy 90.757816 -316.713866) (xy 90.833197 -316.721925)
			(xy 90.907295 -316.73795) (xy 90.97927 -316.76176) (xy 91.048306 -316.793086) (xy 91.113621 -316.831573)
			(xy 91.174476 -316.876784) (xy 91.23018 -316.928208) (xy 91.280102 -316.985261) (xy 91.323677 -317.047297)
			(xy 91.360412 -317.113614) (xy 91.389889 -317.18346) (xy 91.411775 -317.256043) (xy 91.425822 -317.330541)
			(xy 91.431871 -317.406111) (xy 91.429852 -317.481895) (xy 91.41979 -317.557035) (xy 91.401798 -317.63068)
			(xy 91.37608 -317.701996) (xy 91.342928 -317.770173) (xy 91.302716 -317.834441) (xy 91.255901 -317.89407)
			(xy 91.203013 -317.948386) (xy 91.144651 -317.996772) (xy 91.081476 -318.03868) (xy 91.014205 -318.073636)
			(xy 90.9436 -318.101243) (xy 90.870459 -318.121189) (xy 90.795614 -318.133248) (xy 90.71991 -318.137283)
			(xy 90.644206 -318.133248) (xy 90.569361 -318.121189) (xy 90.49622 -318.101243) (xy 90.425615 -318.073636)
			(xy 90.358344 -318.03868) (xy 90.295169 -317.996772) (xy 90.236807 -317.948386) (xy 90.183919 -317.89407)
			(xy 90.137104 -317.834441) (xy 90.096892 -317.770173) (xy 90.06374 -317.701996) (xy 90.038022 -317.63068)
			(xy 90.02003 -317.557035) (xy 90.009968 -317.481895) (xy 90.007949 -317.406111) (xy 88.891871 -317.406111)
			(xy 88.889852 -317.481895) (xy 88.87979 -317.557035) (xy 88.861798 -317.63068) (xy 88.83608 -317.701996)
			(xy 88.802928 -317.770173) (xy 88.762716 -317.834441) (xy 88.715901 -317.89407) (xy 88.663013 -317.948386)
			(xy 88.604651 -317.996772) (xy 88.541476 -318.03868) (xy 88.474205 -318.073636) (xy 88.4036 -318.101243)
			(xy 88.330459 -318.121189) (xy 88.255614 -318.133248) (xy 88.17991 -318.137283) (xy 88.104206 -318.133248)
			(xy 88.029361 -318.121189) (xy 87.95622 -318.101243) (xy 87.885615 -318.073636) (xy 87.818344 -318.03868)
			(xy 87.755169 -317.996772) (xy 87.696807 -317.948386) (xy 87.643919 -317.89407) (xy 87.597104 -317.834441)
			(xy 87.556892 -317.770173) (xy 87.52374 -317.701996) (xy 87.498022 -317.63068) (xy 87.48003 -317.557035)
			(xy 87.469968 -317.481895) (xy 87.467949 -317.406111) (xy 86.351871 -317.406111) (xy 86.349852 -317.481895)
			(xy 86.33979 -317.557035) (xy 86.321798 -317.63068) (xy 86.29608 -317.701996) (xy 86.262928 -317.770173)
			(xy 86.222716 -317.834441) (xy 86.175901 -317.89407) (xy 86.123013 -317.948386) (xy 86.064651 -317.996772)
			(xy 86.001476 -318.03868) (xy 85.934205 -318.073636) (xy 85.8636 -318.101243) (xy 85.790459 -318.121189)
			(xy 85.715614 -318.133248) (xy 85.63991 -318.137283) (xy 85.564206 -318.133248) (xy 85.489361 -318.121189)
			(xy 85.41622 -318.101243) (xy 85.345615 -318.073636) (xy 85.278344 -318.03868) (xy 85.215169 -317.996772)
			(xy 85.156807 -317.948386) (xy 85.103919 -317.89407) (xy 85.057104 -317.834441) (xy 85.016892 -317.770173)
			(xy 84.98374 -317.701996) (xy 84.958022 -317.63068) (xy 84.94003 -317.557035) (xy 84.929968 -317.481895)
			(xy 84.927949 -317.406111) (xy 82.290588 -317.406111) (xy 82.290339 -317.406179) (xy 82.215494 -317.418238)
			(xy 82.13979 -317.422273) (xy 82.064086 -317.418238) (xy 81.989241 -317.406179) (xy 81.9161 -317.386233)
			(xy 81.845495 -317.358626) (xy 81.778224 -317.32367) (xy 81.715049 -317.281762) (xy 81.656687 -317.233376)
			(xy 81.603799 -317.17906) (xy 81.556984 -317.119431) (xy 81.516772 -317.055163) (xy 81.48362 -316.986986)
			(xy 81.457902 -316.91567) (xy 81.43991 -316.842025) (xy 81.429848 -316.766885) (xy 81.427829 -316.691101)
			(xy 80.311751 -316.691101) (xy 80.309732 -316.766885) (xy 80.29967 -316.842025) (xy 80.281678 -316.91567)
			(xy 80.25596 -316.986986) (xy 80.222808 -317.055163) (xy 80.182596 -317.119431) (xy 80.135781 -317.17906)
			(xy 80.082893 -317.233376) (xy 80.024531 -317.281762) (xy 79.961356 -317.32367) (xy 79.894085 -317.358626)
			(xy 79.82348 -317.386233) (xy 79.750339 -317.406179) (xy 79.675494 -317.418238) (xy 79.59979 -317.422273)
			(xy 79.524086 -317.418238) (xy 79.449241 -317.406179) (xy 79.3761 -317.386233) (xy 79.305495 -317.358626)
			(xy 79.238224 -317.32367) (xy 79.175049 -317.281762) (xy 79.116687 -317.233376) (xy 79.063799 -317.17906)
			(xy 79.016984 -317.119431) (xy 78.976772 -317.055163) (xy 78.94362 -316.986986) (xy 78.917902 -316.91567)
			(xy 78.89991 -316.842025) (xy 78.889848 -316.766885) (xy 78.887829 -316.691101) (xy 77.771751 -316.691101)
			(xy 77.769732 -316.766885) (xy 77.75967 -316.842025) (xy 77.741678 -316.91567) (xy 77.71596 -316.986986)
			(xy 77.682808 -317.055163) (xy 77.642596 -317.119431) (xy 77.595781 -317.17906) (xy 77.542893 -317.233376)
			(xy 77.484531 -317.281762) (xy 77.421356 -317.32367) (xy 77.354085 -317.358626) (xy 77.28348 -317.386233)
			(xy 77.210339 -317.406179) (xy 77.135494 -317.418238) (xy 77.05979 -317.422273) (xy 76.984086 -317.418238)
			(xy 76.909241 -317.406179) (xy 76.8361 -317.386233) (xy 76.765495 -317.358626) (xy 76.698224 -317.32367)
			(xy 76.635049 -317.281762) (xy 76.576687 -317.233376) (xy 76.523799 -317.17906) (xy 76.476984 -317.119431)
			(xy 76.436772 -317.055163) (xy 76.40362 -316.986986) (xy 76.377902 -316.91567) (xy 76.35991 -316.842025)
			(xy 76.349848 -316.766885) (xy 76.347829 -316.691101) (xy 75.231751 -316.691101) (xy 75.229732 -316.766885)
			(xy 75.21967 -316.842025) (xy 75.201678 -316.91567) (xy 75.17596 -316.986986) (xy 75.142808 -317.055163)
			(xy 75.102596 -317.119431) (xy 75.055781 -317.17906) (xy 75.002893 -317.233376) (xy 74.944531 -317.281762)
			(xy 74.881356 -317.32367) (xy 74.814085 -317.358626) (xy 74.74348 -317.386233) (xy 74.670339 -317.406179)
			(xy 74.595494 -317.418238) (xy 74.51979 -317.422273) (xy 74.444086 -317.418238) (xy 74.369241 -317.406179)
			(xy 74.2961 -317.386233) (xy 74.225495 -317.358626) (xy 74.158224 -317.32367) (xy 74.095049 -317.281762)
			(xy 74.036687 -317.233376) (xy 73.983799 -317.17906) (xy 73.936984 -317.119431) (xy 73.896772 -317.055163)
			(xy 73.86362 -316.986986) (xy 73.837902 -316.91567) (xy 73.81991 -316.842025) (xy 73.809848 -316.766885)
			(xy 73.807829 -316.691101) (xy 72.691751 -316.691101) (xy 72.689732 -316.766885) (xy 72.67967 -316.842025)
			(xy 72.661678 -316.91567) (xy 72.63596 -316.986986) (xy 72.602808 -317.055163) (xy 72.562596 -317.119431)
			(xy 72.515781 -317.17906) (xy 72.462893 -317.233376) (xy 72.404531 -317.281762) (xy 72.341356 -317.32367)
			(xy 72.274085 -317.358626) (xy 72.20348 -317.386233) (xy 72.130339 -317.406179) (xy 72.055494 -317.418238)
			(xy 71.97979 -317.422273) (xy 71.904086 -317.418238) (xy 71.829241 -317.406179) (xy 71.7561 -317.386233)
			(xy 71.685495 -317.358626) (xy 71.618224 -317.32367) (xy 71.555049 -317.281762) (xy 71.496687 -317.233376)
			(xy 71.443799 -317.17906) (xy 71.396984 -317.119431) (xy 71.356772 -317.055163) (xy 71.32362 -316.986986)
			(xy 71.297902 -316.91567) (xy 71.27991 -316.842025) (xy 71.269848 -316.766885) (xy 71.267829 -316.691101)
			(xy 70.151751 -316.691101) (xy 70.149732 -316.766885) (xy 70.13967 -316.842025) (xy 70.121678 -316.91567)
			(xy 70.09596 -316.986986) (xy 70.062808 -317.055163) (xy 70.022596 -317.119431) (xy 69.975781 -317.17906)
			(xy 69.922893 -317.233376) (xy 69.864531 -317.281762) (xy 69.801356 -317.32367) (xy 69.734085 -317.358626)
			(xy 69.66348 -317.386233) (xy 69.590339 -317.406179) (xy 69.515494 -317.418238) (xy 69.43979 -317.422273)
			(xy 69.364086 -317.418238) (xy 69.289241 -317.406179) (xy 69.2161 -317.386233) (xy 69.145495 -317.358626)
			(xy 69.078224 -317.32367) (xy 69.015049 -317.281762) (xy 68.956687 -317.233376) (xy 68.903799 -317.17906)
			(xy 68.856984 -317.119431) (xy 68.816772 -317.055163) (xy 68.78362 -316.986986) (xy 68.757902 -316.91567)
			(xy 68.73991 -316.842025) (xy 68.729848 -316.766885) (xy 68.727829 -316.691101) (xy 67.611751 -316.691101)
			(xy 67.609732 -316.766885) (xy 67.59967 -316.842025) (xy 67.581678 -316.91567) (xy 67.55596 -316.986986)
			(xy 67.522808 -317.055163) (xy 67.482596 -317.119431) (xy 67.435781 -317.17906) (xy 67.382893 -317.233376)
			(xy 67.324531 -317.281762) (xy 67.261356 -317.32367) (xy 67.194085 -317.358626) (xy 67.12348 -317.386233)
			(xy 67.050339 -317.406179) (xy 66.975494 -317.418238) (xy 66.89979 -317.422273) (xy 66.824086 -317.418238)
			(xy 66.749241 -317.406179) (xy 66.6761 -317.386233) (xy 66.605495 -317.358626) (xy 66.538224 -317.32367)
			(xy 66.475049 -317.281762) (xy 66.416687 -317.233376) (xy 66.363799 -317.17906) (xy 66.316984 -317.119431)
			(xy 66.276772 -317.055163) (xy 66.24362 -316.986986) (xy 66.217902 -316.91567) (xy 66.19991 -316.842025)
			(xy 66.189848 -316.766885) (xy 66.187829 -316.691101) (xy 65.071751 -316.691101) (xy 65.069732 -316.766885)
			(xy 65.05967 -316.842025) (xy 65.041678 -316.91567) (xy 65.01596 -316.986986) (xy 64.982808 -317.055163)
			(xy 64.942596 -317.119431) (xy 64.895781 -317.17906) (xy 64.842893 -317.233376) (xy 64.784531 -317.281762)
			(xy 64.721356 -317.32367) (xy 64.654085 -317.358626) (xy 64.58348 -317.386233) (xy 64.510339 -317.406179)
			(xy 64.435494 -317.418238) (xy 64.35979 -317.422273) (xy 64.284086 -317.418238) (xy 64.209241 -317.406179)
			(xy 64.1361 -317.386233) (xy 64.065495 -317.358626) (xy 63.998224 -317.32367) (xy 63.935049 -317.281762)
			(xy 63.876687 -317.233376) (xy 63.823799 -317.17906) (xy 63.776984 -317.119431) (xy 63.736772 -317.055163)
			(xy 63.70362 -316.986986) (xy 63.677902 -316.91567) (xy 63.65991 -316.842025) (xy 63.649848 -316.766885)
			(xy 63.647829 -316.691101) (xy 42.474432 -316.691101) (xy 42.525324 -316.727542) (xy 42.614813 -316.801469)
			(xy 42.698988 -316.881395) (xy 42.777449 -316.966938) (xy 42.849821 -317.057689) (xy 42.91576 -317.153218)
			(xy 42.974951 -317.253068) (xy 43.027112 -317.356764) (xy 43.071995 -317.463811) (xy 43.109385 -317.5737)
			(xy 43.139105 -317.685907) (xy 43.161013 -317.799897) (xy 43.175004 -317.915126) (xy 43.181013 -318.031047)
			(xy 43.179009 -318.147105) (xy 43.169003 -318.262749) (xy 43.151043 -318.377427) (xy 43.125213 -318.490593)
			(xy 43.091638 -318.601707) (xy 43.06342 -318.676111) (xy 86.197949 -318.676111) (xy 86.203998 -318.600541)
			(xy 86.218045 -318.526043) (xy 86.239931 -318.45346) (xy 86.269408 -318.383614) (xy 86.306143 -318.317297)
			(xy 86.349718 -318.255261) (xy 86.39964 -318.198208) (xy 86.455344 -318.146784) (xy 86.516199 -318.101573)
			(xy 86.581514 -318.063086) (xy 86.65055 -318.03176) (xy 86.722525 -318.00795) (xy 86.796623 -317.991925)
			(xy 86.872004 -317.983866) (xy 86.90991 -317.983362) (xy 86.947816 -317.983866) (xy 87.023197 -317.991925)
			(xy 87.097295 -318.00795) (xy 87.16927 -318.03176) (xy 87.238306 -318.063086) (xy 87.303621 -318.101573)
			(xy 87.364476 -318.146784) (xy 87.42018 -318.198208) (xy 87.470102 -318.255261) (xy 87.513677 -318.317297)
			(xy 87.550412 -318.383614) (xy 87.579889 -318.45346) (xy 87.601775 -318.526043) (xy 87.615822 -318.600541)
			(xy 87.621871 -318.676111) (xy 88.737949 -318.676111) (xy 88.743998 -318.600541) (xy 88.758045 -318.526043)
			(xy 88.779931 -318.45346) (xy 88.809408 -318.383614) (xy 88.846143 -318.317297) (xy 88.889718 -318.255261)
			(xy 88.93964 -318.198208) (xy 88.995344 -318.146784) (xy 89.056199 -318.101573) (xy 89.121514 -318.063086)
			(xy 89.19055 -318.03176) (xy 89.262525 -318.00795) (xy 89.336623 -317.991925) (xy 89.412004 -317.983866)
			(xy 89.44991 -317.983362) (xy 89.487816 -317.983866) (xy 89.563197 -317.991925) (xy 89.637295 -318.00795)
			(xy 89.70927 -318.03176) (xy 89.778306 -318.063086) (xy 89.843621 -318.101573) (xy 89.904476 -318.146784)
			(xy 89.96018 -318.198208) (xy 90.010102 -318.255261) (xy 90.053677 -318.317297) (xy 90.090412 -318.383614)
			(xy 90.119889 -318.45346) (xy 90.141775 -318.526043) (xy 90.155822 -318.600541) (xy 90.161871 -318.676111)
			(xy 91.277949 -318.676111) (xy 91.283998 -318.600541) (xy 91.298045 -318.526043) (xy 91.319931 -318.45346)
			(xy 91.349408 -318.383614) (xy 91.386143 -318.317297) (xy 91.429718 -318.255261) (xy 91.47964 -318.198208)
			(xy 91.535344 -318.146784) (xy 91.596199 -318.101573) (xy 91.661514 -318.063086) (xy 91.73055 -318.03176)
			(xy 91.802525 -318.00795) (xy 91.876623 -317.991925) (xy 91.952004 -317.983866) (xy 91.98991 -317.983362)
			(xy 92.027816 -317.983866) (xy 92.103197 -317.991925) (xy 92.177295 -318.00795) (xy 92.24927 -318.03176)
			(xy 92.318306 -318.063086) (xy 92.383621 -318.101573) (xy 92.444476 -318.146784) (xy 92.50018 -318.198208)
			(xy 92.550102 -318.255261) (xy 92.593677 -318.317297) (xy 92.630412 -318.383614) (xy 92.659889 -318.45346)
			(xy 92.681775 -318.526043) (xy 92.695822 -318.600541) (xy 92.701871 -318.676111) (xy 92.699852 -318.751895)
			(xy 92.68979 -318.827035) (xy 92.671798 -318.90068) (xy 92.64608 -318.971996) (xy 92.612928 -319.040173)
			(xy 92.572716 -319.104441) (xy 92.525901 -319.16407) (xy 92.473013 -319.218386) (xy 92.414651 -319.266772)
			(xy 92.351476 -319.30868) (xy 92.284205 -319.343636) (xy 92.2136 -319.371243) (xy 92.177855 -319.380991)
			(xy 93.154757 -319.380991) (xy 93.160779 -319.264808) (xy 93.174802 -319.149317) (xy 93.19676 -319.035069)
			(xy 93.226547 -318.922608) (xy 93.264022 -318.81247) (xy 93.309007 -318.70518) (xy 93.361286 -318.601249)
			(xy 93.420611 -318.501173) (xy 93.486699 -318.405427) (xy 93.559235 -318.31447) (xy 93.637874 -318.228734)
			(xy 93.72224 -318.148627) (xy 93.811932 -318.074531) (xy 93.906522 -318.006801) (xy 94.00556 -317.945757)
			(xy 94.108573 -317.891692) (xy 94.21507 -317.844862) (xy 94.324545 -317.805491) (xy 94.436475 -317.773767)
			(xy 94.550327 -317.749841) (xy 94.665559 -317.733827) (xy 94.781621 -317.7258) (xy 94.83979 -317.725298)
			(xy 94.897959 -317.7258) (xy 95.014021 -317.733827) (xy 95.129253 -317.749841) (xy 95.243105 -317.773767)
			(xy 95.355035 -317.805491) (xy 95.46451 -317.844862) (xy 95.571007 -317.891692) (xy 95.67402 -317.945757)
			(xy 95.773058 -318.006801) (xy 95.867648 -318.074531) (xy 95.95734 -318.148627) (xy 96.041706 -318.228734)
			(xy 96.120345 -318.31447) (xy 96.192881 -318.405427) (xy 96.258969 -318.501173) (xy 96.318294 -318.601249)
			(xy 96.370573 -318.70518) (xy 96.415558 -318.81247) (xy 96.453033 -318.922608) (xy 96.48282 -319.035069)
			(xy 96.504778 -319.149317) (xy 96.518801 -319.264808) (xy 96.524823 -319.380991) (xy 96.522815 -319.497313)
			(xy 96.512786 -319.613219) (xy 96.494785 -319.728156) (xy 96.468897 -319.841579) (xy 96.435246 -319.952944)
			(xy 96.393992 -320.061723) (xy 96.345331 -320.167397) (xy 96.289495 -320.269461) (xy 96.226752 -320.36743)
			(xy 96.157398 -320.460837) (xy 96.081766 -320.549237) (xy 96.000215 -320.632208) (xy 95.913134 -320.709355)
			(xy 95.820938 -320.78031) (xy 95.724066 -320.844736) (xy 95.622981 -320.902325) (xy 95.518163 -320.952802)
			(xy 95.410112 -320.995928) (xy 95.299344 -321.031497) (xy 95.186385 -321.059339) (xy 95.071775 -321.079321)
			(xy 94.95606 -321.091348) (xy 94.83979 -321.095364) (xy 94.72352 -321.091348) (xy 94.607805 -321.079321)
			(xy 94.493195 -321.059339) (xy 94.380236 -321.031497) (xy 94.269468 -320.995928) (xy 94.161417 -320.952802)
			(xy 94.056599 -320.902325) (xy 93.955514 -320.844736) (xy 93.858642 -320.78031) (xy 93.766446 -320.709355)
			(xy 93.679365 -320.632208) (xy 93.597814 -320.549237) (xy 93.522182 -320.460837) (xy 93.452828 -320.36743)
			(xy 93.390085 -320.269461) (xy 93.334249 -320.167397) (xy 93.285588 -320.061723) (xy 93.244334 -319.952944)
			(xy 93.210683 -319.841579) (xy 93.184795 -319.728156) (xy 93.166794 -319.613219) (xy 93.156765 -319.497313)
			(xy 93.154757 -319.380991) (xy 92.177855 -319.380991) (xy 92.140459 -319.391189) (xy 92.065614 -319.403248)
			(xy 91.98991 -319.407283) (xy 91.914206 -319.403248) (xy 91.839361 -319.391189) (xy 91.76622 -319.371243)
			(xy 91.695615 -319.343636) (xy 91.628344 -319.30868) (xy 91.565169 -319.266772) (xy 91.506807 -319.218386)
			(xy 91.453919 -319.16407) (xy 91.407104 -319.104441) (xy 91.366892 -319.040173) (xy 91.33374 -318.971996)
			(xy 91.308022 -318.90068) (xy 91.29003 -318.827035) (xy 91.279968 -318.751895) (xy 91.277949 -318.676111)
			(xy 90.161871 -318.676111) (xy 90.159852 -318.751895) (xy 90.14979 -318.827035) (xy 90.131798 -318.90068)
			(xy 90.10608 -318.971996) (xy 90.072928 -319.040173) (xy 90.032716 -319.104441) (xy 89.985901 -319.16407)
			(xy 89.933013 -319.218386) (xy 89.874651 -319.266772) (xy 89.811476 -319.30868) (xy 89.744205 -319.343636)
			(xy 89.6736 -319.371243) (xy 89.600459 -319.391189) (xy 89.525614 -319.403248) (xy 89.44991 -319.407283)
			(xy 89.374206 -319.403248) (xy 89.299361 -319.391189) (xy 89.22622 -319.371243) (xy 89.155615 -319.343636)
			(xy 89.088344 -319.30868) (xy 89.025169 -319.266772) (xy 88.966807 -319.218386) (xy 88.913919 -319.16407)
			(xy 88.867104 -319.104441) (xy 88.826892 -319.040173) (xy 88.79374 -318.971996) (xy 88.768022 -318.90068)
			(xy 88.75003 -318.827035) (xy 88.739968 -318.751895) (xy 88.737949 -318.676111) (xy 87.621871 -318.676111)
			(xy 87.619852 -318.751895) (xy 87.60979 -318.827035) (xy 87.591798 -318.90068) (xy 87.56608 -318.971996)
			(xy 87.532928 -319.040173) (xy 87.492716 -319.104441) (xy 87.445901 -319.16407) (xy 87.393013 -319.218386)
			(xy 87.334651 -319.266772) (xy 87.271476 -319.30868) (xy 87.204205 -319.343636) (xy 87.1336 -319.371243)
			(xy 87.060459 -319.391189) (xy 86.985614 -319.403248) (xy 86.90991 -319.407283) (xy 86.834206 -319.403248)
			(xy 86.759361 -319.391189) (xy 86.68622 -319.371243) (xy 86.615615 -319.343636) (xy 86.548344 -319.30868)
			(xy 86.485169 -319.266772) (xy 86.426807 -319.218386) (xy 86.373919 -319.16407) (xy 86.327104 -319.104441)
			(xy 86.286892 -319.040173) (xy 86.25374 -318.971996) (xy 86.228022 -318.90068) (xy 86.21003 -318.827035)
			(xy 86.199968 -318.751895) (xy 86.197949 -318.676111) (xy 43.06342 -318.676111) (xy 43.050477 -318.71024)
			(xy 43.001926 -318.815674) (xy 42.946217 -318.917508) (xy 42.883615 -319.015256) (xy 42.814419 -319.108451)
			(xy 42.738957 -319.196651) (xy 42.65759 -319.279434) (xy 42.570706 -319.356407) (xy 42.525601 -319.391121)
			(xy 63.647829 -319.391121) (xy 63.653878 -319.315551) (xy 63.667925 -319.241053) (xy 63.689811 -319.16847)
			(xy 63.719288 -319.098624) (xy 63.756023 -319.032307) (xy 63.799598 -318.970271) (xy 63.84952 -318.913218)
			(xy 63.905224 -318.861794) (xy 63.966079 -318.816583) (xy 64.031394 -318.778096) (xy 64.10043 -318.74677)
			(xy 64.172405 -318.72296) (xy 64.246503 -318.706935) (xy 64.321884 -318.698876) (xy 64.35979 -318.698372)
			(xy 64.397696 -318.698876) (xy 64.473077 -318.706935) (xy 64.547175 -318.72296) (xy 64.61915 -318.74677)
			(xy 64.688186 -318.778096) (xy 64.753501 -318.816583) (xy 64.814356 -318.861794) (xy 64.87006 -318.913218)
			(xy 64.919982 -318.970271) (xy 64.963557 -319.032307) (xy 65.000292 -319.098624) (xy 65.029769 -319.16847)
			(xy 65.051655 -319.241053) (xy 65.065702 -319.315551) (xy 65.071751 -319.391121) (xy 66.187829 -319.391121)
			(xy 66.193878 -319.315551) (xy 66.207925 -319.241053) (xy 66.229811 -319.16847) (xy 66.259288 -319.098624)
			(xy 66.296023 -319.032307) (xy 66.339598 -318.970271) (xy 66.38952 -318.913218) (xy 66.445224 -318.861794)
			(xy 66.506079 -318.816583) (xy 66.571394 -318.778096) (xy 66.64043 -318.74677) (xy 66.712405 -318.72296)
			(xy 66.786503 -318.706935) (xy 66.861884 -318.698876) (xy 66.89979 -318.698372) (xy 66.937696 -318.698876)
			(xy 67.013077 -318.706935) (xy 67.087175 -318.72296) (xy 67.15915 -318.74677) (xy 67.228186 -318.778096)
			(xy 67.293501 -318.816583) (xy 67.354356 -318.861794) (xy 67.41006 -318.913218) (xy 67.459982 -318.970271)
			(xy 67.503557 -319.032307) (xy 67.540292 -319.098624) (xy 67.569769 -319.16847) (xy 67.591655 -319.241053)
			(xy 67.605702 -319.315551) (xy 67.611751 -319.391121) (xy 68.727829 -319.391121) (xy 68.733878 -319.315551)
			(xy 68.747925 -319.241053) (xy 68.769811 -319.16847) (xy 68.799288 -319.098624) (xy 68.836023 -319.032307)
			(xy 68.879598 -318.970271) (xy 68.92952 -318.913218) (xy 68.985224 -318.861794) (xy 69.046079 -318.816583)
			(xy 69.111394 -318.778096) (xy 69.18043 -318.74677) (xy 69.252405 -318.72296) (xy 69.326503 -318.706935)
			(xy 69.401884 -318.698876) (xy 69.43979 -318.698372) (xy 69.477696 -318.698876) (xy 69.553077 -318.706935)
			(xy 69.627175 -318.72296) (xy 69.69915 -318.74677) (xy 69.768186 -318.778096) (xy 69.833501 -318.816583)
			(xy 69.894356 -318.861794) (xy 69.95006 -318.913218) (xy 69.999982 -318.970271) (xy 70.043557 -319.032307)
			(xy 70.080292 -319.098624) (xy 70.109769 -319.16847) (xy 70.131655 -319.241053) (xy 70.145702 -319.315551)
			(xy 70.151751 -319.391121) (xy 71.267829 -319.391121) (xy 71.273878 -319.315551) (xy 71.287925 -319.241053)
			(xy 71.309811 -319.16847) (xy 71.339288 -319.098624) (xy 71.376023 -319.032307) (xy 71.419598 -318.970271)
			(xy 71.46952 -318.913218) (xy 71.525224 -318.861794) (xy 71.586079 -318.816583) (xy 71.651394 -318.778096)
			(xy 71.72043 -318.74677) (xy 71.792405 -318.72296) (xy 71.866503 -318.706935) (xy 71.941884 -318.698876)
			(xy 71.97979 -318.698372) (xy 72.017696 -318.698876) (xy 72.093077 -318.706935) (xy 72.167175 -318.72296)
			(xy 72.23915 -318.74677) (xy 72.308186 -318.778096) (xy 72.373501 -318.816583) (xy 72.434356 -318.861794)
			(xy 72.49006 -318.913218) (xy 72.539982 -318.970271) (xy 72.583557 -319.032307) (xy 72.620292 -319.098624)
			(xy 72.649769 -319.16847) (xy 72.671655 -319.241053) (xy 72.685702 -319.315551) (xy 72.691751 -319.391121)
			(xy 73.807829 -319.391121) (xy 73.813878 -319.315551) (xy 73.827925 -319.241053) (xy 73.849811 -319.16847)
			(xy 73.879288 -319.098624) (xy 73.916023 -319.032307) (xy 73.959598 -318.970271) (xy 74.00952 -318.913218)
			(xy 74.065224 -318.861794) (xy 74.126079 -318.816583) (xy 74.191394 -318.778096) (xy 74.26043 -318.74677)
			(xy 74.332405 -318.72296) (xy 74.406503 -318.706935) (xy 74.481884 -318.698876) (xy 74.51979 -318.698372)
			(xy 74.557696 -318.698876) (xy 74.633077 -318.706935) (xy 74.707175 -318.72296) (xy 74.77915 -318.74677)
			(xy 74.848186 -318.778096) (xy 74.913501 -318.816583) (xy 74.974356 -318.861794) (xy 75.03006 -318.913218)
			(xy 75.079982 -318.970271) (xy 75.123557 -319.032307) (xy 75.160292 -319.098624) (xy 75.189769 -319.16847)
			(xy 75.211655 -319.241053) (xy 75.225702 -319.315551) (xy 75.231751 -319.391121) (xy 76.347829 -319.391121)
			(xy 76.353878 -319.315551) (xy 76.367925 -319.241053) (xy 76.389811 -319.16847) (xy 76.419288 -319.098624)
			(xy 76.456023 -319.032307) (xy 76.499598 -318.970271) (xy 76.54952 -318.913218) (xy 76.605224 -318.861794)
			(xy 76.666079 -318.816583) (xy 76.731394 -318.778096) (xy 76.80043 -318.74677) (xy 76.872405 -318.72296)
			(xy 76.946503 -318.706935) (xy 77.021884 -318.698876) (xy 77.05979 -318.698372) (xy 77.097696 -318.698876)
			(xy 77.173077 -318.706935) (xy 77.247175 -318.72296) (xy 77.31915 -318.74677) (xy 77.388186 -318.778096)
			(xy 77.453501 -318.816583) (xy 77.514356 -318.861794) (xy 77.57006 -318.913218) (xy 77.619982 -318.970271)
			(xy 77.663557 -319.032307) (xy 77.700292 -319.098624) (xy 77.729769 -319.16847) (xy 77.751655 -319.241053)
			(xy 77.765702 -319.315551) (xy 77.771751 -319.391121) (xy 78.887829 -319.391121) (xy 78.893878 -319.315551)
			(xy 78.907925 -319.241053) (xy 78.929811 -319.16847) (xy 78.959288 -319.098624) (xy 78.996023 -319.032307)
			(xy 79.039598 -318.970271) (xy 79.08952 -318.913218) (xy 79.145224 -318.861794) (xy 79.206079 -318.816583)
			(xy 79.271394 -318.778096) (xy 79.34043 -318.74677) (xy 79.412405 -318.72296) (xy 79.486503 -318.706935)
			(xy 79.561884 -318.698876) (xy 79.59979 -318.698372) (xy 79.637696 -318.698876) (xy 79.713077 -318.706935)
			(xy 79.787175 -318.72296) (xy 79.85915 -318.74677) (xy 79.928186 -318.778096) (xy 79.993501 -318.816583)
			(xy 80.054356 -318.861794) (xy 80.11006 -318.913218) (xy 80.159982 -318.970271) (xy 80.203557 -319.032307)
			(xy 80.240292 -319.098624) (xy 80.269769 -319.16847) (xy 80.291655 -319.241053) (xy 80.305702 -319.315551)
			(xy 80.311751 -319.391121) (xy 81.427829 -319.391121) (xy 81.433878 -319.315551) (xy 81.447925 -319.241053)
			(xy 81.469811 -319.16847) (xy 81.499288 -319.098624) (xy 81.536023 -319.032307) (xy 81.579598 -318.970271)
			(xy 81.62952 -318.913218) (xy 81.685224 -318.861794) (xy 81.746079 -318.816583) (xy 81.811394 -318.778096)
			(xy 81.88043 -318.74677) (xy 81.952405 -318.72296) (xy 82.026503 -318.706935) (xy 82.101884 -318.698876)
			(xy 82.13979 -318.698372) (xy 82.177696 -318.698876) (xy 82.253077 -318.706935) (xy 82.327175 -318.72296)
			(xy 82.39915 -318.74677) (xy 82.468186 -318.778096) (xy 82.533501 -318.816583) (xy 82.594356 -318.861794)
			(xy 82.65006 -318.913218) (xy 82.699982 -318.970271) (xy 82.743557 -319.032307) (xy 82.780292 -319.098624)
			(xy 82.809769 -319.16847) (xy 82.831655 -319.241053) (xy 82.845702 -319.315551) (xy 82.851751 -319.391121)
			(xy 82.849732 -319.466905) (xy 82.83967 -319.542045) (xy 82.821678 -319.61569) (xy 82.79596 -319.687006)
			(xy 82.762808 -319.755183) (xy 82.722596 -319.819451) (xy 82.675781 -319.87908) (xy 82.622893 -319.933396)
			(xy 82.607556 -319.946111) (xy 84.927949 -319.946111) (xy 84.933998 -319.870541) (xy 84.948045 -319.796043)
			(xy 84.969931 -319.72346) (xy 84.999408 -319.653614) (xy 85.036143 -319.587297) (xy 85.079718 -319.525261)
			(xy 85.12964 -319.468208) (xy 85.185344 -319.416784) (xy 85.246199 -319.371573) (xy 85.311514 -319.333086)
			(xy 85.38055 -319.30176) (xy 85.452525 -319.27795) (xy 85.526623 -319.261925) (xy 85.602004 -319.253866)
			(xy 85.63991 -319.253362) (xy 85.677816 -319.253866) (xy 85.753197 -319.261925) (xy 85.827295 -319.27795)
			(xy 85.89927 -319.30176) (xy 85.968306 -319.333086) (xy 86.033621 -319.371573) (xy 86.094476 -319.416784)
			(xy 86.15018 -319.468208) (xy 86.200102 -319.525261) (xy 86.243677 -319.587297) (xy 86.280412 -319.653614)
			(xy 86.309889 -319.72346) (xy 86.331775 -319.796043) (xy 86.345822 -319.870541) (xy 86.351871 -319.946111)
			(xy 87.467949 -319.946111) (xy 87.473998 -319.870541) (xy 87.488045 -319.796043) (xy 87.509931 -319.72346)
			(xy 87.539408 -319.653614) (xy 87.576143 -319.587297) (xy 87.619718 -319.525261) (xy 87.66964 -319.468208)
			(xy 87.725344 -319.416784) (xy 87.786199 -319.371573) (xy 87.851514 -319.333086) (xy 87.92055 -319.30176)
			(xy 87.992525 -319.27795) (xy 88.066623 -319.261925) (xy 88.142004 -319.253866) (xy 88.17991 -319.253362)
			(xy 88.217816 -319.253866) (xy 88.293197 -319.261925) (xy 88.367295 -319.27795) (xy 88.43927 -319.30176)
			(xy 88.508306 -319.333086) (xy 88.573621 -319.371573) (xy 88.634476 -319.416784) (xy 88.69018 -319.468208)
			(xy 88.740102 -319.525261) (xy 88.783677 -319.587297) (xy 88.820412 -319.653614) (xy 88.849889 -319.72346)
			(xy 88.871775 -319.796043) (xy 88.885822 -319.870541) (xy 88.891871 -319.946111) (xy 90.007949 -319.946111)
			(xy 90.013998 -319.870541) (xy 90.028045 -319.796043) (xy 90.049931 -319.72346) (xy 90.079408 -319.653614)
			(xy 90.116143 -319.587297) (xy 90.159718 -319.525261) (xy 90.20964 -319.468208) (xy 90.265344 -319.416784)
			(xy 90.326199 -319.371573) (xy 90.391514 -319.333086) (xy 90.46055 -319.30176) (xy 90.532525 -319.27795)
			(xy 90.606623 -319.261925) (xy 90.682004 -319.253866) (xy 90.71991 -319.253362) (xy 90.757816 -319.253866)
			(xy 90.833197 -319.261925) (xy 90.907295 -319.27795) (xy 90.97927 -319.30176) (xy 91.048306 -319.333086)
			(xy 91.113621 -319.371573) (xy 91.174476 -319.416784) (xy 91.23018 -319.468208) (xy 91.280102 -319.525261)
			(xy 91.323677 -319.587297) (xy 91.360412 -319.653614) (xy 91.389889 -319.72346) (xy 91.411775 -319.796043)
			(xy 91.425822 -319.870541) (xy 91.431871 -319.946111) (xy 91.429852 -320.021895) (xy 91.41979 -320.097035)
			(xy 91.401798 -320.17068) (xy 91.37608 -320.241996) (xy 91.342928 -320.310173) (xy 91.302716 -320.374441)
			(xy 91.255901 -320.43407) (xy 91.203013 -320.488386) (xy 91.144651 -320.536772) (xy 91.081476 -320.57868)
			(xy 91.014205 -320.613636) (xy 90.9436 -320.641243) (xy 90.870459 -320.661189) (xy 90.795614 -320.673248)
			(xy 90.71991 -320.677283) (xy 90.644206 -320.673248) (xy 90.569361 -320.661189) (xy 90.49622 -320.641243)
			(xy 90.425615 -320.613636) (xy 90.358344 -320.57868) (xy 90.295169 -320.536772) (xy 90.236807 -320.488386)
			(xy 90.183919 -320.43407) (xy 90.137104 -320.374441) (xy 90.096892 -320.310173) (xy 90.06374 -320.241996)
			(xy 90.038022 -320.17068) (xy 90.02003 -320.097035) (xy 90.009968 -320.021895) (xy 90.007949 -319.946111)
			(xy 88.891871 -319.946111) (xy 88.889852 -320.021895) (xy 88.87979 -320.097035) (xy 88.861798 -320.17068)
			(xy 88.83608 -320.241996) (xy 88.802928 -320.310173) (xy 88.762716 -320.374441) (xy 88.715901 -320.43407)
			(xy 88.663013 -320.488386) (xy 88.604651 -320.536772) (xy 88.541476 -320.57868) (xy 88.474205 -320.613636)
			(xy 88.4036 -320.641243) (xy 88.330459 -320.661189) (xy 88.255614 -320.673248) (xy 88.17991 -320.677283)
			(xy 88.104206 -320.673248) (xy 88.029361 -320.661189) (xy 87.95622 -320.641243) (xy 87.885615 -320.613636)
			(xy 87.818344 -320.57868) (xy 87.755169 -320.536772) (xy 87.696807 -320.488386) (xy 87.643919 -320.43407)
			(xy 87.597104 -320.374441) (xy 87.556892 -320.310173) (xy 87.52374 -320.241996) (xy 87.498022 -320.17068)
			(xy 87.48003 -320.097035) (xy 87.469968 -320.021895) (xy 87.467949 -319.946111) (xy 86.351871 -319.946111)
			(xy 86.349852 -320.021895) (xy 86.33979 -320.097035) (xy 86.321798 -320.17068) (xy 86.29608 -320.241996)
			(xy 86.262928 -320.310173) (xy 86.222716 -320.374441) (xy 86.175901 -320.43407) (xy 86.123013 -320.488386)
			(xy 86.064651 -320.536772) (xy 86.001476 -320.57868) (xy 85.934205 -320.613636) (xy 85.8636 -320.641243)
			(xy 85.790459 -320.661189) (xy 85.715614 -320.673248) (xy 85.63991 -320.677283) (xy 85.564206 -320.673248)
			(xy 85.489361 -320.661189) (xy 85.41622 -320.641243) (xy 85.345615 -320.613636) (xy 85.278344 -320.57868)
			(xy 85.215169 -320.536772) (xy 85.156807 -320.488386) (xy 85.103919 -320.43407) (xy 85.057104 -320.374441)
			(xy 85.016892 -320.310173) (xy 84.98374 -320.241996) (xy 84.958022 -320.17068) (xy 84.94003 -320.097035)
			(xy 84.929968 -320.021895) (xy 84.927949 -319.946111) (xy 82.607556 -319.946111) (xy 82.564531 -319.981782)
			(xy 82.501356 -320.02369) (xy 82.434085 -320.058646) (xy 82.36348 -320.086253) (xy 82.290339 -320.106199)
			(xy 82.215494 -320.118258) (xy 82.13979 -320.122293) (xy 82.064086 -320.118258) (xy 81.989241 -320.106199)
			(xy 81.9161 -320.086253) (xy 81.845495 -320.058646) (xy 81.778224 -320.02369) (xy 81.715049 -319.981782)
			(xy 81.656687 -319.933396) (xy 81.603799 -319.87908) (xy 81.556984 -319.819451) (xy 81.516772 -319.755183)
			(xy 81.48362 -319.687006) (xy 81.457902 -319.61569) (xy 81.43991 -319.542045) (xy 81.429848 -319.466905)
			(xy 81.427829 -319.391121) (xy 80.311751 -319.391121) (xy 80.309732 -319.466905) (xy 80.29967 -319.542045)
			(xy 80.281678 -319.61569) (xy 80.25596 -319.687006) (xy 80.222808 -319.755183) (xy 80.182596 -319.819451)
			(xy 80.135781 -319.87908) (xy 80.082893 -319.933396) (xy 80.024531 -319.981782) (xy 79.961356 -320.02369)
			(xy 79.894085 -320.058646) (xy 79.82348 -320.086253) (xy 79.750339 -320.106199) (xy 79.675494 -320.118258)
			(xy 79.59979 -320.122293) (xy 79.524086 -320.118258) (xy 79.449241 -320.106199) (xy 79.3761 -320.086253)
			(xy 79.305495 -320.058646) (xy 79.238224 -320.02369) (xy 79.175049 -319.981782) (xy 79.116687 -319.933396)
			(xy 79.063799 -319.87908) (xy 79.016984 -319.819451) (xy 78.976772 -319.755183) (xy 78.94362 -319.687006)
			(xy 78.917902 -319.61569) (xy 78.89991 -319.542045) (xy 78.889848 -319.466905) (xy 78.887829 -319.391121)
			(xy 77.771751 -319.391121) (xy 77.769732 -319.466905) (xy 77.75967 -319.542045) (xy 77.741678 -319.61569)
			(xy 77.71596 -319.687006) (xy 77.682808 -319.755183) (xy 77.642596 -319.819451) (xy 77.595781 -319.87908)
			(xy 77.542893 -319.933396) (xy 77.484531 -319.981782) (xy 77.421356 -320.02369) (xy 77.354085 -320.058646)
			(xy 77.28348 -320.086253) (xy 77.210339 -320.106199) (xy 77.135494 -320.118258) (xy 77.05979 -320.122293)
			(xy 76.984086 -320.118258) (xy 76.909241 -320.106199) (xy 76.8361 -320.086253) (xy 76.765495 -320.058646)
			(xy 76.698224 -320.02369) (xy 76.635049 -319.981782) (xy 76.576687 -319.933396) (xy 76.523799 -319.87908)
			(xy 76.476984 -319.819451) (xy 76.436772 -319.755183) (xy 76.40362 -319.687006) (xy 76.377902 -319.61569)
			(xy 76.35991 -319.542045) (xy 76.349848 -319.466905) (xy 76.347829 -319.391121) (xy 75.231751 -319.391121)
			(xy 75.229732 -319.466905) (xy 75.21967 -319.542045) (xy 75.201678 -319.61569) (xy 75.17596 -319.687006)
			(xy 75.142808 -319.755183) (xy 75.102596 -319.819451) (xy 75.055781 -319.87908) (xy 75.002893 -319.933396)
			(xy 74.944531 -319.981782) (xy 74.881356 -320.02369) (xy 74.814085 -320.058646) (xy 74.74348 -320.086253)
			(xy 74.670339 -320.106199) (xy 74.595494 -320.118258) (xy 74.51979 -320.122293) (xy 74.444086 -320.118258)
			(xy 74.369241 -320.106199) (xy 74.2961 -320.086253) (xy 74.225495 -320.058646) (xy 74.158224 -320.02369)
			(xy 74.095049 -319.981782) (xy 74.036687 -319.933396) (xy 73.983799 -319.87908) (xy 73.936984 -319.819451)
			(xy 73.896772 -319.755183) (xy 73.86362 -319.687006) (xy 73.837902 -319.61569) (xy 73.81991 -319.542045)
			(xy 73.809848 -319.466905) (xy 73.807829 -319.391121) (xy 72.691751 -319.391121) (xy 72.689732 -319.466905)
			(xy 72.67967 -319.542045) (xy 72.661678 -319.61569) (xy 72.63596 -319.687006) (xy 72.602808 -319.755183)
			(xy 72.562596 -319.819451) (xy 72.515781 -319.87908) (xy 72.462893 -319.933396) (xy 72.404531 -319.981782)
			(xy 72.341356 -320.02369) (xy 72.274085 -320.058646) (xy 72.20348 -320.086253) (xy 72.130339 -320.106199)
			(xy 72.055494 -320.118258) (xy 71.97979 -320.122293) (xy 71.904086 -320.118258) (xy 71.829241 -320.106199)
			(xy 71.7561 -320.086253) (xy 71.685495 -320.058646) (xy 71.618224 -320.02369) (xy 71.555049 -319.981782)
			(xy 71.496687 -319.933396) (xy 71.443799 -319.87908) (xy 71.396984 -319.819451) (xy 71.356772 -319.755183)
			(xy 71.32362 -319.687006) (xy 71.297902 -319.61569) (xy 71.27991 -319.542045) (xy 71.269848 -319.466905)
			(xy 71.267829 -319.391121) (xy 70.151751 -319.391121) (xy 70.149732 -319.466905) (xy 70.13967 -319.542045)
			(xy 70.121678 -319.61569) (xy 70.09596 -319.687006) (xy 70.062808 -319.755183) (xy 70.022596 -319.819451)
			(xy 69.975781 -319.87908) (xy 69.922893 -319.933396) (xy 69.864531 -319.981782) (xy 69.801356 -320.02369)
			(xy 69.734085 -320.058646) (xy 69.66348 -320.086253) (xy 69.590339 -320.106199) (xy 69.515494 -320.118258)
			(xy 69.43979 -320.122293) (xy 69.364086 -320.118258) (xy 69.289241 -320.106199) (xy 69.2161 -320.086253)
			(xy 69.145495 -320.058646) (xy 69.078224 -320.02369) (xy 69.015049 -319.981782) (xy 68.956687 -319.933396)
			(xy 68.903799 -319.87908) (xy 68.856984 -319.819451) (xy 68.816772 -319.755183) (xy 68.78362 -319.687006)
			(xy 68.757902 -319.61569) (xy 68.73991 -319.542045) (xy 68.729848 -319.466905) (xy 68.727829 -319.391121)
			(xy 67.611751 -319.391121) (xy 67.609732 -319.466905) (xy 67.59967 -319.542045) (xy 67.581678 -319.61569)
			(xy 67.55596 -319.687006) (xy 67.522808 -319.755183) (xy 67.482596 -319.819451) (xy 67.435781 -319.87908)
			(xy 67.382893 -319.933396) (xy 67.324531 -319.981782) (xy 67.261356 -320.02369) (xy 67.194085 -320.058646)
			(xy 67.12348 -320.086253) (xy 67.050339 -320.106199) (xy 66.975494 -320.118258) (xy 66.89979 -320.122293)
			(xy 66.824086 -320.118258) (xy 66.749241 -320.106199) (xy 66.6761 -320.086253) (xy 66.605495 -320.058646)
			(xy 66.538224 -320.02369) (xy 66.475049 -319.981782) (xy 66.416687 -319.933396) (xy 66.363799 -319.87908)
			(xy 66.316984 -319.819451) (xy 66.276772 -319.755183) (xy 66.24362 -319.687006) (xy 66.217902 -319.61569)
			(xy 66.19991 -319.542045) (xy 66.189848 -319.466905) (xy 66.187829 -319.391121) (xy 65.071751 -319.391121)
			(xy 65.069732 -319.466905) (xy 65.05967 -319.542045) (xy 65.041678 -319.61569) (xy 65.01596 -319.687006)
			(xy 64.982808 -319.755183) (xy 64.942596 -319.819451) (xy 64.895781 -319.87908) (xy 64.842893 -319.933396)
			(xy 64.784531 -319.981782) (xy 64.721356 -320.02369) (xy 64.654085 -320.058646) (xy 64.58348 -320.086253)
			(xy 64.510339 -320.106199) (xy 64.435494 -320.118258) (xy 64.35979 -320.122293) (xy 64.284086 -320.118258)
			(xy 64.209241 -320.106199) (xy 64.1361 -320.086253) (xy 64.065495 -320.058646) (xy 63.998224 -320.02369)
			(xy 63.935049 -319.981782) (xy 63.876687 -319.933396) (xy 63.823799 -319.87908) (xy 63.776984 -319.819451)
			(xy 63.736772 -319.755183) (xy 63.70362 -319.687006) (xy 63.677902 -319.61569) (xy 63.65991 -319.542045)
			(xy 63.649848 -319.466905) (xy 63.647829 -319.391121) (xy 42.525601 -319.391121) (xy 42.478719 -319.427202)
			(xy 42.382066 -319.491482) (xy 42.281209 -319.54894) (xy 42.176629 -319.599304) (xy 42.068822 -319.642332)
			(xy 41.958305 -319.67782) (xy 41.845602 -319.705599) (xy 41.731251 -319.725536) (xy 41.615797 -319.737537)
			(xy 41.49979 -319.741543) (xy 41.383783 -319.737537) (xy 41.268329 -319.725536) (xy 41.153978 -319.705599)
			(xy 41.041275 -319.67782) (xy 40.930758 -319.642332) (xy 40.822951 -319.599304) (xy 40.718371 -319.54894)
			(xy 40.617514 -319.491482) (xy 40.520861 -319.427202) (xy 40.428874 -319.356407) (xy 40.34199 -319.279434)
			(xy 40.260623 -319.196651) (xy 40.185161 -319.108451) (xy 40.115965 -319.015256) (xy 40.053363 -318.917508)
			(xy 39.997654 -318.815674) (xy 39.949103 -318.71024) (xy 39.907942 -318.601707) (xy 39.874367 -318.490593)
			(xy 39.848537 -318.377427) (xy 39.830577 -318.262749) (xy 39.820571 -318.147105) (xy 39.818567 -318.031047)
			(xy 29.294836 -318.031047) (xy 29.294836 -319.817496) (xy 29.295314 -319.839621) (xy 29.30298 -319.883202)
			(xy 29.31808 -319.924796) (xy 29.340157 -319.963145) (xy 29.368545 -319.997089) (xy 29.402384 -320.025602)
			(xy 29.440651 -320.047822) (xy 29.482188 -320.063075) (xy 29.525741 -320.070902) (xy 29.569991 -320.071065)
			(xy 29.613599 -320.06356) (xy 29.655248 -320.048613) (xy 29.693678 -320.026676) (xy 29.727726 -319.998413)
			(xy 29.742384 -319.981834) (xy 29.770742 -319.949145) (xy 29.832533 -319.88855) (xy 29.899631 -319.833889)
			(xy 29.971467 -319.785624) (xy 30.047435 -319.744165) (xy 30.12689 -319.709861) (xy 30.209162 -319.683003)
			(xy 30.293553 -319.663819) (xy 30.379351 -319.65247) (xy 30.465828 -319.649053) (xy 30.552253 -319.653596)
			(xy 30.637895 -319.666062) (xy 30.722029 -319.686344) (xy 30.803944 -319.71427) (xy 30.882946 -319.749606)
			(xy 30.958367 -319.792052) (xy 31.029569 -319.841248) (xy 31.095949 -319.896778) (xy 31.156946 -319.958173)
			(xy 31.212043 -320.024913) (xy 31.260775 -320.096433) (xy 31.302729 -320.172129) (xy 31.33755 -320.251359)
			(xy 31.364944 -320.333454) (xy 31.384678 -320.417718) (xy 31.396586 -320.503439) (xy 31.400567 -320.589892)
			(xy 31.398566 -320.63336) (xy 34.599874 -320.63336) (xy 34.599874 -320.54646) (xy 34.607892 -320.459931)
			(xy 34.62386 -320.374511) (xy 34.647641 -320.290929) (xy 34.679033 -320.209897) (xy 34.717767 -320.132108)
			(xy 34.763514 -320.058224) (xy 34.815883 -319.988877) (xy 34.874427 -319.924657) (xy 34.938647 -319.866113)
			(xy 35.007994 -319.813744) (xy 35.081878 -319.767997) (xy 35.159667 -319.729263) (xy 35.240699 -319.697871)
			(xy 35.324281 -319.67409) (xy 35.409701 -319.658122) (xy 35.49623 -319.650104) (xy 35.53968 -319.649602)
			(xy 35.58313 -319.650104) (xy 35.669659 -319.658122) (xy 35.755079 -319.67409) (xy 35.838661 -319.697871)
			(xy 35.919693 -319.729263) (xy 35.997482 -319.767997) (xy 36.071366 -319.813744) (xy 36.140713 -319.866113)
			(xy 36.204933 -319.924657) (xy 36.263477 -319.988877) (xy 36.315846 -320.058224) (xy 36.361593 -320.132108)
			(xy 36.400327 -320.209897) (xy 36.431719 -320.290929) (xy 36.4555 -320.374511) (xy 36.471468 -320.459931)
			(xy 36.479486 -320.54646) (xy 36.479486 -320.63336) (xy 36.471468 -320.719889) (xy 36.4555 -320.805309)
			(xy 36.431719 -320.888891) (xy 36.400327 -320.969923) (xy 36.361593 -321.047712) (xy 36.315846 -321.121596)
			(xy 36.263477 -321.190943) (xy 36.204933 -321.255163) (xy 36.140713 -321.313707) (xy 36.071366 -321.366076)
			(xy 35.997482 -321.411823) (xy 35.919693 -321.450557) (xy 35.838661 -321.481949) (xy 35.755079 -321.50573)
			(xy 35.669659 -321.521698) (xy 35.58313 -321.529716) (xy 35.49623 -321.529716) (xy 35.409701 -321.521698)
			(xy 35.324281 -321.50573) (xy 35.240699 -321.481949) (xy 35.159667 -321.450557) (xy 35.081878 -321.411823)
			(xy 35.007994 -321.366076) (xy 34.938647 -321.313707) (xy 34.874427 -321.255163) (xy 34.815883 -321.190943)
			(xy 34.763514 -321.121596) (xy 34.717767 -321.047712) (xy 34.679033 -320.969923) (xy 34.647641 -320.888891)
			(xy 34.62386 -320.805309) (xy 34.607892 -320.719889) (xy 34.599874 -320.63336) (xy 31.398566 -320.63336)
			(xy 31.396587 -320.676345) (xy 31.384681 -320.762067) (xy 31.364948 -320.846332) (xy 31.337556 -320.928427)
			(xy 31.302736 -321.007658) (xy 31.260783 -321.083354) (xy 31.212052 -321.154875) (xy 31.156956 -321.221616)
			(xy 31.09596 -321.283012) (xy 31.029581 -321.338543) (xy 30.95838 -321.38774) (xy 30.88296 -321.430187)
			(xy 30.803958 -321.465524) (xy 30.722044 -321.493452) (xy 30.63791 -321.513736) (xy 30.552268 -321.526202)
			(xy 30.465843 -321.530747) (xy 30.379366 -321.527331) (xy 30.293568 -321.515984) (xy 30.209177 -321.496801)
			(xy 30.126905 -321.469944) (xy 30.047448 -321.435642) (xy 29.97148 -321.394184) (xy 29.899643 -321.34592)
			(xy 29.832544 -321.291261) (xy 29.770752 -321.230666) (xy 29.742384 -321.197986) (xy 29.727699 -321.181435)
			(xy 29.693651 -321.153183) (xy 29.655223 -321.131256) (xy 29.613579 -321.116317) (xy 29.569976 -321.108816)
			(xy 29.525734 -321.108981) (xy 29.482188 -321.116806) (xy 29.440656 -321.132056) (xy 29.402394 -321.154269)
			(xy 29.368557 -321.182774) (xy 29.340168 -321.216708) (xy 29.318087 -321.255047) (xy 29.30298 -321.296631)
			(xy 29.295303 -321.340203) (xy 29.294836 -321.362324) (xy 29.294836 -322.357496) (xy 29.295314 -322.379621)
			(xy 29.30298 -322.423202) (xy 29.31808 -322.464796) (xy 29.340157 -322.503145) (xy 29.368545 -322.537089)
			(xy 29.402384 -322.565602) (xy 29.440651 -322.587822) (xy 29.482188 -322.603075) (xy 29.525741 -322.610902)
			(xy 29.569991 -322.611065) (xy 29.613599 -322.60356) (xy 29.655248 -322.588613) (xy 29.693678 -322.566676)
			(xy 29.727726 -322.538413) (xy 29.742384 -322.521834) (xy 29.770742 -322.489145) (xy 29.832533 -322.42855)
			(xy 29.899631 -322.373889) (xy 29.971467 -322.325624) (xy 30.047435 -322.284165) (xy 30.12689 -322.249861)
			(xy 30.209162 -322.223003) (xy 30.293553 -322.203819) (xy 30.379351 -322.19247) (xy 30.465828 -322.189053)
			(xy 30.552253 -322.193596) (xy 30.637895 -322.206062) (xy 30.722029 -322.226344) (xy 30.803944 -322.25427)
			(xy 30.882946 -322.289606) (xy 30.958367 -322.332052) (xy 31.029569 -322.381248) (xy 31.095949 -322.436778)
			(xy 31.156946 -322.498173) (xy 31.212043 -322.564913) (xy 31.260775 -322.636433) (xy 31.302729 -322.712129)
			(xy 31.33755 -322.791359) (xy 31.364944 -322.873454) (xy 31.384678 -322.957718) (xy 31.396586 -323.043439)
			(xy 31.400567 -323.129892) (xy 31.398566 -323.17336) (xy 34.599874 -323.17336) (xy 34.599874 -323.08646)
			(xy 34.607892 -322.999931) (xy 34.62386 -322.914511) (xy 34.647641 -322.830929) (xy 34.679033 -322.749897)
			(xy 34.717767 -322.672108) (xy 34.763514 -322.598224) (xy 34.815883 -322.528877) (xy 34.874427 -322.464657)
			(xy 34.938647 -322.406113) (xy 35.007994 -322.353744) (xy 35.081878 -322.307997) (xy 35.159667 -322.269263)
			(xy 35.240699 -322.237871) (xy 35.324281 -322.21409) (xy 35.409701 -322.198122) (xy 35.49623 -322.190104)
			(xy 35.53968 -322.189602) (xy 35.58313 -322.190104) (xy 35.669659 -322.198122) (xy 35.755079 -322.21409)
			(xy 35.838661 -322.237871) (xy 35.919693 -322.269263) (xy 35.997482 -322.307997) (xy 36.071366 -322.353744)
			(xy 36.140713 -322.406113) (xy 36.204933 -322.464657) (xy 36.263477 -322.528877) (xy 36.315846 -322.598224)
			(xy 36.361593 -322.672108) (xy 36.400327 -322.749897) (xy 36.431719 -322.830929) (xy 36.4555 -322.914511)
			(xy 36.471468 -322.999931) (xy 36.479486 -323.08646) (xy 36.479486 -323.17336) (xy 36.473971 -323.232881)
			(xy 65.298566 -323.232881) (xy 65.298566 -323.161559) (xy 65.306552 -323.090685) (xy 65.322422 -323.02115)
			(xy 65.345979 -322.95383) (xy 65.376924 -322.889571) (xy 65.41487 -322.82918) (xy 65.459339 -322.773418)
			(xy 65.509772 -322.722985) (xy 65.565534 -322.678516) (xy 65.625925 -322.64057) (xy 65.690184 -322.609625)
			(xy 65.757504 -322.586068) (xy 65.827039 -322.570198) (xy 65.897913 -322.562212) (xy 65.933574 -322.561712)
			(xy 65.969235 -322.562212) (xy 66.040109 -322.570198) (xy 66.109644 -322.586068) (xy 66.176964 -322.609625)
			(xy 66.241223 -322.64057) (xy 66.301614 -322.678516) (xy 66.357376 -322.722985) (xy 66.407809 -322.773418)
			(xy 66.452278 -322.82918) (xy 66.490224 -322.889571) (xy 66.521169 -322.95383) (xy 66.544726 -323.02115)
			(xy 66.560596 -323.090685) (xy 66.568582 -323.161559) (xy 66.568582 -323.232881) (xy 68.10298 -323.232881)
			(xy 68.10298 -323.161559) (xy 68.110966 -323.090685) (xy 68.126836 -323.02115) (xy 68.150393 -322.95383)
			(xy 68.181338 -322.889571) (xy 68.219284 -322.82918) (xy 68.263753 -322.773418) (xy 68.314186 -322.722985)
			(xy 68.369948 -322.678516) (xy 68.430339 -322.64057) (xy 68.494598 -322.609625) (xy 68.561918 -322.586068)
			(xy 68.631453 -322.570198) (xy 68.702327 -322.562212) (xy 68.737988 -322.561712) (xy 68.773649 -322.562212)
			(xy 68.844523 -322.570198) (xy 68.914058 -322.586068) (xy 68.981378 -322.609625) (xy 69.045637 -322.64057)
			(xy 69.106028 -322.678516) (xy 69.16179 -322.722985) (xy 69.212223 -322.773418) (xy 69.256692 -322.82918)
			(xy 69.294638 -322.889571) (xy 69.325583 -322.95383) (xy 69.34914 -323.02115) (xy 69.36501 -323.090685)
			(xy 69.372996 -323.161559) (xy 69.372996 -323.232881) (xy 69.36501 -323.303755) (xy 69.34914 -323.37329)
			(xy 69.325583 -323.44061) (xy 69.294638 -323.504869) (xy 69.256692 -323.56526) (xy 69.212223 -323.621022)
			(xy 69.16179 -323.671455) (xy 69.106028 -323.715924) (xy 69.045637 -323.75387) (xy 68.981378 -323.784815)
			(xy 68.914058 -323.808372) (xy 68.844523 -323.824242) (xy 68.773649 -323.832228) (xy 68.702327 -323.832228)
			(xy 68.631453 -323.824242) (xy 68.561918 -323.808372) (xy 68.494598 -323.784815) (xy 68.430339 -323.75387)
			(xy 68.369948 -323.715924) (xy 68.314186 -323.671455) (xy 68.263753 -323.621022) (xy 68.219284 -323.56526)
			(xy 68.181338 -323.504869) (xy 68.150393 -323.44061) (xy 68.126836 -323.37329) (xy 68.110966 -323.303755)
			(xy 68.10298 -323.232881) (xy 66.568582 -323.232881) (xy 66.560596 -323.303755) (xy 66.544726 -323.37329)
			(xy 66.521169 -323.44061) (xy 66.490224 -323.504869) (xy 66.452278 -323.56526) (xy 66.407809 -323.621022)
			(xy 66.357376 -323.671455) (xy 66.301614 -323.715924) (xy 66.241223 -323.75387) (xy 66.176964 -323.784815)
			(xy 66.109644 -323.808372) (xy 66.040109 -323.824242) (xy 65.969235 -323.832228) (xy 65.897913 -323.832228)
			(xy 65.827039 -323.824242) (xy 65.757504 -323.808372) (xy 65.690184 -323.784815) (xy 65.625925 -323.75387)
			(xy 65.565534 -323.715924) (xy 65.509772 -323.671455) (xy 65.459339 -323.621022) (xy 65.41487 -323.56526)
			(xy 65.376924 -323.504869) (xy 65.345979 -323.44061) (xy 65.322422 -323.37329) (xy 65.306552 -323.303755)
			(xy 65.298566 -323.232881) (xy 36.473971 -323.232881) (xy 36.471468 -323.259889) (xy 36.4555 -323.345309)
			(xy 36.431719 -323.428891) (xy 36.400327 -323.509923) (xy 36.361593 -323.587712) (xy 36.315846 -323.661596)
			(xy 36.263477 -323.730943) (xy 36.204933 -323.795163) (xy 36.140713 -323.853707) (xy 36.071366 -323.906076)
			(xy 35.997482 -323.951823) (xy 35.919693 -323.990557) (xy 35.838661 -324.021949) (xy 35.755079 -324.04573)
			(xy 35.669659 -324.061698) (xy 35.58313 -324.069716) (xy 35.49623 -324.069716) (xy 35.409701 -324.061698)
			(xy 35.324281 -324.04573) (xy 35.240699 -324.021949) (xy 35.159667 -323.990557) (xy 35.081878 -323.951823)
			(xy 35.007994 -323.906076) (xy 34.938647 -323.853707) (xy 34.874427 -323.795163) (xy 34.815883 -323.730943)
			(xy 34.763514 -323.661596) (xy 34.717767 -323.587712) (xy 34.679033 -323.509923) (xy 34.647641 -323.428891)
			(xy 34.62386 -323.345309) (xy 34.607892 -323.259889) (xy 34.599874 -323.17336) (xy 31.398566 -323.17336)
			(xy 31.396587 -323.216345) (xy 31.384681 -323.302067) (xy 31.364948 -323.386332) (xy 31.337556 -323.468427)
			(xy 31.302736 -323.547658) (xy 31.260783 -323.623354) (xy 31.212052 -323.694875) (xy 31.156956 -323.761616)
			(xy 31.09596 -323.823012) (xy 31.029581 -323.878543) (xy 30.95838 -323.92774) (xy 30.88296 -323.970187)
			(xy 30.803958 -324.005524) (xy 30.722044 -324.033452) (xy 30.63791 -324.053736) (xy 30.552268 -324.066202)
			(xy 30.465843 -324.070747) (xy 30.379366 -324.067331) (xy 30.293568 -324.055984) (xy 30.209177 -324.036801)
			(xy 30.126905 -324.009944) (xy 30.047448 -323.975642) (xy 29.97148 -323.934184) (xy 29.899643 -323.88592)
			(xy 29.832544 -323.831261) (xy 29.770752 -323.770666) (xy 29.742384 -323.737986) (xy 29.727699 -323.721435)
			(xy 29.693651 -323.693183) (xy 29.655223 -323.671256) (xy 29.613579 -323.656317) (xy 29.569976 -323.648816)
			(xy 29.525734 -323.648981) (xy 29.482188 -323.656806) (xy 29.440656 -323.672056) (xy 29.402394 -323.694269)
			(xy 29.368557 -323.722774) (xy 29.340168 -323.756708) (xy 29.318087 -323.795047) (xy 29.30298 -323.836631)
			(xy 29.295303 -323.880203) (xy 29.294836 -323.902324) (xy 29.294836 -324.339454) (xy 84.18625 -324.339454)
			(xy 84.18625 -324.279518) (xy 84.194073 -324.220096) (xy 84.209586 -324.162203) (xy 84.232522 -324.10683)
			(xy 84.262489 -324.054924) (xy 84.298976 -324.007374) (xy 84.341356 -323.964994) (xy 84.388906 -323.928507)
			(xy 84.440812 -323.89854) (xy 84.496185 -323.875604) (xy 84.554078 -323.860091) (xy 84.6135 -323.852268)
			(xy 84.643468 -323.851778) (xy 84.673436 -323.852268) (xy 84.732858 -323.860091) (xy 84.790751 -323.875604)
			(xy 84.846124 -323.89854) (xy 84.89803 -323.928507) (xy 84.94558 -323.964994) (xy 84.98796 -324.007374)
			(xy 85.024447 -324.054924) (xy 85.054414 -324.10683) (xy 85.07735 -324.162203) (xy 85.092863 -324.220096)
			(xy 85.100686 -324.279518) (xy 85.100686 -324.339454) (xy 85.092863 -324.398876) (xy 85.07735 -324.456769)
			(xy 85.054414 -324.512142) (xy 85.024447 -324.564048) (xy 84.98796 -324.611598) (xy 84.94558 -324.653978)
			(xy 84.89803 -324.690465) (xy 84.846124 -324.720432) (xy 84.790751 -324.743368) (xy 84.732858 -324.758881)
			(xy 84.673436 -324.766704) (xy 84.6135 -324.766704) (xy 84.554078 -324.758881) (xy 84.496185 -324.743368)
			(xy 84.440812 -324.720432) (xy 84.388906 -324.690465) (xy 84.341356 -324.653978) (xy 84.298976 -324.611598)
			(xy 84.262489 -324.564048) (xy 84.232522 -324.512142) (xy 84.209586 -324.456769) (xy 84.194073 -324.398876)
			(xy 84.18625 -324.339454) (xy 29.294836 -324.339454) (xy 29.294836 -324.897496) (xy 29.295314 -324.919621)
			(xy 29.30298 -324.963202) (xy 29.31808 -325.004796) (xy 29.340157 -325.043145) (xy 29.368545 -325.077089)
			(xy 29.402384 -325.105602) (xy 29.440651 -325.127822) (xy 29.482188 -325.143075) (xy 29.525741 -325.150902)
			(xy 29.569991 -325.151065) (xy 29.613599 -325.14356) (xy 29.655248 -325.128613) (xy 29.693678 -325.106676)
			(xy 29.727726 -325.078413) (xy 29.742384 -325.061834) (xy 29.770742 -325.029145) (xy 29.832533 -324.96855)
			(xy 29.899631 -324.913889) (xy 29.971467 -324.865624) (xy 30.047435 -324.824165) (xy 30.12689 -324.789861)
			(xy 30.209162 -324.763003) (xy 30.293553 -324.743819) (xy 30.379351 -324.73247) (xy 30.465828 -324.729053)
			(xy 30.552253 -324.733596) (xy 30.637895 -324.746062) (xy 30.722029 -324.766344) (xy 30.803944 -324.79427)
			(xy 30.882946 -324.829606) (xy 30.958367 -324.872052) (xy 31.029569 -324.921248) (xy 31.095949 -324.976778)
			(xy 31.156946 -325.038173) (xy 31.212043 -325.104913) (xy 31.260775 -325.176433) (xy 31.302729 -325.252129)
			(xy 31.33755 -325.331359) (xy 31.364944 -325.413454) (xy 31.384678 -325.497718) (xy 31.396586 -325.583439)
			(xy 31.400567 -325.669892) (xy 31.398566 -325.71336) (xy 34.599874 -325.71336) (xy 34.599874 -325.62646)
			(xy 34.607892 -325.539931) (xy 34.62386 -325.454511) (xy 34.647641 -325.370929) (xy 34.679033 -325.289897)
			(xy 34.717767 -325.212108) (xy 34.763514 -325.138224) (xy 34.815883 -325.068877) (xy 34.874427 -325.004657)
			(xy 34.938647 -324.946113) (xy 35.007994 -324.893744) (xy 35.081878 -324.847997) (xy 35.159667 -324.809263)
			(xy 35.240699 -324.777871) (xy 35.324281 -324.75409) (xy 35.409701 -324.738122) (xy 35.49623 -324.730104)
			(xy 35.53968 -324.729602) (xy 35.58313 -324.730104) (xy 35.669659 -324.738122) (xy 35.755079 -324.75409)
			(xy 35.838661 -324.777871) (xy 35.919693 -324.809263) (xy 35.997482 -324.847997) (xy 36.071366 -324.893744)
			(xy 36.140713 -324.946113) (xy 36.204933 -325.004657) (xy 36.209353 -325.009506) (xy 82.71559 -325.009506)
			(xy 82.71559 -324.94957) (xy 82.723413 -324.890148) (xy 82.738926 -324.832255) (xy 82.761862 -324.776882)
			(xy 82.791829 -324.724976) (xy 82.828316 -324.677426) (xy 82.870696 -324.635046) (xy 82.918246 -324.598559)
			(xy 82.970152 -324.568592) (xy 83.025525 -324.545656) (xy 83.083418 -324.530143) (xy 83.14284 -324.52232)
			(xy 83.172808 -324.52183) (xy 83.202776 -324.52232) (xy 83.262198 -324.530143) (xy 83.320091 -324.545656)
			(xy 83.375464 -324.568592) (xy 83.42737 -324.598559) (xy 83.47492 -324.635046) (xy 83.5173 -324.677426)
			(xy 83.553787 -324.724976) (xy 83.583754 -324.776882) (xy 83.60669 -324.832255) (xy 83.622203 -324.890148)
			(xy 83.630026 -324.94957) (xy 83.630026 -325.009506) (xy 83.622203 -325.068928) (xy 83.60669 -325.126821)
			(xy 83.583754 -325.182194) (xy 83.553787 -325.2341) (xy 83.5173 -325.28165) (xy 83.47492 -325.32403)
			(xy 83.42737 -325.360517) (xy 83.375464 -325.390484) (xy 83.320091 -325.41342) (xy 83.262198 -325.428933)
			(xy 83.202776 -325.436756) (xy 83.14284 -325.436756) (xy 83.083418 -325.428933) (xy 83.025525 -325.41342)
			(xy 82.970152 -325.390484) (xy 82.918246 -325.360517) (xy 82.870696 -325.32403) (xy 82.828316 -325.28165)
			(xy 82.791829 -325.2341) (xy 82.761862 -325.182194) (xy 82.738926 -325.126821) (xy 82.723413 -325.068928)
			(xy 82.71559 -325.009506) (xy 36.209353 -325.009506) (xy 36.263477 -325.068877) (xy 36.315846 -325.138224)
			(xy 36.361593 -325.212108) (xy 36.400327 -325.289897) (xy 36.431719 -325.370929) (xy 36.4555 -325.454511)
			(xy 36.471468 -325.539931) (xy 36.479486 -325.62646) (xy 36.479486 -325.71336) (xy 36.471468 -325.799889)
			(xy 36.4555 -325.885309) (xy 36.45027 -325.903691) (xy 65.298566 -325.903691) (xy 65.298566 -325.832369)
			(xy 65.306552 -325.761495) (xy 65.322422 -325.69196) (xy 65.345979 -325.62464) (xy 65.376924 -325.560381)
			(xy 65.41487 -325.49999) (xy 65.459339 -325.444228) (xy 65.509772 -325.393795) (xy 65.565534 -325.349326)
			(xy 65.625925 -325.31138) (xy 65.690184 -325.280435) (xy 65.757504 -325.256878) (xy 65.827039 -325.241008)
			(xy 65.897913 -325.233022) (xy 65.933574 -325.232522) (xy 65.969235 -325.233022) (xy 66.040109 -325.241008)
			(xy 66.109644 -325.256878) (xy 66.176964 -325.280435) (xy 66.241223 -325.31138) (xy 66.301614 -325.349326)
			(xy 66.357376 -325.393795) (xy 66.407809 -325.444228) (xy 66.452278 -325.49999) (xy 66.490224 -325.560381)
			(xy 66.521169 -325.62464) (xy 66.544726 -325.69196) (xy 66.560596 -325.761495) (xy 66.568582 -325.832369)
			(xy 66.568582 -325.903691) (xy 68.10298 -325.903691) (xy 68.10298 -325.832369) (xy 68.110966 -325.761495)
			(xy 68.126836 -325.69196) (xy 68.150393 -325.62464) (xy 68.181338 -325.560381) (xy 68.219284 -325.49999)
			(xy 68.263753 -325.444228) (xy 68.314186 -325.393795) (xy 68.369948 -325.349326) (xy 68.430339 -325.31138)
			(xy 68.494598 -325.280435) (xy 68.561918 -325.256878) (xy 68.631453 -325.241008) (xy 68.702327 -325.233022)
			(xy 68.737988 -325.232522) (xy 68.773649 -325.233022) (xy 68.844523 -325.241008) (xy 68.914058 -325.256878)
			(xy 68.981378 -325.280435) (xy 69.045637 -325.31138) (xy 69.106028 -325.349326) (xy 69.16179 -325.393795)
			(xy 69.212223 -325.444228) (xy 69.256692 -325.49999) (xy 69.294638 -325.560381) (xy 69.325583 -325.62464)
			(xy 69.344889 -325.679812) (xy 81.325194 -325.679812) (xy 81.325194 -325.619876) (xy 81.333017 -325.560454)
			(xy 81.34853 -325.502561) (xy 81.371466 -325.447188) (xy 81.401433 -325.395282) (xy 81.43792 -325.347732)
			(xy 81.4803 -325.305352) (xy 81.52785 -325.268865) (xy 81.579756 -325.238898) (xy 81.635129 -325.215962)
			(xy 81.693022 -325.200449) (xy 81.752444 -325.192626) (xy 81.782412 -325.192136) (xy 81.81238 -325.192626)
			(xy 81.871802 -325.200449) (xy 81.929695 -325.215962) (xy 81.985068 -325.238898) (xy 82.036974 -325.268865)
			(xy 82.084524 -325.305352) (xy 82.126904 -325.347732) (xy 82.163391 -325.395282) (xy 82.193358 -325.447188)
			(xy 82.216294 -325.502561) (xy 82.231807 -325.560454) (xy 82.23963 -325.619876) (xy 82.23963 -325.679812)
			(xy 82.231807 -325.739234) (xy 82.216294 -325.797127) (xy 82.193358 -325.8525) (xy 82.163391 -325.904406)
			(xy 82.126904 -325.951956) (xy 82.084524 -325.994336) (xy 82.036974 -326.030823) (xy 81.985068 -326.06079)
			(xy 81.929695 -326.083726) (xy 81.871802 -326.099239) (xy 81.81238 -326.107062) (xy 81.752444 -326.107062)
			(xy 81.693022 -326.099239) (xy 81.635129 -326.083726) (xy 81.579756 -326.06079) (xy 81.52785 -326.030823)
			(xy 81.4803 -325.994336) (xy 81.43792 -325.951956) (xy 81.401433 -325.904406) (xy 81.371466 -325.8525)
			(xy 81.34853 -325.797127) (xy 81.333017 -325.739234) (xy 81.325194 -325.679812) (xy 69.344889 -325.679812)
			(xy 69.34914 -325.69196) (xy 69.36501 -325.761495) (xy 69.372996 -325.832369) (xy 69.372996 -325.903691)
			(xy 69.36501 -325.974565) (xy 69.34914 -326.0441) (xy 69.325583 -326.11142) (xy 69.297357 -326.170032)
			(xy 83.266008 -326.170032) (xy 83.266008 -326.110096) (xy 83.273831 -326.050674) (xy 83.289344 -325.992781)
			(xy 83.31228 -325.937408) (xy 83.342247 -325.885502) (xy 83.378734 -325.837952) (xy 83.421114 -325.795572)
			(xy 83.468664 -325.759085) (xy 83.52057 -325.729118) (xy 83.575943 -325.706182) (xy 83.633836 -325.690669)
			(xy 83.693258 -325.682846) (xy 83.723226 -325.682356) (xy 83.753194 -325.682846) (xy 83.812616 -325.690669)
			(xy 83.870509 -325.706182) (xy 83.925882 -325.729118) (xy 83.977788 -325.759085) (xy 84.025338 -325.795572)
			(xy 84.03988 -325.810114) (xy 85.40672 -325.810114) (xy 85.40672 -325.750178) (xy 85.414543 -325.690756)
			(xy 85.430056 -325.632863) (xy 85.452992 -325.57749) (xy 85.482959 -325.525584) (xy 85.519446 -325.478034)
			(xy 85.561826 -325.435654) (xy 85.609376 -325.399167) (xy 85.661282 -325.3692) (xy 85.716655 -325.346264)
			(xy 85.774548 -325.330751) (xy 85.83397 -325.322928) (xy 85.863938 -325.322438) (xy 85.893906 -325.322928)
			(xy 85.953328 -325.330751) (xy 86.011221 -325.346264) (xy 86.066594 -325.3692) (xy 86.1185 -325.399167)
			(xy 86.16605 -325.435654) (xy 86.20843 -325.478034) (xy 86.244917 -325.525584) (xy 86.274884 -325.57749)
			(xy 86.29782 -325.632863) (xy 86.313333 -325.690756) (xy 86.321156 -325.750178) (xy 86.321156 -325.810114)
			(xy 86.313333 -325.869536) (xy 86.29782 -325.927429) (xy 86.274884 -325.982802) (xy 86.244917 -326.034708)
			(xy 86.20843 -326.082258) (xy 86.16605 -326.124638) (xy 86.1185 -326.161125) (xy 86.066594 -326.191092)
			(xy 86.011221 -326.214028) (xy 85.953328 -326.229541) (xy 85.893906 -326.237364) (xy 85.83397 -326.237364)
			(xy 85.774548 -326.229541) (xy 85.716655 -326.214028) (xy 85.661282 -326.191092) (xy 85.609376 -326.161125)
			(xy 85.561826 -326.124638) (xy 85.519446 -326.082258) (xy 85.482959 -326.034708) (xy 85.452992 -325.982802)
			(xy 85.430056 -325.927429) (xy 85.414543 -325.869536) (xy 85.40672 -325.810114) (xy 84.03988 -325.810114)
			(xy 84.067718 -325.837952) (xy 84.104205 -325.885502) (xy 84.134172 -325.937408) (xy 84.157108 -325.992781)
			(xy 84.172621 -326.050674) (xy 84.180444 -326.110096) (xy 84.180444 -326.170032) (xy 84.172621 -326.229454)
			(xy 84.157108 -326.287347) (xy 84.134172 -326.34272) (xy 84.104205 -326.394626) (xy 84.067718 -326.442176)
			(xy 84.025338 -326.484556) (xy 83.977788 -326.521043) (xy 83.925882 -326.55101) (xy 83.870509 -326.573946)
			(xy 83.812616 -326.589459) (xy 83.753194 -326.597282) (xy 83.693258 -326.597282) (xy 83.633836 -326.589459)
			(xy 83.575943 -326.573946) (xy 83.52057 -326.55101) (xy 83.468664 -326.521043) (xy 83.421114 -326.484556)
			(xy 83.378734 -326.442176) (xy 83.342247 -326.394626) (xy 83.31228 -326.34272) (xy 83.289344 -326.287347)
			(xy 83.273831 -326.229454) (xy 83.266008 -326.170032) (xy 69.297357 -326.170032) (xy 69.294638 -326.175679)
			(xy 69.256692 -326.23607) (xy 69.212223 -326.291832) (xy 69.16179 -326.342265) (xy 69.106028 -326.386734)
			(xy 69.045637 -326.42468) (xy 68.981378 -326.455625) (xy 68.914058 -326.479182) (xy 68.844523 -326.495052)
			(xy 68.773649 -326.503038) (xy 68.702327 -326.503038) (xy 68.631453 -326.495052) (xy 68.561918 -326.479182)
			(xy 68.494598 -326.455625) (xy 68.430339 -326.42468) (xy 68.369948 -326.386734) (xy 68.314186 -326.342265)
			(xy 68.263753 -326.291832) (xy 68.219284 -326.23607) (xy 68.181338 -326.175679) (xy 68.150393 -326.11142)
			(xy 68.126836 -326.0441) (xy 68.110966 -325.974565) (xy 68.10298 -325.903691) (xy 66.568582 -325.903691)
			(xy 66.560596 -325.974565) (xy 66.544726 -326.0441) (xy 66.521169 -326.11142) (xy 66.490224 -326.175679)
			(xy 66.452278 -326.23607) (xy 66.407809 -326.291832) (xy 66.357376 -326.342265) (xy 66.301614 -326.386734)
			(xy 66.241223 -326.42468) (xy 66.176964 -326.455625) (xy 66.109644 -326.479182) (xy 66.040109 -326.495052)
			(xy 65.969235 -326.503038) (xy 65.897913 -326.503038) (xy 65.827039 -326.495052) (xy 65.757504 -326.479182)
			(xy 65.690184 -326.455625) (xy 65.625925 -326.42468) (xy 65.565534 -326.386734) (xy 65.509772 -326.342265)
			(xy 65.459339 -326.291832) (xy 65.41487 -326.23607) (xy 65.376924 -326.175679) (xy 65.345979 -326.11142)
			(xy 65.322422 -326.0441) (xy 65.306552 -325.974565) (xy 65.298566 -325.903691) (xy 36.45027 -325.903691)
			(xy 36.431719 -325.968891) (xy 36.400327 -326.049923) (xy 36.361593 -326.127712) (xy 36.315846 -326.201596)
			(xy 36.263477 -326.270943) (xy 36.204933 -326.335163) (xy 36.140713 -326.393707) (xy 36.071366 -326.446076)
			(xy 35.997482 -326.491823) (xy 35.919693 -326.530557) (xy 35.838661 -326.561949) (xy 35.755079 -326.58573)
			(xy 35.669659 -326.601698) (xy 35.58313 -326.609716) (xy 35.49623 -326.609716) (xy 35.409701 -326.601698)
			(xy 35.324281 -326.58573) (xy 35.240699 -326.561949) (xy 35.159667 -326.530557) (xy 35.081878 -326.491823)
			(xy 35.007994 -326.446076) (xy 34.938647 -326.393707) (xy 34.874427 -326.335163) (xy 34.815883 -326.270943)
			(xy 34.763514 -326.201596) (xy 34.717767 -326.127712) (xy 34.679033 -326.049923) (xy 34.647641 -325.968891)
			(xy 34.62386 -325.885309) (xy 34.607892 -325.799889) (xy 34.599874 -325.71336) (xy 31.398566 -325.71336)
			(xy 31.396587 -325.756345) (xy 31.384681 -325.842067) (xy 31.364948 -325.926332) (xy 31.337556 -326.008427)
			(xy 31.302736 -326.087658) (xy 31.260783 -326.163354) (xy 31.212052 -326.234875) (xy 31.156956 -326.301616)
			(xy 31.09596 -326.363012) (xy 31.029581 -326.418543) (xy 30.95838 -326.46774) (xy 30.88296 -326.510187)
			(xy 30.803958 -326.545524) (xy 30.722044 -326.573452) (xy 30.63791 -326.593736) (xy 30.552268 -326.606202)
			(xy 30.465843 -326.610747) (xy 30.379366 -326.607331) (xy 30.293568 -326.595984) (xy 30.209177 -326.576801)
			(xy 30.126905 -326.549944) (xy 30.047448 -326.515642) (xy 29.97148 -326.474184) (xy 29.899643 -326.42592)
			(xy 29.832544 -326.371261) (xy 29.770752 -326.310666) (xy 29.742384 -326.277986) (xy 29.727699 -326.261435)
			(xy 29.693651 -326.233183) (xy 29.655223 -326.211256) (xy 29.613579 -326.196317) (xy 29.569976 -326.188816)
			(xy 29.525734 -326.188981) (xy 29.482188 -326.196806) (xy 29.440656 -326.212056) (xy 29.402394 -326.234269)
			(xy 29.368557 -326.262774) (xy 29.340168 -326.296708) (xy 29.318087 -326.335047) (xy 29.30298 -326.376631)
			(xy 29.295303 -326.420203) (xy 29.294836 -326.442324) (xy 29.294836 -327.002749) (xy 55.045348 -327.002749)
			(xy 55.045348 -326.931427) (xy 55.053334 -326.860553) (xy 55.069204 -326.791018) (xy 55.092761 -326.723698)
			(xy 55.123706 -326.659439) (xy 55.161652 -326.599048) (xy 55.206121 -326.543286) (xy 55.256554 -326.492853)
			(xy 55.312316 -326.448384) (xy 55.372707 -326.410438) (xy 55.436966 -326.379493) (xy 55.504286 -326.355936)
			(xy 55.573821 -326.340066) (xy 55.644695 -326.33208) (xy 55.680356 -326.33158) (xy 55.716017 -326.33208)
			(xy 55.786891 -326.340066) (xy 55.856426 -326.355936) (xy 55.923746 -326.379493) (xy 55.988005 -326.410438)
			(xy 56.048396 -326.448384) (xy 56.104158 -326.492853) (xy 56.154591 -326.543286) (xy 56.19906 -326.599048)
			(xy 56.237006 -326.659439) (xy 56.267951 -326.723698) (xy 56.291508 -326.791018) (xy 56.307378 -326.860553)
			(xy 56.315364 -326.931427) (xy 56.315364 -327.002749) (xy 56.93206 -327.002749) (xy 56.93206 -326.931427)
			(xy 56.940046 -326.860553) (xy 56.955916 -326.791018) (xy 56.979473 -326.723698) (xy 57.010418 -326.659439)
			(xy 57.048364 -326.599048) (xy 57.092833 -326.543286) (xy 57.143266 -326.492853) (xy 57.199028 -326.448384)
			(xy 57.259419 -326.410438) (xy 57.323678 -326.379493) (xy 57.390998 -326.355936) (xy 57.460533 -326.340066)
			(xy 57.531407 -326.33208) (xy 57.567068 -326.33158) (xy 57.602729 -326.33208) (xy 57.673603 -326.340066)
			(xy 57.743138 -326.355936) (xy 57.810458 -326.379493) (xy 57.874717 -326.410438) (xy 57.935108 -326.448384)
			(xy 57.99087 -326.492853) (xy 58.041303 -326.543286) (xy 58.085772 -326.599048) (xy 58.123718 -326.659439)
			(xy 58.154663 -326.723698) (xy 58.17822 -326.791018) (xy 58.19409 -326.860553) (xy 58.202076 -326.931427)
			(xy 58.202076 -327.002749) (xy 58.19409 -327.073623) (xy 58.17822 -327.143158) (xy 58.154663 -327.210478)
			(xy 58.123718 -327.274737) (xy 58.085772 -327.335128) (xy 58.041303 -327.39089) (xy 57.99087 -327.441323)
			(xy 57.935108 -327.485792) (xy 57.925066 -327.492102) (xy 82.83751 -327.492102) (xy 82.83751 -327.432166)
			(xy 82.845333 -327.372744) (xy 82.860846 -327.314851) (xy 82.883782 -327.259478) (xy 82.913749 -327.207572)
			(xy 82.950236 -327.160022) (xy 82.992616 -327.117642) (xy 83.040166 -327.081155) (xy 83.092072 -327.051188)
			(xy 83.147445 -327.028252) (xy 83.205338 -327.012739) (xy 83.26476 -327.004916) (xy 83.294728 -327.004426)
			(xy 83.324696 -327.004916) (xy 83.384118 -327.012739) (xy 83.442011 -327.028252) (xy 83.497384 -327.051188)
			(xy 83.54929 -327.081155) (xy 83.59684 -327.117642) (xy 83.63922 -327.160022) (xy 83.675707 -327.207572)
			(xy 83.705674 -327.259478) (xy 83.72861 -327.314851) (xy 83.744123 -327.372744) (xy 83.751946 -327.432166)
			(xy 83.751946 -327.492102) (xy 83.744123 -327.551524) (xy 83.72861 -327.609417) (xy 83.705674 -327.66479)
			(xy 83.675707 -327.716696) (xy 83.63922 -327.764246) (xy 83.59684 -327.806626) (xy 83.54929 -327.843113)
			(xy 83.497384 -327.87308) (xy 83.442011 -327.896016) (xy 83.384118 -327.911529) (xy 83.324696 -327.919352)
			(xy 83.26476 -327.919352) (xy 83.205338 -327.911529) (xy 83.147445 -327.896016) (xy 83.092072 -327.87308)
			(xy 83.040166 -327.843113) (xy 82.992616 -327.806626) (xy 82.950236 -327.764246) (xy 82.913749 -327.716696)
			(xy 82.883782 -327.66479) (xy 82.860846 -327.609417) (xy 82.845333 -327.551524) (xy 82.83751 -327.492102)
			(xy 57.925066 -327.492102) (xy 57.874717 -327.523738) (xy 57.810458 -327.554683) (xy 57.743138 -327.57824)
			(xy 57.673603 -327.59411) (xy 57.602729 -327.602096) (xy 57.531407 -327.602096) (xy 57.460533 -327.59411)
			(xy 57.390998 -327.57824) (xy 57.323678 -327.554683) (xy 57.259419 -327.523738) (xy 57.199028 -327.485792)
			(xy 57.143266 -327.441323) (xy 57.092833 -327.39089) (xy 57.048364 -327.335128) (xy 57.010418 -327.274737)
			(xy 56.979473 -327.210478) (xy 56.955916 -327.143158) (xy 56.940046 -327.073623) (xy 56.93206 -327.002749)
			(xy 56.315364 -327.002749) (xy 56.307378 -327.073623) (xy 56.291508 -327.143158) (xy 56.267951 -327.210478)
			(xy 56.237006 -327.274737) (xy 56.19906 -327.335128) (xy 56.154591 -327.39089) (xy 56.104158 -327.441323)
			(xy 56.048396 -327.485792) (xy 55.988005 -327.523738) (xy 55.923746 -327.554683) (xy 55.856426 -327.57824)
			(xy 55.786891 -327.59411) (xy 55.716017 -327.602096) (xy 55.644695 -327.602096) (xy 55.573821 -327.59411)
			(xy 55.504286 -327.57824) (xy 55.436966 -327.554683) (xy 55.372707 -327.523738) (xy 55.312316 -327.485792)
			(xy 55.256554 -327.441323) (xy 55.206121 -327.39089) (xy 55.161652 -327.335128) (xy 55.123706 -327.274737)
			(xy 55.092761 -327.210478) (xy 55.069204 -327.143158) (xy 55.053334 -327.073623) (xy 55.045348 -327.002749)
			(xy 29.294836 -327.002749) (xy 29.294836 -327.437496) (xy 29.295314 -327.459621) (xy 29.30298 -327.503202)
			(xy 29.31808 -327.544796) (xy 29.340157 -327.583145) (xy 29.368545 -327.617089) (xy 29.402384 -327.645602)
			(xy 29.440651 -327.667822) (xy 29.482188 -327.683075) (xy 29.525741 -327.690902) (xy 29.569991 -327.691065)
			(xy 29.613599 -327.68356) (xy 29.655248 -327.668613) (xy 29.693678 -327.646676) (xy 29.727726 -327.618413)
			(xy 29.742384 -327.601834) (xy 29.770742 -327.569145) (xy 29.832533 -327.50855) (xy 29.899631 -327.453889)
			(xy 29.971467 -327.405624) (xy 30.047435 -327.364165) (xy 30.12689 -327.329861) (xy 30.209162 -327.303003)
			(xy 30.293553 -327.283819) (xy 30.379351 -327.27247) (xy 30.465828 -327.269053) (xy 30.552253 -327.273596)
			(xy 30.637895 -327.286062) (xy 30.722029 -327.306344) (xy 30.803944 -327.33427) (xy 30.882946 -327.369606)
			(xy 30.958367 -327.412052) (xy 31.029569 -327.461248) (xy 31.095949 -327.516778) (xy 31.156946 -327.578173)
			(xy 31.212043 -327.644913) (xy 31.260775 -327.716433) (xy 31.302729 -327.792129) (xy 31.33755 -327.871359)
			(xy 31.364944 -327.953454) (xy 31.384678 -328.037718) (xy 31.396586 -328.123439) (xy 31.400567 -328.209892)
			(xy 31.398566 -328.25336) (xy 34.599874 -328.25336) (xy 34.599874 -328.16646) (xy 34.607892 -328.079931)
			(xy 34.62386 -327.994511) (xy 34.647641 -327.910929) (xy 34.679033 -327.829897) (xy 34.717767 -327.752108)
			(xy 34.763514 -327.678224) (xy 34.815883 -327.608877) (xy 34.874427 -327.544657) (xy 34.938647 -327.486113)
			(xy 35.007994 -327.433744) (xy 35.081878 -327.387997) (xy 35.159667 -327.349263) (xy 35.240699 -327.317871)
			(xy 35.324281 -327.29409) (xy 35.409701 -327.278122) (xy 35.49623 -327.270104) (xy 35.53968 -327.269602)
			(xy 35.58313 -327.270104) (xy 35.669659 -327.278122) (xy 35.755079 -327.29409) (xy 35.838661 -327.317871)
			(xy 35.919693 -327.349263) (xy 35.997482 -327.387997) (xy 36.071366 -327.433744) (xy 36.140713 -327.486113)
			(xy 36.204933 -327.544657) (xy 36.263477 -327.608877) (xy 36.315846 -327.678224) (xy 36.361593 -327.752108)
			(xy 36.400327 -327.829897) (xy 36.431719 -327.910929) (xy 36.4555 -327.994511) (xy 36.471468 -328.079931)
			(xy 36.479486 -328.16646) (xy 36.479486 -328.25336) (xy 36.471468 -328.339889) (xy 36.4555 -328.425309)
			(xy 36.431719 -328.508891) (xy 36.400327 -328.589923) (xy 36.361593 -328.667712) (xy 36.315846 -328.741596)
			(xy 36.263477 -328.810943) (xy 36.240293 -328.836375) (xy 55.045348 -328.836375) (xy 55.045348 -328.765053)
			(xy 55.053334 -328.694179) (xy 55.069204 -328.624644) (xy 55.092761 -328.557324) (xy 55.123706 -328.493065)
			(xy 55.161652 -328.432674) (xy 55.206121 -328.376912) (xy 55.256554 -328.326479) (xy 55.312316 -328.28201)
			(xy 55.372707 -328.244064) (xy 55.436966 -328.213119) (xy 55.504286 -328.189562) (xy 55.573821 -328.173692)
			(xy 55.644695 -328.165706) (xy 55.680356 -328.165206) (xy 55.716017 -328.165706) (xy 55.786891 -328.173692)
			(xy 55.856426 -328.189562) (xy 55.923746 -328.213119) (xy 55.988005 -328.244064) (xy 56.048396 -328.28201)
			(xy 56.104158 -328.326479) (xy 56.154591 -328.376912) (xy 56.19906 -328.432674) (xy 56.237006 -328.493065)
			(xy 56.267951 -328.557324) (xy 56.291508 -328.624644) (xy 56.307378 -328.694179) (xy 56.315364 -328.765053)
			(xy 56.315364 -328.836375) (xy 56.93206 -328.836375) (xy 56.93206 -328.765053) (xy 56.940046 -328.694179)
			(xy 56.955916 -328.624644) (xy 56.979473 -328.557324) (xy 57.010418 -328.493065) (xy 57.048364 -328.432674)
			(xy 57.092833 -328.376912) (xy 57.143266 -328.326479) (xy 57.199028 -328.28201) (xy 57.259419 -328.244064)
			(xy 57.323678 -328.213119) (xy 57.390998 -328.189562) (xy 57.460533 -328.173692) (xy 57.531407 -328.165706)
			(xy 57.567068 -328.165206) (xy 57.602729 -328.165706) (xy 57.673603 -328.173692) (xy 57.743138 -328.189562)
			(xy 57.810458 -328.213119) (xy 57.874717 -328.244064) (xy 57.935108 -328.28201) (xy 57.99087 -328.326479)
			(xy 58.041303 -328.376912) (xy 58.085772 -328.432674) (xy 58.123718 -328.493065) (xy 58.154663 -328.557324)
			(xy 58.17822 -328.624644) (xy 58.19409 -328.694179) (xy 58.202076 -328.765053) (xy 58.202076 -328.836375)
			(xy 59.173102 -328.836375) (xy 59.173102 -328.765053) (xy 59.181088 -328.694179) (xy 59.196958 -328.624644)
			(xy 59.220515 -328.557324) (xy 59.25146 -328.493065) (xy 59.289406 -328.432674) (xy 59.333875 -328.376912)
			(xy 59.384308 -328.326479) (xy 59.44007 -328.28201) (xy 59.500461 -328.244064) (xy 59.56472 -328.213119)
			(xy 59.63204 -328.189562) (xy 59.701575 -328.173692) (xy 59.772449 -328.165706) (xy 59.80811 -328.165206)
			(xy 59.843771 -328.165706) (xy 59.914645 -328.173692) (xy 59.98418 -328.189562) (xy 60.0515 -328.213119)
			(xy 60.115759 -328.244064) (xy 60.17615 -328.28201) (xy 60.231912 -328.326479) (xy 60.282345 -328.376912)
			(xy 60.326814 -328.432674) (xy 60.36476 -328.493065) (xy 60.395705 -328.557324) (xy 60.419262 -328.624644)
			(xy 60.435132 -328.694179) (xy 60.443118 -328.765053) (xy 60.443118 -328.836375) (xy 61.077086 -328.836375)
			(xy 61.077086 -328.765053) (xy 61.085072 -328.694179) (xy 61.100942 -328.624644) (xy 61.124499 -328.557324)
			(xy 61.155444 -328.493065) (xy 61.19339 -328.432674) (xy 61.237859 -328.376912) (xy 61.288292 -328.326479)
			(xy 61.344054 -328.28201) (xy 61.404445 -328.244064) (xy 61.468704 -328.213119) (xy 61.536024 -328.189562)
			(xy 61.605559 -328.173692) (xy 61.676433 -328.165706) (xy 61.712094 -328.165206) (xy 61.747755 -328.165706)
			(xy 61.818629 -328.173692) (xy 61.888164 -328.189562) (xy 61.955484 -328.213119) (xy 62.019743 -328.244064)
			(xy 62.080134 -328.28201) (xy 62.135896 -328.326479) (xy 62.186329 -328.376912) (xy 62.230798 -328.432674)
			(xy 62.268744 -328.493065) (xy 62.299689 -328.557324) (xy 62.304811 -328.571961) (xy 65.298566 -328.571961)
			(xy 65.298566 -328.500639) (xy 65.306552 -328.429765) (xy 65.322422 -328.36023) (xy 65.345979 -328.29291)
			(xy 65.376924 -328.228651) (xy 65.41487 -328.16826) (xy 65.459339 -328.112498) (xy 65.509772 -328.062065)
			(xy 65.565534 -328.017596) (xy 65.625925 -327.97965) (xy 65.690184 -327.948705) (xy 65.757504 -327.925148)
			(xy 65.827039 -327.909278) (xy 65.897913 -327.901292) (xy 65.933574 -327.900792) (xy 65.969235 -327.901292)
			(xy 66.040109 -327.909278) (xy 66.109644 -327.925148) (xy 66.176964 -327.948705) (xy 66.241223 -327.97965)
			(xy 66.301614 -328.017596) (xy 66.357376 -328.062065) (xy 66.407809 -328.112498) (xy 66.452278 -328.16826)
			(xy 66.490224 -328.228651) (xy 66.521169 -328.29291) (xy 66.544726 -328.36023) (xy 66.560596 -328.429765)
			(xy 66.568582 -328.500639) (xy 66.568582 -328.571961) (xy 68.10298 -328.571961) (xy 68.10298 -328.500639)
			(xy 68.110966 -328.429765) (xy 68.126836 -328.36023) (xy 68.150393 -328.29291) (xy 68.181338 -328.228651)
			(xy 68.219284 -328.16826) (xy 68.263753 -328.112498) (xy 68.314186 -328.062065) (xy 68.369948 -328.017596)
			(xy 68.430339 -327.97965) (xy 68.494598 -327.948705) (xy 68.561918 -327.925148) (xy 68.631453 -327.909278)
			(xy 68.702327 -327.901292) (xy 68.737988 -327.900792) (xy 68.773649 -327.901292) (xy 68.844523 -327.909278)
			(xy 68.914058 -327.925148) (xy 68.981378 -327.948705) (xy 69.045637 -327.97965) (xy 69.106028 -328.017596)
			(xy 69.16179 -328.062065) (xy 69.212223 -328.112498) (xy 69.256692 -328.16826) (xy 69.294638 -328.228651)
			(xy 69.325583 -328.29291) (xy 69.34914 -328.36023) (xy 69.36501 -328.429765) (xy 69.372996 -328.500639)
			(xy 69.372996 -328.571961) (xy 69.36501 -328.642835) (xy 69.34914 -328.71237) (xy 69.325583 -328.77969)
			(xy 69.294638 -328.843949) (xy 69.256692 -328.90434) (xy 69.212223 -328.960102) (xy 69.16179 -329.010535)
			(xy 69.106028 -329.055004) (xy 69.045637 -329.09295) (xy 68.981378 -329.123895) (xy 68.914058 -329.147452)
			(xy 68.844523 -329.163322) (xy 68.773649 -329.171308) (xy 68.702327 -329.171308) (xy 68.631453 -329.163322)
			(xy 68.561918 -329.147452) (xy 68.494598 -329.123895) (xy 68.430339 -329.09295) (xy 68.369948 -329.055004)
			(xy 68.314186 -329.010535) (xy 68.263753 -328.960102) (xy 68.219284 -328.90434) (xy 68.181338 -328.843949)
			(xy 68.150393 -328.77969) (xy 68.126836 -328.71237) (xy 68.110966 -328.642835) (xy 68.10298 -328.571961)
			(xy 66.568582 -328.571961) (xy 66.560596 -328.642835) (xy 66.544726 -328.71237) (xy 66.521169 -328.77969)
			(xy 66.490224 -328.843949) (xy 66.452278 -328.90434) (xy 66.407809 -328.960102) (xy 66.357376 -329.010535)
			(xy 66.301614 -329.055004) (xy 66.241223 -329.09295) (xy 66.176964 -329.123895) (xy 66.109644 -329.147452)
			(xy 66.040109 -329.163322) (xy 65.969235 -329.171308) (xy 65.897913 -329.171308) (xy 65.827039 -329.163322)
			(xy 65.757504 -329.147452) (xy 65.690184 -329.123895) (xy 65.625925 -329.09295) (xy 65.565534 -329.055004)
			(xy 65.509772 -329.010535) (xy 65.459339 -328.960102) (xy 65.41487 -328.90434) (xy 65.376924 -328.843949)
			(xy 65.345979 -328.77969) (xy 65.322422 -328.71237) (xy 65.306552 -328.642835) (xy 65.298566 -328.571961)
			(xy 62.304811 -328.571961) (xy 62.323246 -328.624644) (xy 62.339116 -328.694179) (xy 62.347102 -328.765053)
			(xy 62.347102 -328.836375) (xy 62.339116 -328.907249) (xy 62.323246 -328.976784) (xy 62.299689 -329.044104)
			(xy 62.268744 -329.108363) (xy 62.230798 -329.168754) (xy 62.186329 -329.224516) (xy 62.135896 -329.274949)
			(xy 62.080134 -329.319418) (xy 62.019743 -329.357364) (xy 61.955484 -329.388309) (xy 61.888164 -329.411866)
			(xy 61.818629 -329.427736) (xy 61.747755 -329.435722) (xy 61.676433 -329.435722) (xy 61.605559 -329.427736)
			(xy 61.536024 -329.411866) (xy 61.468704 -329.388309) (xy 61.404445 -329.357364) (xy 61.344054 -329.319418)
			(xy 61.288292 -329.274949) (xy 61.237859 -329.224516) (xy 61.19339 -329.168754) (xy 61.155444 -329.108363)
			(xy 61.124499 -329.044104) (xy 61.100942 -328.976784) (xy 61.085072 -328.907249) (xy 61.077086 -328.836375)
			(xy 60.443118 -328.836375) (xy 60.435132 -328.907249) (xy 60.419262 -328.976784) (xy 60.395705 -329.044104)
			(xy 60.36476 -329.108363) (xy 60.326814 -329.168754) (xy 60.282345 -329.224516) (xy 60.231912 -329.274949)
			(xy 60.17615 -329.319418) (xy 60.115759 -329.357364) (xy 60.0515 -329.388309) (xy 59.98418 -329.411866)
			(xy 59.914645 -329.427736) (xy 59.843771 -329.435722) (xy 59.772449 -329.435722) (xy 59.701575 -329.427736)
			(xy 59.63204 -329.411866) (xy 59.56472 -329.388309) (xy 59.500461 -329.357364) (xy 59.44007 -329.319418)
			(xy 59.384308 -329.274949) (xy 59.333875 -329.224516) (xy 59.289406 -329.168754) (xy 59.25146 -329.108363)
			(xy 59.220515 -329.044104) (xy 59.196958 -328.976784) (xy 59.181088 -328.907249) (xy 59.173102 -328.836375)
			(xy 58.202076 -328.836375) (xy 58.19409 -328.907249) (xy 58.17822 -328.976784) (xy 58.154663 -329.044104)
			(xy 58.123718 -329.108363) (xy 58.085772 -329.168754) (xy 58.041303 -329.224516) (xy 57.99087 -329.274949)
			(xy 57.935108 -329.319418) (xy 57.874717 -329.357364) (xy 57.810458 -329.388309) (xy 57.743138 -329.411866)
			(xy 57.673603 -329.427736) (xy 57.602729 -329.435722) (xy 57.531407 -329.435722) (xy 57.460533 -329.427736)
			(xy 57.390998 -329.411866) (xy 57.323678 -329.388309) (xy 57.259419 -329.357364) (xy 57.199028 -329.319418)
			(xy 57.143266 -329.274949) (xy 57.092833 -329.224516) (xy 57.048364 -329.168754) (xy 57.010418 -329.108363)
			(xy 56.979473 -329.044104) (xy 56.955916 -328.976784) (xy 56.940046 -328.907249) (xy 56.93206 -328.836375)
			(xy 56.315364 -328.836375) (xy 56.307378 -328.907249) (xy 56.291508 -328.976784) (xy 56.267951 -329.044104)
			(xy 56.237006 -329.108363) (xy 56.19906 -329.168754) (xy 56.154591 -329.224516) (xy 56.104158 -329.274949)
			(xy 56.048396 -329.319418) (xy 55.988005 -329.357364) (xy 55.923746 -329.388309) (xy 55.856426 -329.411866)
			(xy 55.786891 -329.427736) (xy 55.716017 -329.435722) (xy 55.644695 -329.435722) (xy 55.573821 -329.427736)
			(xy 55.504286 -329.411866) (xy 55.436966 -329.388309) (xy 55.372707 -329.357364) (xy 55.312316 -329.319418)
			(xy 55.256554 -329.274949) (xy 55.206121 -329.224516) (xy 55.161652 -329.168754) (xy 55.123706 -329.108363)
			(xy 55.092761 -329.044104) (xy 55.069204 -328.976784) (xy 55.053334 -328.907249) (xy 55.045348 -328.836375)
			(xy 36.240293 -328.836375) (xy 36.204933 -328.875163) (xy 36.140713 -328.933707) (xy 36.071366 -328.986076)
			(xy 35.997482 -329.031823) (xy 35.919693 -329.070557) (xy 35.838661 -329.101949) (xy 35.755079 -329.12573)
			(xy 35.669659 -329.141698) (xy 35.618829 -329.146408) (xy 51.402996 -329.146408) (xy 53.055012 -329.146408)
			(xy 53.055012 -330.737311) (xy 55.045348 -330.737311) (xy 55.045348 -330.665989) (xy 55.053334 -330.595115)
			(xy 55.069204 -330.52558) (xy 55.092761 -330.45826) (xy 55.123706 -330.394001) (xy 55.161652 -330.33361)
			(xy 55.206121 -330.277848) (xy 55.256554 -330.227415) (xy 55.312316 -330.182946) (xy 55.372707 -330.145)
			(xy 55.436966 -330.114055) (xy 55.504286 -330.090498) (xy 55.573821 -330.074628) (xy 55.644695 -330.066642)
			(xy 55.680356 -330.066142) (xy 55.716017 -330.066642) (xy 55.786891 -330.074628) (xy 55.856426 -330.090498)
			(xy 55.923746 -330.114055) (xy 55.988005 -330.145) (xy 56.048396 -330.182946) (xy 56.104158 -330.227415)
			(xy 56.154591 -330.277848) (xy 56.19906 -330.33361) (xy 56.237006 -330.394001) (xy 56.267951 -330.45826)
			(xy 56.291508 -330.52558) (xy 56.307378 -330.595115) (xy 56.315364 -330.665989) (xy 56.315364 -330.737311)
			(xy 56.93206 -330.737311) (xy 56.93206 -330.665989) (xy 56.940046 -330.595115) (xy 56.955916 -330.52558)
			(xy 56.979473 -330.45826) (xy 57.010418 -330.394001) (xy 57.048364 -330.33361) (xy 57.092833 -330.277848)
			(xy 57.143266 -330.227415) (xy 57.199028 -330.182946) (xy 57.259419 -330.145) (xy 57.323678 -330.114055)
			(xy 57.390998 -330.090498) (xy 57.460533 -330.074628) (xy 57.531407 -330.066642) (xy 57.567068 -330.066142)
			(xy 57.602729 -330.066642) (xy 57.673603 -330.074628) (xy 57.743138 -330.090498) (xy 57.810458 -330.114055)
			(xy 57.874717 -330.145) (xy 57.935108 -330.182946) (xy 57.99087 -330.227415) (xy 58.041303 -330.277848)
			(xy 58.085772 -330.33361) (xy 58.123718 -330.394001) (xy 58.154663 -330.45826) (xy 58.17822 -330.52558)
			(xy 58.19409 -330.595115) (xy 58.202076 -330.665989) (xy 58.202076 -330.737311) (xy 59.173102 -330.737311)
			(xy 59.173102 -330.665989) (xy 59.181088 -330.595115) (xy 59.196958 -330.52558) (xy 59.220515 -330.45826)
			(xy 59.25146 -330.394001) (xy 59.289406 -330.33361) (xy 59.333875 -330.277848) (xy 59.384308 -330.227415)
			(xy 59.44007 -330.182946) (xy 59.500461 -330.145) (xy 59.56472 -330.114055) (xy 59.63204 -330.090498)
			(xy 59.701575 -330.074628) (xy 59.772449 -330.066642) (xy 59.80811 -330.066142) (xy 59.843771 -330.066642)
			(xy 59.914645 -330.074628) (xy 59.98418 -330.090498) (xy 60.0515 -330.114055) (xy 60.115759 -330.145)
			(xy 60.17615 -330.182946) (xy 60.231912 -330.227415) (xy 60.282345 -330.277848) (xy 60.326814 -330.33361)
			(xy 60.36476 -330.394001) (xy 60.395705 -330.45826) (xy 60.419262 -330.52558) (xy 60.435132 -330.595115)
			(xy 60.443118 -330.665989) (xy 60.443118 -330.737311) (xy 61.077086 -330.737311) (xy 61.077086 -330.665989)
			(xy 61.085072 -330.595115) (xy 61.100942 -330.52558) (xy 61.124499 -330.45826) (xy 61.155444 -330.394001)
			(xy 61.19339 -330.33361) (xy 61.237859 -330.277848) (xy 61.288292 -330.227415) (xy 61.344054 -330.182946)
			(xy 61.404445 -330.145) (xy 61.468704 -330.114055) (xy 61.536024 -330.090498) (xy 61.605559 -330.074628)
			(xy 61.676433 -330.066642) (xy 61.712094 -330.066142) (xy 61.747755 -330.066642) (xy 61.818629 -330.074628)
			(xy 61.888164 -330.090498) (xy 61.955484 -330.114055) (xy 62.019743 -330.145) (xy 62.080134 -330.182946)
			(xy 62.135896 -330.227415) (xy 62.186329 -330.277848) (xy 62.230798 -330.33361) (xy 62.268744 -330.394001)
			(xy 62.299689 -330.45826) (xy 62.323246 -330.52558) (xy 62.339116 -330.595115) (xy 62.347102 -330.665989)
			(xy 62.347102 -330.737311) (xy 62.339116 -330.808185) (xy 62.323246 -330.87772) (xy 62.300207 -330.943559)
			(xy 65.298566 -330.943559) (xy 65.298566 -330.872237) (xy 65.306552 -330.801363) (xy 65.322422 -330.731828)
			(xy 65.345979 -330.664508) (xy 65.376924 -330.600249) (xy 65.41487 -330.539858) (xy 65.459339 -330.484096)
			(xy 65.509772 -330.433663) (xy 65.565534 -330.389194) (xy 65.625925 -330.351248) (xy 65.690184 -330.320303)
			(xy 65.757504 -330.296746) (xy 65.827039 -330.280876) (xy 65.897913 -330.27289) (xy 65.933574 -330.27239)
			(xy 65.969235 -330.27289) (xy 66.040109 -330.280876) (xy 66.109644 -330.296746) (xy 66.176964 -330.320303)
			(xy 66.241223 -330.351248) (xy 66.301614 -330.389194) (xy 66.357376 -330.433663) (xy 66.407809 -330.484096)
			(xy 66.452278 -330.539858) (xy 66.490224 -330.600249) (xy 66.521169 -330.664508) (xy 66.544726 -330.731828)
			(xy 66.560596 -330.801363) (xy 66.568582 -330.872237) (xy 66.568582 -330.943559) (xy 68.10298 -330.943559)
			(xy 68.10298 -330.872237) (xy 68.110966 -330.801363) (xy 68.126836 -330.731828) (xy 68.150393 -330.664508)
			(xy 68.181338 -330.600249) (xy 68.219284 -330.539858) (xy 68.263753 -330.484096) (xy 68.314186 -330.433663)
			(xy 68.369948 -330.389194) (xy 68.430339 -330.351248) (xy 68.494598 -330.320303) (xy 68.561918 -330.296746)
			(xy 68.631453 -330.280876) (xy 68.702327 -330.27289) (xy 68.737988 -330.27239) (xy 68.773649 -330.27289)
			(xy 68.844523 -330.280876) (xy 68.914058 -330.296746) (xy 68.981378 -330.320303) (xy 69.045637 -330.351248)
			(xy 69.106028 -330.389194) (xy 69.16179 -330.433663) (xy 69.212223 -330.484096) (xy 69.256692 -330.539858)
			(xy 69.294638 -330.600249) (xy 69.325583 -330.664508) (xy 69.34914 -330.731828) (xy 69.36501 -330.801363)
			(xy 69.372996 -330.872237) (xy 69.372996 -330.943559) (xy 69.36501 -331.014433) (xy 69.34914 -331.083968)
			(xy 69.325583 -331.151288) (xy 69.297111 -331.210411) (xy 86.399122 -331.210411) (xy 86.401115 -331.010283)
			(xy 86.411112 -330.810394) (xy 86.429099 -330.611066) (xy 86.455047 -330.412617) (xy 86.488914 -330.215365)
			(xy 86.530646 -330.019626) (xy 86.580175 -329.825713) (xy 86.637424 -329.633938) (xy 86.702299 -329.444606)
			(xy 86.774698 -329.258022) (xy 86.854504 -329.074483) (xy 86.941589 -328.894285) (xy 87.035814 -328.717715)
			(xy 87.137028 -328.545056) (xy 87.245069 -328.376586) (xy 87.359764 -328.212572) (xy 87.48093 -328.053279)
			(xy 87.608371 -327.898962) (xy 87.741885 -327.749866) (xy 87.881257 -327.606232) (xy 88.026264 -327.46829)
			(xy 88.176675 -327.336259) (xy 88.332247 -327.210352) (xy 88.492732 -327.09077) (xy 88.657873 -326.977705)
			(xy 88.827405 -326.871337) (xy 89.001058 -326.771838) (xy 89.178552 -326.679366) (xy 89.359604 -326.59407)
			(xy 89.543924 -326.516086) (xy 89.731216 -326.445538) (xy 89.921181 -326.382541) (xy 90.113514 -326.327195)
			(xy 90.307908 -326.279588) (xy 90.504051 -326.239797) (xy 90.701628 -326.207885) (xy 90.900325 -326.183904)
			(xy 91.099821 -326.167891) (xy 91.299799 -326.159874) (xy 91.399868 -326.159368) (xy 91.499937 -326.159864)
			(xy 91.699915 -326.167861) (xy 91.899414 -326.183853) (xy 92.098112 -326.207814) (xy 92.295693 -326.239706)
			(xy 92.49184 -326.279477) (xy 92.686239 -326.327064) (xy 92.878578 -326.382391) (xy 93.068549 -326.445369)
			(xy 93.255848 -326.515897) (xy 93.440176 -326.593863) (xy 93.621237 -326.679141) (xy 93.79874 -326.771594)
			(xy 93.972403 -326.871076) (xy 94.141946 -326.977426) (xy 94.307099 -327.090475) (xy 94.467596 -327.21004)
			(xy 94.623181 -327.335932) (xy 94.773605 -327.467947) (xy 94.918626 -327.605875) (xy 95.058012 -327.749495)
			(xy 95.191541 -327.898576) (xy 95.318999 -328.052881) (xy 95.44018 -328.212162) (xy 95.554892 -328.376163)
			(xy 95.66295 -328.544623) (xy 95.764182 -328.717272) (xy 95.858425 -328.893832) (xy 95.945528 -329.074022)
			(xy 96.025353 -329.257552) (xy 96.09777 -329.444129) (xy 96.162665 -329.633454) (xy 96.219933 -329.825224)
			(xy 96.269483 -330.019131) (xy 96.311234 -330.214866) (xy 96.345121 -330.412115) (xy 96.371089 -330.610561)
			(xy 96.389096 -330.809888) (xy 96.399114 -331.009775) (xy 96.401127 -331.209903) (xy 96.395131 -331.409951)
			(xy 96.381135 -331.6096) (xy 96.359164 -331.808528) (xy 96.32925 -332.006418) (xy 96.291443 -332.202953)
			(xy 96.245804 -332.397818) (xy 96.192404 -332.590701) (xy 96.13133 -332.781293) (xy 96.062679 -332.969288)
			(xy 95.986561 -333.154387) (xy 95.903099 -333.336292) (xy 95.812426 -333.514711) (xy 95.714687 -333.689361)
			(xy 95.610038 -333.85996) (xy 95.498648 -334.026235) (xy 95.380694 -334.18792) (xy 95.256365 -334.344757)
			(xy 95.125862 -334.496494) (xy 94.989391 -334.642888) (xy 94.847173 -334.783704) (xy 94.699435 -334.918718)
			(xy 94.546413 -335.047713) (xy 94.388353 -335.170482) (xy 94.225507 -335.286829) (xy 94.058137 -335.396567)
			(xy 93.88651 -335.499521) (xy 93.710902 -335.595526) (xy 93.531592 -335.684428) (xy 93.34887 -335.766084)
			(xy 93.163027 -335.840365) (xy 92.97436 -335.907151) (xy 92.783173 -335.966334) (xy 92.589771 -336.017821)
			(xy 92.394464 -336.061529) (xy 92.197564 -336.097388) (xy 91.999387 -336.12534) (xy 91.800251 -336.14534)
			(xy 91.600474 -336.157358) (xy 91.400376 -336.161372) (xy 91.200278 -336.157378) (xy 91.000499 -336.145381)
			(xy 90.801361 -336.125401) (xy 90.603182 -336.097469) (xy 90.406278 -336.06163) (xy 90.210967 -336.017942)
			(xy 90.017559 -335.966475) (xy 89.826366 -335.907311) (xy 89.637693 -335.840544) (xy 89.451842 -335.766282)
			(xy 89.269111 -335.684644) (xy 89.089793 -335.595761) (xy 88.914175 -335.499774) (xy 88.742537 -335.396837)
			(xy 88.575156 -335.287116) (xy 88.412298 -335.170785) (xy 88.254226 -335.048032) (xy 88.101191 -334.919053)
			(xy 87.953439 -334.784055) (xy 87.811206 -334.643252) (xy 87.674721 -334.496872) (xy 87.544202 -334.345149)
			(xy 87.419858 -334.188325) (xy 87.301888 -334.026651) (xy 87.19048 -333.860387) (xy 87.085814 -333.689799)
			(xy 86.988057 -333.51516) (xy 86.897366 -333.336749) (xy 86.813885 -333.154853) (xy 86.737749 -332.969762)
			(xy 86.669079 -332.781773) (xy 86.607986 -332.591188) (xy 86.554566 -332.39831) (xy 86.508906 -332.20345)
			(xy 86.47108 -332.006919) (xy 86.441146 -331.809032) (xy 86.419154 -331.610106) (xy 86.405139 -331.410459)
			(xy 86.399122 -331.210411) (xy 69.297111 -331.210411) (xy 69.294638 -331.215547) (xy 69.256692 -331.275938)
			(xy 69.212223 -331.3317) (xy 69.16179 -331.382133) (xy 69.106028 -331.426602) (xy 69.045637 -331.464548)
			(xy 68.981378 -331.495493) (xy 68.914058 -331.51905) (xy 68.844523 -331.53492) (xy 68.773649 -331.542906)
			(xy 68.702327 -331.542906) (xy 68.631453 -331.53492) (xy 68.561918 -331.51905) (xy 68.494598 -331.495493)
			(xy 68.430339 -331.464548) (xy 68.369948 -331.426602) (xy 68.314186 -331.382133) (xy 68.263753 -331.3317)
			(xy 68.219284 -331.275938) (xy 68.181338 -331.215547) (xy 68.150393 -331.151288) (xy 68.126836 -331.083968)
			(xy 68.110966 -331.014433) (xy 68.10298 -330.943559) (xy 66.568582 -330.943559) (xy 66.560596 -331.014433)
			(xy 66.544726 -331.083968) (xy 66.521169 -331.151288) (xy 66.490224 -331.215547) (xy 66.452278 -331.275938)
			(xy 66.407809 -331.3317) (xy 66.357376 -331.382133) (xy 66.301614 -331.426602) (xy 66.241223 -331.464548)
			(xy 66.176964 -331.495493) (xy 66.109644 -331.51905) (xy 66.040109 -331.53492) (xy 65.969235 -331.542906)
			(xy 65.897913 -331.542906) (xy 65.827039 -331.53492) (xy 65.757504 -331.51905) (xy 65.690184 -331.495493)
			(xy 65.625925 -331.464548) (xy 65.565534 -331.426602) (xy 65.509772 -331.382133) (xy 65.459339 -331.3317)
			(xy 65.41487 -331.275938) (xy 65.376924 -331.215547) (xy 65.345979 -331.151288) (xy 65.322422 -331.083968)
			(xy 65.306552 -331.014433) (xy 65.298566 -330.943559) (xy 62.300207 -330.943559) (xy 62.299689 -330.94504)
			(xy 62.268744 -331.009299) (xy 62.230798 -331.06969) (xy 62.186329 -331.125452) (xy 62.135896 -331.175885)
			(xy 62.080134 -331.220354) (xy 62.019743 -331.2583) (xy 61.955484 -331.289245) (xy 61.888164 -331.312802)
			(xy 61.818629 -331.328672) (xy 61.747755 -331.336658) (xy 61.676433 -331.336658) (xy 61.605559 -331.328672)
			(xy 61.536024 -331.312802) (xy 61.468704 -331.289245) (xy 61.404445 -331.2583) (xy 61.344054 -331.220354)
			(xy 61.288292 -331.175885) (xy 61.237859 -331.125452) (xy 61.19339 -331.06969) (xy 61.155444 -331.009299)
			(xy 61.124499 -330.94504) (xy 61.100942 -330.87772) (xy 61.085072 -330.808185) (xy 61.077086 -330.737311)
			(xy 60.443118 -330.737311) (xy 60.435132 -330.808185) (xy 60.419262 -330.87772) (xy 60.395705 -330.94504)
			(xy 60.36476 -331.009299) (xy 60.326814 -331.06969) (xy 60.282345 -331.125452) (xy 60.231912 -331.175885)
			(xy 60.17615 -331.220354) (xy 60.115759 -331.2583) (xy 60.0515 -331.289245) (xy 59.98418 -331.312802)
			(xy 59.914645 -331.328672) (xy 59.843771 -331.336658) (xy 59.772449 -331.336658) (xy 59.701575 -331.328672)
			(xy 59.63204 -331.312802) (xy 59.56472 -331.289245) (xy 59.500461 -331.2583) (xy 59.44007 -331.220354)
			(xy 59.384308 -331.175885) (xy 59.333875 -331.125452) (xy 59.289406 -331.06969) (xy 59.25146 -331.009299)
			(xy 59.220515 -330.94504) (xy 59.196958 -330.87772) (xy 59.181088 -330.808185) (xy 59.173102 -330.737311)
			(xy 58.202076 -330.737311) (xy 58.19409 -330.808185) (xy 58.17822 -330.87772) (xy 58.154663 -330.94504)
			(xy 58.123718 -331.009299) (xy 58.085772 -331.06969) (xy 58.041303 -331.125452) (xy 57.99087 -331.175885)
			(xy 57.935108 -331.220354) (xy 57.874717 -331.2583) (xy 57.810458 -331.289245) (xy 57.743138 -331.312802)
			(xy 57.673603 -331.328672) (xy 57.602729 -331.336658) (xy 57.531407 -331.336658) (xy 57.460533 -331.328672)
			(xy 57.390998 -331.312802) (xy 57.323678 -331.289245) (xy 57.259419 -331.2583) (xy 57.199028 -331.220354)
			(xy 57.143266 -331.175885) (xy 57.092833 -331.125452) (xy 57.048364 -331.06969) (xy 57.010418 -331.009299)
			(xy 56.979473 -330.94504) (xy 56.955916 -330.87772) (xy 56.940046 -330.808185) (xy 56.93206 -330.737311)
			(xy 56.315364 -330.737311) (xy 56.307378 -330.808185) (xy 56.291508 -330.87772) (xy 56.267951 -330.94504)
			(xy 56.237006 -331.009299) (xy 56.19906 -331.06969) (xy 56.154591 -331.125452) (xy 56.104158 -331.175885)
			(xy 56.048396 -331.220354) (xy 55.988005 -331.2583) (xy 55.923746 -331.289245) (xy 55.856426 -331.312802)
			(xy 55.786891 -331.328672) (xy 55.716017 -331.336658) (xy 55.644695 -331.336658) (xy 55.573821 -331.328672)
			(xy 55.504286 -331.312802) (xy 55.436966 -331.289245) (xy 55.372707 -331.2583) (xy 55.312316 -331.220354)
			(xy 55.256554 -331.175885) (xy 55.206121 -331.125452) (xy 55.161652 -331.06969) (xy 55.123706 -331.009299)
			(xy 55.092761 -330.94504) (xy 55.069204 -330.87772) (xy 55.053334 -330.808185) (xy 55.045348 -330.737311)
			(xy 53.055012 -330.737311) (xy 53.055012 -330.798424) (xy 51.402996 -330.798424) (xy 51.402996 -329.146408)
			(xy 35.618829 -329.146408) (xy 35.58313 -329.149716) (xy 35.49623 -329.149716) (xy 35.409701 -329.141698)
			(xy 35.324281 -329.12573) (xy 35.240699 -329.101949) (xy 35.159667 -329.070557) (xy 35.081878 -329.031823)
			(xy 35.007994 -328.986076) (xy 34.938647 -328.933707) (xy 34.874427 -328.875163) (xy 34.815883 -328.810943)
			(xy 34.763514 -328.741596) (xy 34.717767 -328.667712) (xy 34.679033 -328.589923) (xy 34.647641 -328.508891)
			(xy 34.62386 -328.425309) (xy 34.607892 -328.339889) (xy 34.599874 -328.25336) (xy 31.398566 -328.25336)
			(xy 31.396587 -328.296345) (xy 31.384681 -328.382067) (xy 31.364948 -328.466332) (xy 31.337556 -328.548427)
			(xy 31.302736 -328.627658) (xy 31.260783 -328.703354) (xy 31.212052 -328.774875) (xy 31.156956 -328.841616)
			(xy 31.09596 -328.903012) (xy 31.029581 -328.958543) (xy 30.95838 -329.00774) (xy 30.88296 -329.050187)
			(xy 30.803958 -329.085524) (xy 30.722044 -329.113452) (xy 30.63791 -329.133736) (xy 30.552268 -329.146202)
			(xy 30.465843 -329.150747) (xy 30.379366 -329.147331) (xy 30.293568 -329.135984) (xy 30.209177 -329.116801)
			(xy 30.126905 -329.089944) (xy 30.047448 -329.055642) (xy 29.97148 -329.014184) (xy 29.899643 -328.96592)
			(xy 29.832544 -328.911261) (xy 29.770752 -328.850666) (xy 29.742384 -328.817986) (xy 29.727699 -328.801435)
			(xy 29.693651 -328.773183) (xy 29.655223 -328.751256) (xy 29.613579 -328.736317) (xy 29.569976 -328.728816)
			(xy 29.525734 -328.728981) (xy 29.482188 -328.736806) (xy 29.440656 -328.752056) (xy 29.402394 -328.774269)
			(xy 29.368557 -328.802774) (xy 29.340168 -328.836708) (xy 29.318087 -328.875047) (xy 29.30298 -328.916631)
			(xy 29.295303 -328.960203) (xy 29.294836 -328.982324) (xy 29.294836 -329.977496) (xy 29.295314 -329.999621)
			(xy 29.30298 -330.043202) (xy 29.31808 -330.084796) (xy 29.340157 -330.123145) (xy 29.368545 -330.157089)
			(xy 29.402384 -330.185602) (xy 29.440651 -330.207822) (xy 29.482188 -330.223075) (xy 29.525741 -330.230902)
			(xy 29.569991 -330.231065) (xy 29.613599 -330.22356) (xy 29.655248 -330.208613) (xy 29.693678 -330.186676)
			(xy 29.727726 -330.158413) (xy 29.742384 -330.141834) (xy 29.770742 -330.109145) (xy 29.832533 -330.04855)
			(xy 29.899631 -329.993889) (xy 29.971467 -329.945624) (xy 30.047435 -329.904165) (xy 30.12689 -329.869861)
			(xy 30.209162 -329.843003) (xy 30.293553 -329.823819) (xy 30.379351 -329.81247) (xy 30.465828 -329.809053)
			(xy 30.552253 -329.813596) (xy 30.637895 -329.826062) (xy 30.722029 -329.846344) (xy 30.803944 -329.87427)
			(xy 30.882946 -329.909606) (xy 30.958367 -329.952052) (xy 31.029569 -330.001248) (xy 31.095949 -330.056778)
			(xy 31.156946 -330.118173) (xy 31.212043 -330.184913) (xy 31.260775 -330.256433) (xy 31.302729 -330.332129)
			(xy 31.33755 -330.411359) (xy 31.364944 -330.493454) (xy 31.384678 -330.577718) (xy 31.396586 -330.663439)
			(xy 31.400567 -330.749892) (xy 31.398566 -330.79336) (xy 34.599874 -330.79336) (xy 34.599874 -330.70646)
			(xy 34.607892 -330.619931) (xy 34.62386 -330.534511) (xy 34.647641 -330.450929) (xy 34.679033 -330.369897)
			(xy 34.717767 -330.292108) (xy 34.763514 -330.218224) (xy 34.815883 -330.148877) (xy 34.874427 -330.084657)
			(xy 34.938647 -330.026113) (xy 35.007994 -329.973744) (xy 35.081878 -329.927997) (xy 35.159667 -329.889263)
			(xy 35.240699 -329.857871) (xy 35.324281 -329.83409) (xy 35.409701 -329.818122) (xy 35.49623 -329.810104)
			(xy 35.53968 -329.809602) (xy 35.58313 -329.810104) (xy 35.669659 -329.818122) (xy 35.755079 -329.83409)
			(xy 35.838661 -329.857871) (xy 35.919693 -329.889263) (xy 35.997482 -329.927997) (xy 36.071366 -329.973744)
			(xy 36.140713 -330.026113) (xy 36.204933 -330.084657) (xy 36.263477 -330.148877) (xy 36.315846 -330.218224)
			(xy 36.361593 -330.292108) (xy 36.400327 -330.369897) (xy 36.431719 -330.450929) (xy 36.4555 -330.534511)
			(xy 36.471468 -330.619931) (xy 36.479486 -330.70646) (xy 36.479486 -330.79336) (xy 36.471468 -330.879889)
			(xy 36.4555 -330.965309) (xy 36.431719 -331.048891) (xy 36.400327 -331.129923) (xy 36.361593 -331.207712)
			(xy 36.315846 -331.281596) (xy 36.263477 -331.350943) (xy 36.204933 -331.415163) (xy 36.140713 -331.473707)
			(xy 36.071366 -331.526076) (xy 35.997482 -331.571823) (xy 35.919693 -331.610557) (xy 35.838661 -331.641949)
			(xy 35.755079 -331.66573) (xy 35.669659 -331.681698) (xy 35.58313 -331.689716) (xy 35.49623 -331.689716)
			(xy 35.409701 -331.681698) (xy 35.324281 -331.66573) (xy 35.240699 -331.641949) (xy 35.159667 -331.610557)
			(xy 35.081878 -331.571823) (xy 35.007994 -331.526076) (xy 34.938647 -331.473707) (xy 34.874427 -331.415163)
			(xy 34.815883 -331.350943) (xy 34.763514 -331.281596) (xy 34.717767 -331.207712) (xy 34.679033 -331.129923)
			(xy 34.647641 -331.048891) (xy 34.62386 -330.965309) (xy 34.607892 -330.879889) (xy 34.599874 -330.79336)
			(xy 31.398566 -330.79336) (xy 31.396587 -330.836345) (xy 31.384681 -330.922067) (xy 31.364948 -331.006332)
			(xy 31.337556 -331.088427) (xy 31.302736 -331.167658) (xy 31.260783 -331.243354) (xy 31.212052 -331.314875)
			(xy 31.156956 -331.381616) (xy 31.09596 -331.443012) (xy 31.029581 -331.498543) (xy 30.95838 -331.54774)
			(xy 30.88296 -331.590187) (xy 30.803958 -331.625524) (xy 30.722044 -331.653452) (xy 30.63791 -331.673736)
			(xy 30.552268 -331.686202) (xy 30.465843 -331.690747) (xy 30.379366 -331.687331) (xy 30.293568 -331.675984)
			(xy 30.209177 -331.656801) (xy 30.126905 -331.629944) (xy 30.047448 -331.595642) (xy 29.97148 -331.554184)
			(xy 29.899643 -331.50592) (xy 29.832544 -331.451261) (xy 29.770752 -331.390666) (xy 29.742384 -331.357986)
			(xy 29.727699 -331.341435) (xy 29.693651 -331.313183) (xy 29.655223 -331.291256) (xy 29.613579 -331.276317)
			(xy 29.569976 -331.268816) (xy 29.525734 -331.268981) (xy 29.482188 -331.276806) (xy 29.440656 -331.292056)
			(xy 29.402394 -331.314269) (xy 29.368557 -331.342774) (xy 29.340168 -331.376708) (xy 29.318087 -331.415047)
			(xy 29.30298 -331.456631) (xy 29.295303 -331.500203) (xy 29.294836 -331.522324) (xy 29.294836 -332.199843)
			(xy 38.925238 -332.199843) (xy 38.925238 -332.128521) (xy 38.933224 -332.057647) (xy 38.949094 -331.988112)
			(xy 38.972651 -331.920792) (xy 39.003596 -331.856533) (xy 39.041542 -331.796142) (xy 39.086011 -331.74038)
			(xy 39.136444 -331.689947) (xy 39.192206 -331.645478) (xy 39.252597 -331.607532) (xy 39.316856 -331.576587)
			(xy 39.384176 -331.55303) (xy 39.453711 -331.53716) (xy 39.524585 -331.529174) (xy 39.560246 -331.528674)
			(xy 39.595907 -331.529174) (xy 39.666781 -331.53716) (xy 39.736316 -331.55303) (xy 39.803636 -331.576587)
			(xy 39.867895 -331.607532) (xy 39.928286 -331.645478) (xy 39.984048 -331.689947) (xy 40.034481 -331.74038)
			(xy 40.07895 -331.796142) (xy 40.116896 -331.856533) (xy 40.147841 -331.920792) (xy 40.171398 -331.988112)
			(xy 40.187268 -332.057647) (xy 40.195254 -332.128521) (xy 40.195254 -332.199843) (xy 40.187268 -332.270717)
			(xy 40.171398 -332.340252) (xy 40.147841 -332.407572) (xy 40.116896 -332.471831) (xy 40.097715 -332.502357)
			(xy 55.079638 -332.502357) (xy 55.079638 -332.431035) (xy 55.087624 -332.360161) (xy 55.103494 -332.290626)
			(xy 55.127051 -332.223306) (xy 55.157996 -332.159047) (xy 55.195942 -332.098656) (xy 55.240411 -332.042894)
			(xy 55.290844 -331.992461) (xy 55.346606 -331.947992) (xy 55.406997 -331.910046) (xy 55.471256 -331.879101)
			(xy 55.538576 -331.855544) (xy 55.608111 -331.839674) (xy 55.678985 -331.831688) (xy 55.714646 -331.831188)
			(xy 55.750307 -331.831688) (xy 55.821181 -331.839674) (xy 55.890716 -331.855544) (xy 55.958036 -331.879101)
			(xy 56.022295 -331.910046) (xy 56.082686 -331.947992) (xy 56.138448 -331.992461) (xy 56.188881 -332.042894)
			(xy 56.23335 -332.098656) (xy 56.271296 -332.159047) (xy 56.302241 -332.223306) (xy 56.325798 -332.290626)
			(xy 56.341668 -332.360161) (xy 56.349654 -332.431035) (xy 56.349654 -332.502357) (xy 56.96635 -332.502357)
			(xy 56.96635 -332.431035) (xy 56.974336 -332.360161) (xy 56.990206 -332.290626) (xy 57.013763 -332.223306)
			(xy 57.044708 -332.159047) (xy 57.082654 -332.098656) (xy 57.127123 -332.042894) (xy 57.177556 -331.992461)
			(xy 57.233318 -331.947992) (xy 57.293709 -331.910046) (xy 57.357968 -331.879101) (xy 57.425288 -331.855544)
			(xy 57.494823 -331.839674) (xy 57.565697 -331.831688) (xy 57.601358 -331.831188) (xy 57.637019 -331.831688)
			(xy 57.707893 -331.839674) (xy 57.777428 -331.855544) (xy 57.844748 -331.879101) (xy 57.909007 -331.910046)
			(xy 57.969398 -331.947992) (xy 58.02516 -331.992461) (xy 58.075593 -332.042894) (xy 58.120062 -332.098656)
			(xy 58.158008 -332.159047) (xy 58.188953 -332.223306) (xy 58.21251 -332.290626) (xy 58.22838 -332.360161)
			(xy 58.236366 -332.431035) (xy 58.236366 -332.502357) (xy 59.207392 -332.502357) (xy 59.207392 -332.431035)
			(xy 59.215378 -332.360161) (xy 59.231248 -332.290626) (xy 59.254805 -332.223306) (xy 59.28575 -332.159047)
			(xy 59.323696 -332.098656) (xy 59.368165 -332.042894) (xy 59.418598 -331.992461) (xy 59.47436 -331.947992)
			(xy 59.534751 -331.910046) (xy 59.59901 -331.879101) (xy 59.66633 -331.855544) (xy 59.735865 -331.839674)
			(xy 59.806739 -331.831688) (xy 59.8424 -331.831188) (xy 59.878061 -331.831688) (xy 59.948935 -331.839674)
			(xy 60.01847 -331.855544) (xy 60.08579 -331.879101) (xy 60.150049 -331.910046) (xy 60.21044 -331.947992)
			(xy 60.266202 -331.992461) (xy 60.316635 -332.042894) (xy 60.361104 -332.098656) (xy 60.39905 -332.159047)
			(xy 60.429995 -332.223306) (xy 60.453552 -332.290626) (xy 60.469422 -332.360161) (xy 60.477408 -332.431035)
			(xy 60.477408 -332.502357) (xy 61.111376 -332.502357) (xy 61.111376 -332.431035) (xy 61.119362 -332.360161)
			(xy 61.135232 -332.290626) (xy 61.158789 -332.223306) (xy 61.189734 -332.159047) (xy 61.22768 -332.098656)
			(xy 61.272149 -332.042894) (xy 61.322582 -331.992461) (xy 61.378344 -331.947992) (xy 61.438735 -331.910046)
			(xy 61.502994 -331.879101) (xy 61.570314 -331.855544) (xy 61.639849 -331.839674) (xy 61.710723 -331.831688)
			(xy 61.746384 -331.831188) (xy 61.782045 -331.831688) (xy 61.852919 -331.839674) (xy 61.922454 -331.855544)
			(xy 61.989774 -331.879101) (xy 62.054033 -331.910046) (xy 62.114424 -331.947992) (xy 62.170186 -331.992461)
			(xy 62.220619 -332.042894) (xy 62.265088 -332.098656) (xy 62.303034 -332.159047) (xy 62.333979 -332.223306)
			(xy 62.357536 -332.290626) (xy 62.373406 -332.360161) (xy 62.381392 -332.431035) (xy 62.381392 -332.502357)
			(xy 62.373406 -332.573231) (xy 62.357536 -332.642766) (xy 62.333979 -332.710086) (xy 62.303034 -332.774345)
			(xy 62.265088 -332.834736) (xy 62.220619 -332.890498) (xy 62.204646 -332.906471) (xy 65.298566 -332.906471)
			(xy 65.298566 -332.835149) (xy 65.306552 -332.764275) (xy 65.322422 -332.69474) (xy 65.345979 -332.62742)
			(xy 65.376924 -332.563161) (xy 65.41487 -332.50277) (xy 65.459339 -332.447008) (xy 65.509772 -332.396575)
			(xy 65.565534 -332.352106) (xy 65.625925 -332.31416) (xy 65.690184 -332.283215) (xy 65.757504 -332.259658)
			(xy 65.827039 -332.243788) (xy 65.897913 -332.235802) (xy 65.933574 -332.235302) (xy 65.969235 -332.235802)
			(xy 66.040109 -332.243788) (xy 66.109644 -332.259658) (xy 66.176964 -332.283215) (xy 66.241223 -332.31416)
			(xy 66.301614 -332.352106) (xy 66.357376 -332.396575) (xy 66.407809 -332.447008) (xy 66.452278 -332.50277)
			(xy 66.490224 -332.563161) (xy 66.521169 -332.62742) (xy 66.544726 -332.69474) (xy 66.560596 -332.764275)
			(xy 66.568582 -332.835149) (xy 66.568582 -332.906471) (xy 68.10298 -332.906471) (xy 68.10298 -332.835149)
			(xy 68.110966 -332.764275) (xy 68.126836 -332.69474) (xy 68.150393 -332.62742) (xy 68.181338 -332.563161)
			(xy 68.219284 -332.50277) (xy 68.263753 -332.447008) (xy 68.314186 -332.396575) (xy 68.369948 -332.352106)
			(xy 68.430339 -332.31416) (xy 68.494598 -332.283215) (xy 68.561918 -332.259658) (xy 68.631453 -332.243788)
			(xy 68.702327 -332.235802) (xy 68.737988 -332.235302) (xy 68.773649 -332.235802) (xy 68.844523 -332.243788)
			(xy 68.914058 -332.259658) (xy 68.981378 -332.283215) (xy 69.045637 -332.31416) (xy 69.106028 -332.352106)
			(xy 69.16179 -332.396575) (xy 69.212223 -332.447008) (xy 69.256692 -332.50277) (xy 69.294638 -332.563161)
			(xy 69.325583 -332.62742) (xy 69.34914 -332.69474) (xy 69.36501 -332.764275) (xy 69.372996 -332.835149)
			(xy 69.372996 -332.906471) (xy 69.36501 -332.977345) (xy 69.34914 -333.04688) (xy 69.325583 -333.1142)
			(xy 69.294638 -333.178459) (xy 69.256692 -333.23885) (xy 69.212223 -333.294612) (xy 69.16179 -333.345045)
			(xy 69.106028 -333.389514) (xy 69.045637 -333.42746) (xy 68.981378 -333.458405) (xy 68.914058 -333.481962)
			(xy 68.844523 -333.497832) (xy 68.773649 -333.505818) (xy 68.702327 -333.505818) (xy 68.631453 -333.497832)
			(xy 68.561918 -333.481962) (xy 68.494598 -333.458405) (xy 68.430339 -333.42746) (xy 68.369948 -333.389514)
			(xy 68.314186 -333.345045) (xy 68.263753 -333.294612) (xy 68.219284 -333.23885) (xy 68.181338 -333.178459)
			(xy 68.150393 -333.1142) (xy 68.126836 -333.04688) (xy 68.110966 -332.977345) (xy 68.10298 -332.906471)
			(xy 66.568582 -332.906471) (xy 66.560596 -332.977345) (xy 66.544726 -333.04688) (xy 66.521169 -333.1142)
			(xy 66.490224 -333.178459) (xy 66.452278 -333.23885) (xy 66.407809 -333.294612) (xy 66.357376 -333.345045)
			(xy 66.301614 -333.389514) (xy 66.241223 -333.42746) (xy 66.176964 -333.458405) (xy 66.109644 -333.481962)
			(xy 66.040109 -333.497832) (xy 65.969235 -333.505818) (xy 65.897913 -333.505818) (xy 65.827039 -333.497832)
			(xy 65.757504 -333.481962) (xy 65.690184 -333.458405) (xy 65.625925 -333.42746) (xy 65.565534 -333.389514)
			(xy 65.509772 -333.345045) (xy 65.459339 -333.294612) (xy 65.41487 -333.23885) (xy 65.376924 -333.178459)
			(xy 65.345979 -333.1142) (xy 65.322422 -333.04688) (xy 65.306552 -332.977345) (xy 65.298566 -332.906471)
			(xy 62.204646 -332.906471) (xy 62.170186 -332.940931) (xy 62.114424 -332.9854) (xy 62.054033 -333.023346)
			(xy 61.989774 -333.054291) (xy 61.922454 -333.077848) (xy 61.852919 -333.093718) (xy 61.782045 -333.101704)
			(xy 61.710723 -333.101704) (xy 61.639849 -333.093718) (xy 61.570314 -333.077848) (xy 61.502994 -333.054291)
			(xy 61.438735 -333.023346) (xy 61.378344 -332.9854) (xy 61.322582 -332.940931) (xy 61.272149 -332.890498)
			(xy 61.22768 -332.834736) (xy 61.189734 -332.774345) (xy 61.158789 -332.710086) (xy 61.135232 -332.642766)
			(xy 61.119362 -332.573231) (xy 61.111376 -332.502357) (xy 60.477408 -332.502357) (xy 60.469422 -332.573231)
			(xy 60.453552 -332.642766) (xy 60.429995 -332.710086) (xy 60.39905 -332.774345) (xy 60.361104 -332.834736)
			(xy 60.316635 -332.890498) (xy 60.266202 -332.940931) (xy 60.21044 -332.9854) (xy 60.150049 -333.023346)
			(xy 60.08579 -333.054291) (xy 60.01847 -333.077848) (xy 59.948935 -333.093718) (xy 59.878061 -333.101704)
			(xy 59.806739 -333.101704) (xy 59.735865 -333.093718) (xy 59.66633 -333.077848) (xy 59.59901 -333.054291)
			(xy 59.534751 -333.023346) (xy 59.47436 -332.9854) (xy 59.418598 -332.940931) (xy 59.368165 -332.890498)
			(xy 59.323696 -332.834736) (xy 59.28575 -332.774345) (xy 59.254805 -332.710086) (xy 59.231248 -332.642766)
			(xy 59.215378 -332.573231) (xy 59.207392 -332.502357) (xy 58.236366 -332.502357) (xy 58.22838 -332.573231)
			(xy 58.21251 -332.642766) (xy 58.188953 -332.710086) (xy 58.158008 -332.774345) (xy 58.120062 -332.834736)
			(xy 58.075593 -332.890498) (xy 58.02516 -332.940931) (xy 57.969398 -332.9854) (xy 57.909007 -333.023346)
			(xy 57.844748 -333.054291) (xy 57.777428 -333.077848) (xy 57.707893 -333.093718) (xy 57.637019 -333.101704)
			(xy 57.565697 -333.101704) (xy 57.494823 -333.093718) (xy 57.425288 -333.077848) (xy 57.357968 -333.054291)
			(xy 57.293709 -333.023346) (xy 57.233318 -332.9854) (xy 57.177556 -332.940931) (xy 57.127123 -332.890498)
			(xy 57.082654 -332.834736) (xy 57.044708 -332.774345) (xy 57.013763 -332.710086) (xy 56.990206 -332.642766)
			(xy 56.974336 -332.573231) (xy 56.96635 -332.502357) (xy 56.349654 -332.502357) (xy 56.341668 -332.573231)
			(xy 56.325798 -332.642766) (xy 56.302241 -332.710086) (xy 56.271296 -332.774345) (xy 56.23335 -332.834736)
			(xy 56.188881 -332.890498) (xy 56.138448 -332.940931) (xy 56.082686 -332.9854) (xy 56.022295 -333.023346)
			(xy 55.958036 -333.054291) (xy 55.890716 -333.077848) (xy 55.821181 -333.093718) (xy 55.750307 -333.101704)
			(xy 55.678985 -333.101704) (xy 55.608111 -333.093718) (xy 55.538576 -333.077848) (xy 55.471256 -333.054291)
			(xy 55.406997 -333.023346) (xy 55.346606 -332.9854) (xy 55.290844 -332.940931) (xy 55.240411 -332.890498)
			(xy 55.195942 -332.834736) (xy 55.157996 -332.774345) (xy 55.127051 -332.710086) (xy 55.103494 -332.642766)
			(xy 55.087624 -332.573231) (xy 55.079638 -332.502357) (xy 40.097715 -332.502357) (xy 40.07895 -332.532222)
			(xy 40.034481 -332.587984) (xy 39.984048 -332.638417) (xy 39.928286 -332.682886) (xy 39.867895 -332.720832)
			(xy 39.803636 -332.751777) (xy 39.736316 -332.775334) (xy 39.666781 -332.791204) (xy 39.595907 -332.79919)
			(xy 39.524585 -332.79919) (xy 39.453711 -332.791204) (xy 39.384176 -332.775334) (xy 39.316856 -332.751777)
			(xy 39.252597 -332.720832) (xy 39.192206 -332.682886) (xy 39.136444 -332.638417) (xy 39.086011 -332.587984)
			(xy 39.041542 -332.532222) (xy 39.003596 -332.471831) (xy 38.972651 -332.407572) (xy 38.949094 -332.340252)
			(xy 38.933224 -332.270717) (xy 38.925238 -332.199843) (xy 29.294836 -332.199843) (xy 29.294836 -332.517496)
			(xy 29.295314 -332.539621) (xy 29.30298 -332.583202) (xy 29.31808 -332.624796) (xy 29.340157 -332.663145)
			(xy 29.368545 -332.697089) (xy 29.402384 -332.725602) (xy 29.440651 -332.747822) (xy 29.482188 -332.763075)
			(xy 29.525741 -332.770902) (xy 29.569991 -332.771065) (xy 29.613599 -332.76356) (xy 29.655248 -332.748613)
			(xy 29.693678 -332.726676) (xy 29.727726 -332.698413) (xy 29.742384 -332.681834) (xy 29.770742 -332.649145)
			(xy 29.832533 -332.58855) (xy 29.899631 -332.533889) (xy 29.971467 -332.485624) (xy 30.047435 -332.444165)
			(xy 30.12689 -332.409861) (xy 30.209162 -332.383003) (xy 30.293553 -332.363819) (xy 30.379351 -332.35247)
			(xy 30.465828 -332.349053) (xy 30.552253 -332.353596) (xy 30.637895 -332.366062) (xy 30.722029 -332.386344)
			(xy 30.803944 -332.41427) (xy 30.882946 -332.449606) (xy 30.958367 -332.492052) (xy 31.029569 -332.541248)
			(xy 31.095949 -332.596778) (xy 31.156946 -332.658173) (xy 31.212043 -332.724913) (xy 31.260775 -332.796433)
			(xy 31.302729 -332.872129) (xy 31.33755 -332.951359) (xy 31.364944 -333.033454) (xy 31.384678 -333.117718)
			(xy 31.396586 -333.203439) (xy 31.400567 -333.289892) (xy 31.398566 -333.33336) (xy 34.599874 -333.33336)
			(xy 34.599874 -333.24646) (xy 34.607892 -333.159931) (xy 34.62386 -333.074511) (xy 34.647641 -332.990929)
			(xy 34.679033 -332.909897) (xy 34.717767 -332.832108) (xy 34.763514 -332.758224) (xy 34.815883 -332.688877)
			(xy 34.874427 -332.624657) (xy 34.938647 -332.566113) (xy 35.007994 -332.513744) (xy 35.081878 -332.467997)
			(xy 35.159667 -332.429263) (xy 35.240699 -332.397871) (xy 35.324281 -332.37409) (xy 35.409701 -332.358122)
			(xy 35.49623 -332.350104) (xy 35.53968 -332.349602) (xy 35.58313 -332.350104) (xy 35.669659 -332.358122)
			(xy 35.755079 -332.37409) (xy 35.838661 -332.397871) (xy 35.919693 -332.429263) (xy 35.997482 -332.467997)
			(xy 36.071366 -332.513744) (xy 36.140713 -332.566113) (xy 36.204933 -332.624657) (xy 36.263477 -332.688877)
			(xy 36.315846 -332.758224) (xy 36.361593 -332.832108) (xy 36.400327 -332.909897) (xy 36.431719 -332.990929)
			(xy 36.4555 -333.074511) (xy 36.471468 -333.159931) (xy 36.479486 -333.24646) (xy 36.479486 -333.33336)
			(xy 36.471468 -333.419889) (xy 36.4555 -333.505309) (xy 36.431719 -333.588891) (xy 36.400327 -333.669923)
			(xy 36.361593 -333.747712) (xy 36.315846 -333.821596) (xy 36.263477 -333.890943) (xy 36.204933 -333.955163)
			(xy 36.140713 -334.013707) (xy 36.071366 -334.066076) (xy 35.997482 -334.111823) (xy 35.919693 -334.150557)
			(xy 35.838661 -334.181949) (xy 35.755079 -334.20573) (xy 35.669659 -334.221698) (xy 35.58313 -334.229716)
			(xy 35.49623 -334.229716) (xy 35.409701 -334.221698) (xy 35.324281 -334.20573) (xy 35.240699 -334.181949)
			(xy 35.159667 -334.150557) (xy 35.081878 -334.111823) (xy 35.007994 -334.066076) (xy 34.938647 -334.013707)
			(xy 34.874427 -333.955163) (xy 34.815883 -333.890943) (xy 34.763514 -333.821596) (xy 34.717767 -333.747712)
			(xy 34.679033 -333.669923) (xy 34.647641 -333.588891) (xy 34.62386 -333.505309) (xy 34.607892 -333.419889)
			(xy 34.599874 -333.33336) (xy 31.398566 -333.33336) (xy 31.396587 -333.376345) (xy 31.384681 -333.462067)
			(xy 31.364948 -333.546332) (xy 31.337556 -333.628427) (xy 31.302736 -333.707658) (xy 31.260783 -333.783354)
			(xy 31.212052 -333.854875) (xy 31.156956 -333.921616) (xy 31.09596 -333.983012) (xy 31.029581 -334.038543)
			(xy 30.95838 -334.08774) (xy 30.88296 -334.130187) (xy 30.803958 -334.165524) (xy 30.722044 -334.193452)
			(xy 30.63791 -334.213736) (xy 30.552268 -334.226202) (xy 30.465843 -334.230747) (xy 30.379366 -334.227331)
			(xy 30.293568 -334.215984) (xy 30.209177 -334.196801) (xy 30.126905 -334.169944) (xy 30.047448 -334.135642)
			(xy 29.97148 -334.094184) (xy 29.899643 -334.04592) (xy 29.832544 -333.991261) (xy 29.770752 -333.930666)
			(xy 29.742384 -333.897986) (xy 29.727699 -333.881435) (xy 29.693651 -333.853183) (xy 29.655223 -333.831256)
			(xy 29.613579 -333.816317) (xy 29.569976 -333.808816) (xy 29.525734 -333.808981) (xy 29.482188 -333.816806)
			(xy 29.440656 -333.832056) (xy 29.402394 -333.854269) (xy 29.368557 -333.882774) (xy 29.340168 -333.916708)
			(xy 29.318087 -333.955047) (xy 29.30298 -333.996631) (xy 29.295303 -334.040203) (xy 29.294836 -334.062324)
			(xy 29.294836 -334.870653) (xy 38.925238 -334.870653) (xy 38.925238 -334.799331) (xy 38.933224 -334.728457)
			(xy 38.949094 -334.658922) (xy 38.972651 -334.591602) (xy 39.003596 -334.527343) (xy 39.041542 -334.466952)
			(xy 39.086011 -334.41119) (xy 39.136444 -334.360757) (xy 39.192206 -334.316288) (xy 39.252597 -334.278342)
			(xy 39.316856 -334.247397) (xy 39.384176 -334.22384) (xy 39.453711 -334.20797) (xy 39.524585 -334.199984)
			(xy 39.560246 -334.199484) (xy 39.595907 -334.199984) (xy 39.666781 -334.20797) (xy 39.736316 -334.22384)
			(xy 39.803636 -334.247397) (xy 39.867895 -334.278342) (xy 39.928286 -334.316288) (xy 39.984048 -334.360757)
			(xy 40.034481 -334.41119) (xy 40.07895 -334.466952) (xy 40.108216 -334.513529) (xy 55.036204 -334.513529)
			(xy 55.036204 -334.442207) (xy 55.04419 -334.371333) (xy 55.06006 -334.301798) (xy 55.083617 -334.234478)
			(xy 55.114562 -334.170219) (xy 55.152508 -334.109828) (xy 55.196977 -334.054066) (xy 55.24741 -334.003633)
			(xy 55.303172 -333.959164) (xy 55.363563 -333.921218) (xy 55.427822 -333.890273) (xy 55.495142 -333.866716)
			(xy 55.564677 -333.850846) (xy 55.635551 -333.84286) (xy 55.671212 -333.84236) (xy 55.706873 -333.84286)
			(xy 55.777747 -333.850846) (xy 55.847282 -333.866716) (xy 55.914602 -333.890273) (xy 55.978861 -333.921218)
			(xy 56.039252 -333.959164) (xy 56.095014 -334.003633) (xy 56.145447 -334.054066) (xy 56.189916 -334.109828)
			(xy 56.227862 -334.170219) (xy 56.258807 -334.234478) (xy 56.282364 -334.301798) (xy 56.298234 -334.371333)
			(xy 56.30622 -334.442207) (xy 56.30622 -334.513529) (xy 56.922916 -334.513529) (xy 56.922916 -334.442207)
			(xy 56.930902 -334.371333) (xy 56.946772 -334.301798) (xy 56.970329 -334.234478) (xy 57.001274 -334.170219)
			(xy 57.03922 -334.109828) (xy 57.083689 -334.054066) (xy 57.134122 -334.003633) (xy 57.189884 -333.959164)
			(xy 57.250275 -333.921218) (xy 57.314534 -333.890273) (xy 57.381854 -333.866716) (xy 57.451389 -333.850846)
			(xy 57.522263 -333.84286) (xy 57.557924 -333.84236) (xy 57.593585 -333.84286) (xy 57.664459 -333.850846)
			(xy 57.733994 -333.866716) (xy 57.801314 -333.890273) (xy 57.865573 -333.921218) (xy 57.925964 -333.959164)
			(xy 57.981726 -334.003633) (xy 58.032159 -334.054066) (xy 58.076628 -334.109828) (xy 58.114574 -334.170219)
			(xy 58.145519 -334.234478) (xy 58.169076 -334.301798) (xy 58.184946 -334.371333) (xy 58.192932 -334.442207)
			(xy 58.192932 -334.513529) (xy 59.163958 -334.513529) (xy 59.163958 -334.442207) (xy 59.171944 -334.371333)
			(xy 59.187814 -334.301798) (xy 59.211371 -334.234478) (xy 59.242316 -334.170219) (xy 59.280262 -334.109828)
			(xy 59.324731 -334.054066) (xy 59.375164 -334.003633) (xy 59.430926 -333.959164) (xy 59.491317 -333.921218)
			(xy 59.555576 -333.890273) (xy 59.622896 -333.866716) (xy 59.692431 -333.850846) (xy 59.763305 -333.84286)
			(xy 59.798966 -333.84236) (xy 59.834627 -333.84286) (xy 59.905501 -333.850846) (xy 59.975036 -333.866716)
			(xy 60.042356 -333.890273) (xy 60.106615 -333.921218) (xy 60.167006 -333.959164) (xy 60.222768 -334.003633)
			(xy 60.273201 -334.054066) (xy 60.31767 -334.109828) (xy 60.355616 -334.170219) (xy 60.386561 -334.234478)
			(xy 60.410118 -334.301798) (xy 60.425988 -334.371333) (xy 60.433974 -334.442207) (xy 60.433974 -334.513529)
			(xy 61.067942 -334.513529) (xy 61.067942 -334.442207) (xy 61.075928 -334.371333) (xy 61.091798 -334.301798)
			(xy 61.115355 -334.234478) (xy 61.1463 -334.170219) (xy 61.184246 -334.109828) (xy 61.228715 -334.054066)
			(xy 61.279148 -334.003633) (xy 61.33491 -333.959164) (xy 61.395301 -333.921218) (xy 61.45956 -333.890273)
			(xy 61.52688 -333.866716) (xy 61.596415 -333.850846) (xy 61.667289 -333.84286) (xy 61.70295 -333.84236)
			(xy 61.738611 -333.84286) (xy 61.809485 -333.850846) (xy 61.87902 -333.866716) (xy 61.94634 -333.890273)
			(xy 62.010599 -333.921218) (xy 62.07099 -333.959164) (xy 62.126752 -334.003633) (xy 62.177185 -334.054066)
			(xy 62.221654 -334.109828) (xy 62.2596 -334.170219) (xy 62.290545 -334.234478) (xy 62.314102 -334.301798)
			(xy 62.329972 -334.371333) (xy 62.337958 -334.442207) (xy 62.337958 -334.513529) (xy 62.329972 -334.584403)
			(xy 62.314102 -334.653938) (xy 62.290545 -334.721258) (xy 62.2596 -334.785517) (xy 62.221654 -334.845908)
			(xy 62.177185 -334.90167) (xy 62.126752 -334.952103) (xy 62.07099 -334.996572) (xy 62.010599 -335.034518)
			(xy 61.978498 -335.049977) (xy 65.298566 -335.049977) (xy 65.298566 -334.978655) (xy 65.306552 -334.907781)
			(xy 65.322422 -334.838246) (xy 65.345979 -334.770926) (xy 65.376924 -334.706667) (xy 65.41487 -334.646276)
			(xy 65.459339 -334.590514) (xy 65.509772 -334.540081) (xy 65.565534 -334.495612) (xy 65.625925 -334.457666)
			(xy 65.690184 -334.426721) (xy 65.757504 -334.403164) (xy 65.827039 -334.387294) (xy 65.897913 -334.379308)
			(xy 65.933574 -334.378808) (xy 65.969235 -334.379308) (xy 66.040109 -334.387294) (xy 66.109644 -334.403164)
			(xy 66.176964 -334.426721) (xy 66.241223 -334.457666) (xy 66.301614 -334.495612) (xy 66.357376 -334.540081)
			(xy 66.407809 -334.590514) (xy 66.452278 -334.646276) (xy 66.490224 -334.706667) (xy 66.521169 -334.770926)
			(xy 66.544726 -334.838246) (xy 66.560596 -334.907781) (xy 66.568582 -334.978655) (xy 66.568582 -335.049977)
			(xy 68.10298 -335.049977) (xy 68.10298 -334.978655) (xy 68.110966 -334.907781) (xy 68.126836 -334.838246)
			(xy 68.150393 -334.770926) (xy 68.181338 -334.706667) (xy 68.219284 -334.646276) (xy 68.263753 -334.590514)
			(xy 68.314186 -334.540081) (xy 68.369948 -334.495612) (xy 68.430339 -334.457666) (xy 68.494598 -334.426721)
			(xy 68.561918 -334.403164) (xy 68.631453 -334.387294) (xy 68.702327 -334.379308) (xy 68.737988 -334.378808)
			(xy 68.773649 -334.379308) (xy 68.844523 -334.387294) (xy 68.914058 -334.403164) (xy 68.981378 -334.426721)
			(xy 69.045637 -334.457666) (xy 69.106028 -334.495612) (xy 69.16179 -334.540081) (xy 69.212223 -334.590514)
			(xy 69.256692 -334.646276) (xy 69.294638 -334.706667) (xy 69.325583 -334.770926) (xy 69.34914 -334.838246)
			(xy 69.36501 -334.907781) (xy 69.372996 -334.978655) (xy 69.372996 -335.049977) (xy 69.36501 -335.120851)
			(xy 69.34914 -335.190386) (xy 69.325583 -335.257706) (xy 69.294638 -335.321965) (xy 69.256692 -335.382356)
			(xy 69.212223 -335.438118) (xy 69.16179 -335.488551) (xy 69.106028 -335.53302) (xy 69.045637 -335.570966)
			(xy 68.981378 -335.601911) (xy 68.914058 -335.625468) (xy 68.844523 -335.641338) (xy 68.773649 -335.649324)
			(xy 68.702327 -335.649324) (xy 68.631453 -335.641338) (xy 68.561918 -335.625468) (xy 68.494598 -335.601911)
			(xy 68.430339 -335.570966) (xy 68.369948 -335.53302) (xy 68.314186 -335.488551) (xy 68.263753 -335.438118)
			(xy 68.219284 -335.382356) (xy 68.181338 -335.321965) (xy 68.150393 -335.257706) (xy 68.126836 -335.190386)
			(xy 68.110966 -335.120851) (xy 68.10298 -335.049977) (xy 66.568582 -335.049977) (xy 66.560596 -335.120851)
			(xy 66.544726 -335.190386) (xy 66.521169 -335.257706) (xy 66.490224 -335.321965) (xy 66.452278 -335.382356)
			(xy 66.407809 -335.438118) (xy 66.357376 -335.488551) (xy 66.301614 -335.53302) (xy 66.241223 -335.570966)
			(xy 66.176964 -335.601911) (xy 66.109644 -335.625468) (xy 66.040109 -335.641338) (xy 65.969235 -335.649324)
			(xy 65.897913 -335.649324) (xy 65.827039 -335.641338) (xy 65.757504 -335.625468) (xy 65.690184 -335.601911)
			(xy 65.625925 -335.570966) (xy 65.565534 -335.53302) (xy 65.509772 -335.488551) (xy 65.459339 -335.438118)
			(xy 65.41487 -335.382356) (xy 65.376924 -335.321965) (xy 65.345979 -335.257706) (xy 65.322422 -335.190386)
			(xy 65.306552 -335.120851) (xy 65.298566 -335.049977) (xy 61.978498 -335.049977) (xy 61.94634 -335.065463)
			(xy 61.87902 -335.08902) (xy 61.809485 -335.10489) (xy 61.738611 -335.112876) (xy 61.667289 -335.112876)
			(xy 61.596415 -335.10489) (xy 61.52688 -335.08902) (xy 61.45956 -335.065463) (xy 61.395301 -335.034518)
			(xy 61.33491 -334.996572) (xy 61.279148 -334.952103) (xy 61.228715 -334.90167) (xy 61.184246 -334.845908)
			(xy 61.1463 -334.785517) (xy 61.115355 -334.721258) (xy 61.091798 -334.653938) (xy 61.075928 -334.584403)
			(xy 61.067942 -334.513529) (xy 60.433974 -334.513529) (xy 60.425988 -334.584403) (xy 60.410118 -334.653938)
			(xy 60.386561 -334.721258) (xy 60.355616 -334.785517) (xy 60.31767 -334.845908) (xy 60.273201 -334.90167)
			(xy 60.222768 -334.952103) (xy 60.167006 -334.996572) (xy 60.106615 -335.034518) (xy 60.042356 -335.065463)
			(xy 59.975036 -335.08902) (xy 59.905501 -335.10489) (xy 59.834627 -335.112876) (xy 59.763305 -335.112876)
			(xy 59.692431 -335.10489) (xy 59.622896 -335.08902) (xy 59.555576 -335.065463) (xy 59.491317 -335.034518)
			(xy 59.430926 -334.996572) (xy 59.375164 -334.952103) (xy 59.324731 -334.90167) (xy 59.280262 -334.845908)
			(xy 59.242316 -334.785517) (xy 59.211371 -334.721258) (xy 59.187814 -334.653938) (xy 59.171944 -334.584403)
			(xy 59.163958 -334.513529) (xy 58.192932 -334.513529) (xy 58.184946 -334.584403) (xy 58.169076 -334.653938)
			(xy 58.145519 -334.721258) (xy 58.114574 -334.785517) (xy 58.076628 -334.845908) (xy 58.032159 -334.90167)
			(xy 57.981726 -334.952103) (xy 57.925964 -334.996572) (xy 57.865573 -335.034518) (xy 57.801314 -335.065463)
			(xy 57.733994 -335.08902) (xy 57.664459 -335.10489) (xy 57.593585 -335.112876) (xy 57.522263 -335.112876)
			(xy 57.451389 -335.10489) (xy 57.381854 -335.08902) (xy 57.314534 -335.065463) (xy 57.250275 -335.034518)
			(xy 57.189884 -334.996572) (xy 57.134122 -334.952103) (xy 57.083689 -334.90167) (xy 57.03922 -334.845908)
			(xy 57.001274 -334.785517) (xy 56.970329 -334.721258) (xy 56.946772 -334.653938) (xy 56.930902 -334.584403)
			(xy 56.922916 -334.513529) (xy 56.30622 -334.513529) (xy 56.298234 -334.584403) (xy 56.282364 -334.653938)
			(xy 56.258807 -334.721258) (xy 56.227862 -334.785517) (xy 56.189916 -334.845908) (xy 56.145447 -334.90167)
			(xy 56.095014 -334.952103) (xy 56.039252 -334.996572) (xy 55.978861 -335.034518) (xy 55.914602 -335.065463)
			(xy 55.847282 -335.08902) (xy 55.777747 -335.10489) (xy 55.706873 -335.112876) (xy 55.635551 -335.112876)
			(xy 55.564677 -335.10489) (xy 55.495142 -335.08902) (xy 55.427822 -335.065463) (xy 55.363563 -335.034518)
			(xy 55.303172 -334.996572) (xy 55.24741 -334.952103) (xy 55.196977 -334.90167) (xy 55.152508 -334.845908)
			(xy 55.114562 -334.785517) (xy 55.083617 -334.721258) (xy 55.06006 -334.653938) (xy 55.04419 -334.584403)
			(xy 55.036204 -334.513529) (xy 40.108216 -334.513529) (xy 40.116896 -334.527343) (xy 40.147841 -334.591602)
			(xy 40.171398 -334.658922) (xy 40.187268 -334.728457) (xy 40.195254 -334.799331) (xy 40.195254 -334.870653)
			(xy 40.187268 -334.941527) (xy 40.171398 -335.011062) (xy 40.147841 -335.078382) (xy 40.116896 -335.142641)
			(xy 40.07895 -335.203032) (xy 40.034481 -335.258794) (xy 39.984048 -335.309227) (xy 39.928286 -335.353696)
			(xy 39.867895 -335.391642) (xy 39.803636 -335.422587) (xy 39.736316 -335.446144) (xy 39.666781 -335.462014)
			(xy 39.595907 -335.47) (xy 39.524585 -335.47) (xy 39.453711 -335.462014) (xy 39.384176 -335.446144)
			(xy 39.316856 -335.422587) (xy 39.252597 -335.391642) (xy 39.192206 -335.353696) (xy 39.136444 -335.309227)
			(xy 39.086011 -335.258794) (xy 39.041542 -335.203032) (xy 39.003596 -335.142641) (xy 38.972651 -335.078382)
			(xy 38.949094 -335.011062) (xy 38.933224 -334.941527) (xy 38.925238 -334.870653) (xy 29.294836 -334.870653)
			(xy 29.294836 -335.057496) (xy 29.295314 -335.079621) (xy 29.30298 -335.123202) (xy 29.31808 -335.164796)
			(xy 29.340157 -335.203145) (xy 29.368545 -335.237089) (xy 29.402384 -335.265602) (xy 29.440651 -335.287822)
			(xy 29.482188 -335.303075) (xy 29.525741 -335.310902) (xy 29.569991 -335.311065) (xy 29.613599 -335.30356)
			(xy 29.655248 -335.288613) (xy 29.693678 -335.266676) (xy 29.727726 -335.238413) (xy 29.742384 -335.221834)
			(xy 29.770742 -335.189145) (xy 29.832533 -335.12855) (xy 29.899631 -335.073889) (xy 29.971467 -335.025624)
			(xy 30.047435 -334.984165) (xy 30.12689 -334.949861) (xy 30.209162 -334.923003) (xy 30.293553 -334.903819)
			(xy 30.379351 -334.89247) (xy 30.465828 -334.889053) (xy 30.552253 -334.893596) (xy 30.637895 -334.906062)
			(xy 30.722029 -334.926344) (xy 30.803944 -334.95427) (xy 30.882946 -334.989606) (xy 30.958367 -335.032052)
			(xy 31.029569 -335.081248) (xy 31.095949 -335.136778) (xy 31.156946 -335.198173) (xy 31.212043 -335.264913)
			(xy 31.260775 -335.336433) (xy 31.302729 -335.412129) (xy 31.33755 -335.491359) (xy 31.364944 -335.573454)
			(xy 31.384678 -335.657718) (xy 31.396586 -335.743439) (xy 31.400567 -335.829892) (xy 31.398566 -335.87336)
			(xy 34.599874 -335.87336) (xy 34.599874 -335.78646) (xy 34.607892 -335.699931) (xy 34.62386 -335.614511)
			(xy 34.647641 -335.530929) (xy 34.679033 -335.449897) (xy 34.717767 -335.372108) (xy 34.763514 -335.298224)
			(xy 34.815883 -335.228877) (xy 34.874427 -335.164657) (xy 34.938647 -335.106113) (xy 35.007994 -335.053744)
			(xy 35.081878 -335.007997) (xy 35.159667 -334.969263) (xy 35.240699 -334.937871) (xy 35.324281 -334.91409)
			(xy 35.409701 -334.898122) (xy 35.49623 -334.890104) (xy 35.53968 -334.889602) (xy 35.58313 -334.890104)
			(xy 35.669659 -334.898122) (xy 35.755079 -334.91409) (xy 35.838661 -334.937871) (xy 35.919693 -334.969263)
			(xy 35.997482 -335.007997) (xy 36.071366 -335.053744) (xy 36.140713 -335.106113) (xy 36.204933 -335.164657)
			(xy 36.263477 -335.228877) (xy 36.315846 -335.298224) (xy 36.361593 -335.372108) (xy 36.400327 -335.449897)
			(xy 36.431719 -335.530929) (xy 36.4555 -335.614511) (xy 36.471468 -335.699931) (xy 36.479486 -335.78646)
			(xy 36.479486 -335.87336) (xy 36.471468 -335.959889) (xy 36.4555 -336.045309) (xy 36.431719 -336.128891)
			(xy 36.400327 -336.209923) (xy 36.361593 -336.287712) (xy 36.315846 -336.361596) (xy 36.283785 -336.404051)
			(xy 55.036204 -336.404051) (xy 55.036204 -336.332729) (xy 55.04419 -336.261855) (xy 55.06006 -336.19232)
			(xy 55.083617 -336.125) (xy 55.114562 -336.060741) (xy 55.152508 -336.00035) (xy 55.196977 -335.944588)
			(xy 55.24741 -335.894155) (xy 55.303172 -335.849686) (xy 55.363563 -335.81174) (xy 55.427822 -335.780795)
			(xy 55.495142 -335.757238) (xy 55.564677 -335.741368) (xy 55.635551 -335.733382) (xy 55.671212 -335.732882)
			(xy 55.706873 -335.733382) (xy 55.777747 -335.741368) (xy 55.847282 -335.757238) (xy 55.914602 -335.780795)
			(xy 55.978861 -335.81174) (xy 56.039252 -335.849686) (xy 56.095014 -335.894155) (xy 56.145447 -335.944588)
			(xy 56.189916 -336.00035) (xy 56.227862 -336.060741) (xy 56.258807 -336.125) (xy 56.282364 -336.19232)
			(xy 56.298234 -336.261855) (xy 56.30622 -336.332729) (xy 56.30622 -336.404051) (xy 56.922916 -336.404051)
			(xy 56.922916 -336.332729) (xy 56.930902 -336.261855) (xy 56.946772 -336.19232) (xy 56.970329 -336.125)
			(xy 57.001274 -336.060741) (xy 57.03922 -336.00035) (xy 57.083689 -335.944588) (xy 57.134122 -335.894155)
			(xy 57.189884 -335.849686) (xy 57.250275 -335.81174) (xy 57.314534 -335.780795) (xy 57.381854 -335.757238)
			(xy 57.451389 -335.741368) (xy 57.522263 -335.733382) (xy 57.557924 -335.732882) (xy 57.593585 -335.733382)
			(xy 57.664459 -335.741368) (xy 57.733994 -335.757238) (xy 57.801314 -335.780795) (xy 57.865573 -335.81174)
			(xy 57.925964 -335.849686) (xy 57.981726 -335.894155) (xy 58.032159 -335.944588) (xy 58.076628 -336.00035)
			(xy 58.114574 -336.060741) (xy 58.145519 -336.125) (xy 58.169076 -336.19232) (xy 58.184946 -336.261855)
			(xy 58.192932 -336.332729) (xy 58.192932 -336.404051) (xy 59.163958 -336.404051) (xy 59.163958 -336.332729)
			(xy 59.171944 -336.261855) (xy 59.187814 -336.19232) (xy 59.211371 -336.125) (xy 59.242316 -336.060741)
			(xy 59.280262 -336.00035) (xy 59.324731 -335.944588) (xy 59.375164 -335.894155) (xy 59.430926 -335.849686)
			(xy 59.491317 -335.81174) (xy 59.555576 -335.780795) (xy 59.622896 -335.757238) (xy 59.692431 -335.741368)
			(xy 59.763305 -335.733382) (xy 59.798966 -335.732882) (xy 59.834627 -335.733382) (xy 59.905501 -335.741368)
			(xy 59.975036 -335.757238) (xy 60.042356 -335.780795) (xy 60.106615 -335.81174) (xy 60.167006 -335.849686)
			(xy 60.222768 -335.894155) (xy 60.273201 -335.944588) (xy 60.31767 -336.00035) (xy 60.355616 -336.060741)
			(xy 60.386561 -336.125) (xy 60.410118 -336.19232) (xy 60.425988 -336.261855) (xy 60.433974 -336.332729)
			(xy 60.433974 -336.404051) (xy 61.067942 -336.404051) (xy 61.067942 -336.332729) (xy 61.075928 -336.261855)
			(xy 61.091798 -336.19232) (xy 61.115355 -336.125) (xy 61.1463 -336.060741) (xy 61.184246 -336.00035)
			(xy 61.228715 -335.944588) (xy 61.279148 -335.894155) (xy 61.33491 -335.849686) (xy 61.395301 -335.81174)
			(xy 61.45956 -335.780795) (xy 61.52688 -335.757238) (xy 61.596415 -335.741368) (xy 61.667289 -335.733382)
			(xy 61.70295 -335.732882) (xy 61.738611 -335.733382) (xy 61.809485 -335.741368) (xy 61.87902 -335.757238)
			(xy 61.94634 -335.780795) (xy 62.010599 -335.81174) (xy 62.07099 -335.849686) (xy 62.126752 -335.894155)
			(xy 62.177185 -335.944588) (xy 62.221654 -336.00035) (xy 62.2596 -336.060741) (xy 62.290545 -336.125)
			(xy 62.314102 -336.19232) (xy 62.329972 -336.261855) (xy 62.337958 -336.332729) (xy 62.337958 -336.404051)
			(xy 62.329972 -336.474925) (xy 62.314102 -336.54446) (xy 62.290545 -336.61178) (xy 62.2596 -336.676039)
			(xy 62.221654 -336.73643) (xy 62.177185 -336.792192) (xy 62.126752 -336.842625) (xy 62.07099 -336.887094)
			(xy 62.010599 -336.92504) (xy 61.94634 -336.955985) (xy 61.87902 -336.979542) (xy 61.809485 -336.995412)
			(xy 61.738611 -337.003398) (xy 61.667289 -337.003398) (xy 61.596415 -336.995412) (xy 61.52688 -336.979542)
			(xy 61.45956 -336.955985) (xy 61.395301 -336.92504) (xy 61.33491 -336.887094) (xy 61.279148 -336.842625)
			(xy 61.228715 -336.792192) (xy 61.184246 -336.73643) (xy 61.1463 -336.676039) (xy 61.115355 -336.61178)
			(xy 61.091798 -336.54446) (xy 61.075928 -336.474925) (xy 61.067942 -336.404051) (xy 60.433974 -336.404051)
			(xy 60.425988 -336.474925) (xy 60.410118 -336.54446) (xy 60.386561 -336.61178) (xy 60.355616 -336.676039)
			(xy 60.31767 -336.73643) (xy 60.273201 -336.792192) (xy 60.222768 -336.842625) (xy 60.167006 -336.887094)
			(xy 60.106615 -336.92504) (xy 60.042356 -336.955985) (xy 59.975036 -336.979542) (xy 59.905501 -336.995412)
			(xy 59.834627 -337.003398) (xy 59.763305 -337.003398) (xy 59.692431 -336.995412) (xy 59.622896 -336.979542)
			(xy 59.555576 -336.955985) (xy 59.491317 -336.92504) (xy 59.430926 -336.887094) (xy 59.375164 -336.842625)
			(xy 59.324731 -336.792192) (xy 59.280262 -336.73643) (xy 59.242316 -336.676039) (xy 59.211371 -336.61178)
			(xy 59.187814 -336.54446) (xy 59.171944 -336.474925) (xy 59.163958 -336.404051) (xy 58.192932 -336.404051)
			(xy 58.184946 -336.474925) (xy 58.169076 -336.54446) (xy 58.145519 -336.61178) (xy 58.114574 -336.676039)
			(xy 58.076628 -336.73643) (xy 58.032159 -336.792192) (xy 57.981726 -336.842625) (xy 57.925964 -336.887094)
			(xy 57.865573 -336.92504) (xy 57.801314 -336.955985) (xy 57.733994 -336.979542) (xy 57.664459 -336.995412)
			(xy 57.593585 -337.003398) (xy 57.522263 -337.003398) (xy 57.451389 -336.995412) (xy 57.381854 -336.979542)
			(xy 57.314534 -336.955985) (xy 57.250275 -336.92504) (xy 57.189884 -336.887094) (xy 57.134122 -336.842625)
			(xy 57.083689 -336.792192) (xy 57.03922 -336.73643) (xy 57.001274 -336.676039) (xy 56.970329 -336.61178)
			(xy 56.946772 -336.54446) (xy 56.930902 -336.474925) (xy 56.922916 -336.404051) (xy 56.30622 -336.404051)
			(xy 56.298234 -336.474925) (xy 56.282364 -336.54446) (xy 56.258807 -336.61178) (xy 56.227862 -336.676039)
			(xy 56.189916 -336.73643) (xy 56.145447 -336.792192) (xy 56.095014 -336.842625) (xy 56.039252 -336.887094)
			(xy 55.978861 -336.92504) (xy 55.914602 -336.955985) (xy 55.847282 -336.979542) (xy 55.777747 -336.995412)
			(xy 55.706873 -337.003398) (xy 55.635551 -337.003398) (xy 55.564677 -336.995412) (xy 55.495142 -336.979542)
			(xy 55.427822 -336.955985) (xy 55.363563 -336.92504) (xy 55.303172 -336.887094) (xy 55.24741 -336.842625)
			(xy 55.196977 -336.792192) (xy 55.152508 -336.73643) (xy 55.114562 -336.676039) (xy 55.083617 -336.61178)
			(xy 55.06006 -336.54446) (xy 55.04419 -336.474925) (xy 55.036204 -336.404051) (xy 36.283785 -336.404051)
			(xy 36.263477 -336.430943) (xy 36.204933 -336.495163) (xy 36.140713 -336.553707) (xy 36.071366 -336.606076)
			(xy 35.997482 -336.651823) (xy 35.919693 -336.690557) (xy 35.838661 -336.721949) (xy 35.755079 -336.74573)
			(xy 35.669659 -336.761698) (xy 35.58313 -336.769716) (xy 35.49623 -336.769716) (xy 35.409701 -336.761698)
			(xy 35.324281 -336.74573) (xy 35.240699 -336.721949) (xy 35.159667 -336.690557) (xy 35.081878 -336.651823)
			(xy 35.007994 -336.606076) (xy 34.938647 -336.553707) (xy 34.874427 -336.495163) (xy 34.815883 -336.430943)
			(xy 34.763514 -336.361596) (xy 34.717767 -336.287712) (xy 34.679033 -336.209923) (xy 34.647641 -336.128891)
			(xy 34.62386 -336.045309) (xy 34.607892 -335.959889) (xy 34.599874 -335.87336) (xy 31.398566 -335.87336)
			(xy 31.396587 -335.916345) (xy 31.384681 -336.002067) (xy 31.364948 -336.086332) (xy 31.337556 -336.168427)
			(xy 31.302736 -336.247658) (xy 31.260783 -336.323354) (xy 31.212052 -336.394875) (xy 31.156956 -336.461616)
			(xy 31.09596 -336.523012) (xy 31.029581 -336.578543) (xy 30.95838 -336.62774) (xy 30.88296 -336.670187)
			(xy 30.803958 -336.705524) (xy 30.722044 -336.733452) (xy 30.63791 -336.753736) (xy 30.552268 -336.766202)
			(xy 30.465843 -336.770747) (xy 30.379366 -336.767331) (xy 30.293568 -336.755984) (xy 30.209177 -336.736801)
			(xy 30.126905 -336.709944) (xy 30.047448 -336.675642) (xy 29.97148 -336.634184) (xy 29.899643 -336.58592)
			(xy 29.832544 -336.531261) (xy 29.770752 -336.470666) (xy 29.742384 -336.437986) (xy 29.727699 -336.421435)
			(xy 29.693651 -336.393183) (xy 29.655223 -336.371256) (xy 29.613579 -336.356317) (xy 29.569976 -336.348816)
			(xy 29.525734 -336.348981) (xy 29.482188 -336.356806) (xy 29.440656 -336.372056) (xy 29.402394 -336.394269)
			(xy 29.368557 -336.422774) (xy 29.340168 -336.456708) (xy 29.318087 -336.495047) (xy 29.30298 -336.536631)
			(xy 29.295303 -336.580203) (xy 29.294836 -336.602324) (xy 29.294836 -337.597496) (xy 29.295314 -337.619621)
			(xy 29.30298 -337.663202) (xy 29.31808 -337.704796) (xy 29.340157 -337.743145) (xy 29.368545 -337.777089)
			(xy 29.402384 -337.805602) (xy 29.440651 -337.827822) (xy 29.482188 -337.843075) (xy 29.525741 -337.850902)
			(xy 29.569991 -337.851065) (xy 29.613599 -337.84356) (xy 29.655248 -337.828613) (xy 29.693678 -337.806676)
			(xy 29.727726 -337.778413) (xy 29.742384 -337.761834) (xy 29.770742 -337.729145) (xy 29.832533 -337.66855)
			(xy 29.899631 -337.613889) (xy 29.971467 -337.565624) (xy 30.047435 -337.524165) (xy 30.12689 -337.489861)
			(xy 30.209162 -337.463003) (xy 30.293553 -337.443819) (xy 30.379351 -337.43247) (xy 30.465828 -337.429053)
			(xy 30.552253 -337.433596) (xy 30.637895 -337.446062) (xy 30.722029 -337.466344) (xy 30.803944 -337.49427)
			(xy 30.882946 -337.529606) (xy 30.958367 -337.572052) (xy 31.029569 -337.621248) (xy 31.095949 -337.676778)
			(xy 31.156946 -337.738173) (xy 31.212043 -337.804913) (xy 31.260775 -337.876433) (xy 31.302729 -337.952129)
			(xy 31.33755 -338.031359) (xy 31.364944 -338.113454) (xy 31.384678 -338.197718) (xy 31.396586 -338.283439)
			(xy 31.400567 -338.369892) (xy 31.398566 -338.41336) (xy 34.599874 -338.41336) (xy 34.599874 -338.32646)
			(xy 34.607892 -338.239931) (xy 34.62386 -338.154511) (xy 34.647641 -338.070929) (xy 34.679033 -337.989897)
			(xy 34.717767 -337.912108) (xy 34.763514 -337.838224) (xy 34.815883 -337.768877) (xy 34.874427 -337.704657)
			(xy 34.938647 -337.646113) (xy 35.007994 -337.593744) (xy 35.081878 -337.547997) (xy 35.159667 -337.509263)
			(xy 35.240699 -337.477871) (xy 35.324281 -337.45409) (xy 35.409701 -337.438122) (xy 35.49623 -337.430104)
			(xy 35.53968 -337.429602) (xy 35.58313 -337.430104) (xy 35.669659 -337.438122) (xy 35.755079 -337.45409)
			(xy 35.838661 -337.477871) (xy 35.919693 -337.509263) (xy 35.979259 -337.538923) (xy 38.925238 -337.538923)
			(xy 38.925238 -337.467601) (xy 38.933224 -337.396727) (xy 38.949094 -337.327192) (xy 38.972651 -337.259872)
			(xy 39.003596 -337.195613) (xy 39.041542 -337.135222) (xy 39.086011 -337.07946) (xy 39.136444 -337.029027)
			(xy 39.192206 -336.984558) (xy 39.252597 -336.946612) (xy 39.316856 -336.915667) (xy 39.384176 -336.89211)
			(xy 39.453711 -336.87624) (xy 39.524585 -336.868254) (xy 39.560246 -336.867754) (xy 39.595907 -336.868254)
			(xy 39.666781 -336.87624) (xy 39.736316 -336.89211) (xy 39.803636 -336.915667) (xy 39.867895 -336.946612)
			(xy 39.928286 -336.984558) (xy 39.984048 -337.029027) (xy 40.034481 -337.07946) (xy 40.07895 -337.135222)
			(xy 40.116896 -337.195613) (xy 40.147841 -337.259872) (xy 40.171398 -337.327192) (xy 40.187268 -337.396727)
			(xy 40.195254 -337.467601) (xy 40.195254 -337.538923) (xy 40.187268 -337.609797) (xy 40.171398 -337.679332)
			(xy 40.147841 -337.746652) (xy 40.116896 -337.810911) (xy 40.07895 -337.871302) (xy 40.034481 -337.927064)
			(xy 39.984048 -337.977497) (xy 39.928286 -338.021966) (xy 39.867895 -338.059912) (xy 39.803636 -338.090857)
			(xy 39.736316 -338.114414) (xy 39.666781 -338.130284) (xy 39.595907 -338.13827) (xy 39.524585 -338.13827)
			(xy 39.453711 -338.130284) (xy 39.384176 -338.114414) (xy 39.316856 -338.090857) (xy 39.252597 -338.059912)
			(xy 39.192206 -338.021966) (xy 39.136444 -337.977497) (xy 39.086011 -337.927064) (xy 39.041542 -337.871302)
			(xy 39.003596 -337.810911) (xy 38.972651 -337.746652) (xy 38.949094 -337.679332) (xy 38.933224 -337.609797)
			(xy 38.925238 -337.538923) (xy 35.979259 -337.538923) (xy 35.997482 -337.547997) (xy 36.071366 -337.593744)
			(xy 36.140713 -337.646113) (xy 36.204933 -337.704657) (xy 36.263477 -337.768877) (xy 36.315846 -337.838224)
			(xy 36.361593 -337.912108) (xy 36.400327 -337.989897) (xy 36.431719 -338.070929) (xy 36.4555 -338.154511)
			(xy 36.471468 -338.239931) (xy 36.479486 -338.32646) (xy 36.479486 -338.41336) (xy 36.476536 -338.445195)
			(xy 55.036204 -338.445195) (xy 55.036204 -338.373873) (xy 55.04419 -338.302999) (xy 55.06006 -338.233464)
			(xy 55.083617 -338.166144) (xy 55.114562 -338.101885) (xy 55.152508 -338.041494) (xy 55.196977 -337.985732)
			(xy 55.24741 -337.935299) (xy 55.303172 -337.89083) (xy 55.363563 -337.852884) (xy 55.427822 -337.821939)
			(xy 55.495142 -337.798382) (xy 55.564677 -337.782512) (xy 55.635551 -337.774526) (xy 55.671212 -337.774026)
			(xy 55.706873 -337.774526) (xy 55.777747 -337.782512) (xy 55.847282 -337.798382) (xy 55.914602 -337.821939)
			(xy 55.978861 -337.852884) (xy 56.039252 -337.89083) (xy 56.095014 -337.935299) (xy 56.145447 -337.985732)
			(xy 56.189916 -338.041494) (xy 56.227862 -338.101885) (xy 56.258807 -338.166144) (xy 56.282364 -338.233464)
			(xy 56.298234 -338.302999) (xy 56.30622 -338.373873) (xy 56.30622 -338.445195) (xy 56.922916 -338.445195)
			(xy 56.922916 -338.373873) (xy 56.930902 -338.302999) (xy 56.946772 -338.233464) (xy 56.970329 -338.166144)
			(xy 57.001274 -338.101885) (xy 57.03922 -338.041494) (xy 57.083689 -337.985732) (xy 57.134122 -337.935299)
			(xy 57.189884 -337.89083) (xy 57.250275 -337.852884) (xy 57.314534 -337.821939) (xy 57.381854 -337.798382)
			(xy 57.451389 -337.782512) (xy 57.522263 -337.774526) (xy 57.557924 -337.774026) (xy 57.593585 -337.774526)
			(xy 57.664459 -337.782512) (xy 57.733994 -337.798382) (xy 57.801314 -337.821939) (xy 57.865573 -337.852884)
			(xy 57.925964 -337.89083) (xy 57.981726 -337.935299) (xy 58.032159 -337.985732) (xy 58.076628 -338.041494)
			(xy 58.114574 -338.101885) (xy 58.145519 -338.166144) (xy 58.169076 -338.233464) (xy 58.184946 -338.302999)
			(xy 58.192932 -338.373873) (xy 58.192932 -338.445195) (xy 59.163958 -338.445195) (xy 59.163958 -338.373873)
			(xy 59.171944 -338.302999) (xy 59.187814 -338.233464) (xy 59.211371 -338.166144) (xy 59.242316 -338.101885)
			(xy 59.280262 -338.041494) (xy 59.324731 -337.985732) (xy 59.375164 -337.935299) (xy 59.430926 -337.89083)
			(xy 59.491317 -337.852884) (xy 59.555576 -337.821939) (xy 59.622896 -337.798382) (xy 59.692431 -337.782512)
			(xy 59.763305 -337.774526) (xy 59.798966 -337.774026) (xy 59.834627 -337.774526) (xy 59.905501 -337.782512)
			(xy 59.975036 -337.798382) (xy 60.042356 -337.821939) (xy 60.106615 -337.852884) (xy 60.167006 -337.89083)
			(xy 60.222768 -337.935299) (xy 60.273201 -337.985732) (xy 60.31767 -338.041494) (xy 60.355616 -338.101885)
			(xy 60.386561 -338.166144) (xy 60.410118 -338.233464) (xy 60.425988 -338.302999) (xy 60.433974 -338.373873)
			(xy 60.433974 -338.445195) (xy 61.067942 -338.445195) (xy 61.067942 -338.373873) (xy 61.075928 -338.302999)
			(xy 61.091798 -338.233464) (xy 61.115355 -338.166144) (xy 61.1463 -338.101885) (xy 61.184246 -338.041494)
			(xy 61.228715 -337.985732) (xy 61.279148 -337.935299) (xy 61.33491 -337.89083) (xy 61.395301 -337.852884)
			(xy 61.45956 -337.821939) (xy 61.52688 -337.798382) (xy 61.596415 -337.782512) (xy 61.667289 -337.774526)
			(xy 61.70295 -337.774026) (xy 61.738611 -337.774526) (xy 61.809485 -337.782512) (xy 61.87902 -337.798382)
			(xy 61.94634 -337.821939) (xy 62.010599 -337.852884) (xy 62.07099 -337.89083) (xy 62.126752 -337.935299)
			(xy 62.177185 -337.985732) (xy 62.221654 -338.041494) (xy 62.2596 -338.101885) (xy 62.290545 -338.166144)
			(xy 62.314102 -338.233464) (xy 62.329972 -338.302999) (xy 62.337958 -338.373873) (xy 62.337958 -338.445195)
			(xy 62.329972 -338.516069) (xy 62.314102 -338.585604) (xy 62.290545 -338.652924) (xy 62.2596 -338.717183)
			(xy 62.221654 -338.777574) (xy 62.177185 -338.833336) (xy 62.126752 -338.883769) (xy 62.07099 -338.928238)
			(xy 62.010599 -338.966184) (xy 61.94634 -338.997129) (xy 61.87902 -339.020686) (xy 61.809485 -339.036556)
			(xy 61.738611 -339.044542) (xy 61.667289 -339.044542) (xy 61.596415 -339.036556) (xy 61.52688 -339.020686)
			(xy 61.45956 -338.997129) (xy 61.395301 -338.966184) (xy 61.33491 -338.928238) (xy 61.279148 -338.883769)
			(xy 61.228715 -338.833336) (xy 61.184246 -338.777574) (xy 61.1463 -338.717183) (xy 61.115355 -338.652924)
			(xy 61.091798 -338.585604) (xy 61.075928 -338.516069) (xy 61.067942 -338.445195) (xy 60.433974 -338.445195)
			(xy 60.425988 -338.516069) (xy 60.410118 -338.585604) (xy 60.386561 -338.652924) (xy 60.355616 -338.717183)
			(xy 60.31767 -338.777574) (xy 60.273201 -338.833336) (xy 60.222768 -338.883769) (xy 60.167006 -338.928238)
			(xy 60.106615 -338.966184) (xy 60.042356 -338.997129) (xy 59.975036 -339.020686) (xy 59.905501 -339.036556)
			(xy 59.834627 -339.044542) (xy 59.763305 -339.044542) (xy 59.692431 -339.036556) (xy 59.622896 -339.020686)
			(xy 59.555576 -338.997129) (xy 59.491317 -338.966184) (xy 59.430926 -338.928238) (xy 59.375164 -338.883769)
			(xy 59.324731 -338.833336) (xy 59.280262 -338.777574) (xy 59.242316 -338.717183) (xy 59.211371 -338.652924)
			(xy 59.187814 -338.585604) (xy 59.171944 -338.516069) (xy 59.163958 -338.445195) (xy 58.192932 -338.445195)
			(xy 58.184946 -338.516069) (xy 58.169076 -338.585604) (xy 58.145519 -338.652924) (xy 58.114574 -338.717183)
			(xy 58.076628 -338.777574) (xy 58.032159 -338.833336) (xy 57.981726 -338.883769) (xy 57.925964 -338.928238)
			(xy 57.865573 -338.966184) (xy 57.801314 -338.997129) (xy 57.733994 -339.020686) (xy 57.664459 -339.036556)
			(xy 57.593585 -339.044542) (xy 57.522263 -339.044542) (xy 57.451389 -339.036556) (xy 57.381854 -339.020686)
			(xy 57.314534 -338.997129) (xy 57.250275 -338.966184) (xy 57.189884 -338.928238) (xy 57.134122 -338.883769)
			(xy 57.083689 -338.833336) (xy 57.03922 -338.777574) (xy 57.001274 -338.717183) (xy 56.970329 -338.652924)
			(xy 56.946772 -338.585604) (xy 56.930902 -338.516069) (xy 56.922916 -338.445195) (xy 56.30622 -338.445195)
			(xy 56.298234 -338.516069) (xy 56.282364 -338.585604) (xy 56.258807 -338.652924) (xy 56.227862 -338.717183)
			(xy 56.189916 -338.777574) (xy 56.145447 -338.833336) (xy 56.095014 -338.883769) (xy 56.039252 -338.928238)
			(xy 55.978861 -338.966184) (xy 55.914602 -338.997129) (xy 55.847282 -339.020686) (xy 55.777747 -339.036556)
			(xy 55.706873 -339.044542) (xy 55.635551 -339.044542) (xy 55.564677 -339.036556) (xy 55.495142 -339.020686)
			(xy 55.427822 -338.997129) (xy 55.363563 -338.966184) (xy 55.303172 -338.928238) (xy 55.24741 -338.883769)
			(xy 55.196977 -338.833336) (xy 55.152508 -338.777574) (xy 55.114562 -338.717183) (xy 55.083617 -338.652924)
			(xy 55.06006 -338.585604) (xy 55.04419 -338.516069) (xy 55.036204 -338.445195) (xy 36.476536 -338.445195)
			(xy 36.471468 -338.499889) (xy 36.4555 -338.585309) (xy 36.431719 -338.668891) (xy 36.400327 -338.749923)
			(xy 36.361593 -338.827712) (xy 36.315846 -338.901596) (xy 36.263477 -338.970943) (xy 36.204933 -339.035163)
			(xy 36.140713 -339.093707) (xy 36.071366 -339.146076) (xy 35.997482 -339.191823) (xy 35.919693 -339.230557)
			(xy 35.838661 -339.261949) (xy 35.755079 -339.28573) (xy 35.669659 -339.301698) (xy 35.58313 -339.309716)
			(xy 35.49623 -339.309716) (xy 35.409701 -339.301698) (xy 35.324281 -339.28573) (xy 35.240699 -339.261949)
			(xy 35.159667 -339.230557) (xy 35.081878 -339.191823) (xy 35.007994 -339.146076) (xy 34.938647 -339.093707)
			(xy 34.874427 -339.035163) (xy 34.815883 -338.970943) (xy 34.763514 -338.901596) (xy 34.717767 -338.827712)
			(xy 34.679033 -338.749923) (xy 34.647641 -338.668891) (xy 34.62386 -338.585309) (xy 34.607892 -338.499889)
			(xy 34.599874 -338.41336) (xy 31.398566 -338.41336) (xy 31.396587 -338.456345) (xy 31.384681 -338.542067)
			(xy 31.364948 -338.626332) (xy 31.337556 -338.708427) (xy 31.302736 -338.787658) (xy 31.260783 -338.863354)
			(xy 31.212052 -338.934875) (xy 31.156956 -339.001616) (xy 31.09596 -339.063012) (xy 31.029581 -339.118543)
			(xy 30.95838 -339.16774) (xy 30.88296 -339.210187) (xy 30.803958 -339.245524) (xy 30.722044 -339.273452)
			(xy 30.63791 -339.293736) (xy 30.552268 -339.306202) (xy 30.465843 -339.310747) (xy 30.379366 -339.307331)
			(xy 30.293568 -339.295984) (xy 30.209177 -339.276801) (xy 30.126905 -339.249944) (xy 30.047448 -339.215642)
			(xy 29.97148 -339.174184) (xy 29.899643 -339.12592) (xy 29.832544 -339.071261) (xy 29.770752 -339.010666)
			(xy 29.742384 -338.977986) (xy 29.727699 -338.961435) (xy 29.693651 -338.933183) (xy 29.655223 -338.911256)
			(xy 29.613579 -338.896317) (xy 29.569976 -338.888816) (xy 29.525734 -338.888981) (xy 29.482188 -338.896806)
			(xy 29.440656 -338.912056) (xy 29.402394 -338.934269) (xy 29.368557 -338.962774) (xy 29.340168 -338.996708)
			(xy 29.318087 -339.035047) (xy 29.30298 -339.076631) (xy 29.295303 -339.120203) (xy 29.294836 -339.142324)
			(xy 29.294836 -339.910521) (xy 38.925238 -339.910521) (xy 38.925238 -339.839199) (xy 38.933224 -339.768325)
			(xy 38.949094 -339.69879) (xy 38.972651 -339.63147) (xy 39.003596 -339.567211) (xy 39.041542 -339.50682)
			(xy 39.086011 -339.451058) (xy 39.136444 -339.400625) (xy 39.192206 -339.356156) (xy 39.252597 -339.31821)
			(xy 39.316856 -339.287265) (xy 39.384176 -339.263708) (xy 39.453711 -339.247838) (xy 39.524585 -339.239852)
			(xy 39.560246 -339.239352) (xy 39.595907 -339.239852) (xy 39.666781 -339.247838) (xy 39.736316 -339.263708)
			(xy 39.803636 -339.287265) (xy 39.867895 -339.31821) (xy 39.928286 -339.356156) (xy 39.984048 -339.400625)
			(xy 40.034481 -339.451058) (xy 40.07895 -339.50682) (xy 40.116896 -339.567211) (xy 40.147841 -339.63147)
			(xy 40.171398 -339.69879) (xy 40.187268 -339.768325) (xy 40.195254 -339.839199) (xy 40.195254 -339.910521)
			(xy 40.187268 -339.981395) (xy 40.171398 -340.05093) (xy 40.147841 -340.11825) (xy 40.116896 -340.182509)
			(xy 40.07895 -340.2429) (xy 40.034481 -340.298662) (xy 39.984048 -340.349095) (xy 39.976617 -340.355021)
			(xy 55.036204 -340.355021) (xy 55.036204 -340.283699) (xy 55.04419 -340.212825) (xy 55.06006 -340.14329)
			(xy 55.083617 -340.07597) (xy 55.114562 -340.011711) (xy 55.152508 -339.95132) (xy 55.196977 -339.895558)
			(xy 55.24741 -339.845125) (xy 55.303172 -339.800656) (xy 55.363563 -339.76271) (xy 55.427822 -339.731765)
			(xy 55.495142 -339.708208) (xy 55.564677 -339.692338) (xy 55.635551 -339.684352) (xy 55.671212 -339.683852)
			(xy 55.706873 -339.684352) (xy 55.777747 -339.692338) (xy 55.847282 -339.708208) (xy 55.914602 -339.731765)
			(xy 55.978861 -339.76271) (xy 56.039252 -339.800656) (xy 56.095014 -339.845125) (xy 56.145447 -339.895558)
			(xy 56.189916 -339.95132) (xy 56.227862 -340.011711) (xy 56.258807 -340.07597) (xy 56.282364 -340.14329)
			(xy 56.298234 -340.212825) (xy 56.30622 -340.283699) (xy 56.30622 -340.355021) (xy 56.922916 -340.355021)
			(xy 56.922916 -340.283699) (xy 56.930902 -340.212825) (xy 56.946772 -340.14329) (xy 56.970329 -340.07597)
			(xy 57.001274 -340.011711) (xy 57.03922 -339.95132) (xy 57.083689 -339.895558) (xy 57.134122 -339.845125)
			(xy 57.189884 -339.800656) (xy 57.250275 -339.76271) (xy 57.314534 -339.731765) (xy 57.381854 -339.708208)
			(xy 57.451389 -339.692338) (xy 57.522263 -339.684352) (xy 57.557924 -339.683852) (xy 57.593585 -339.684352)
			(xy 57.664459 -339.692338) (xy 57.733994 -339.708208) (xy 57.801314 -339.731765) (xy 57.865573 -339.76271)
			(xy 57.925964 -339.800656) (xy 57.981726 -339.845125) (xy 58.032159 -339.895558) (xy 58.076628 -339.95132)
			(xy 58.114574 -340.011711) (xy 58.145519 -340.07597) (xy 58.169076 -340.14329) (xy 58.184946 -340.212825)
			(xy 58.192932 -340.283699) (xy 58.192932 -340.355021) (xy 59.163958 -340.355021) (xy 59.163958 -340.283699)
			(xy 59.171944 -340.212825) (xy 59.187814 -340.14329) (xy 59.211371 -340.07597) (xy 59.242316 -340.011711)
			(xy 59.280262 -339.95132) (xy 59.324731 -339.895558) (xy 59.375164 -339.845125) (xy 59.430926 -339.800656)
			(xy 59.491317 -339.76271) (xy 59.555576 -339.731765) (xy 59.622896 -339.708208) (xy 59.692431 -339.692338)
			(xy 59.763305 -339.684352) (xy 59.798966 -339.683852) (xy 59.834627 -339.684352) (xy 59.905501 -339.692338)
			(xy 59.975036 -339.708208) (xy 60.042356 -339.731765) (xy 60.106615 -339.76271) (xy 60.167006 -339.800656)
			(xy 60.222768 -339.845125) (xy 60.273201 -339.895558) (xy 60.31767 -339.95132) (xy 60.355616 -340.011711)
			(xy 60.386561 -340.07597) (xy 60.410118 -340.14329) (xy 60.425988 -340.212825) (xy 60.433974 -340.283699)
			(xy 60.433974 -340.355021) (xy 61.067942 -340.355021) (xy 61.067942 -340.283699) (xy 61.075928 -340.212825)
			(xy 61.091798 -340.14329) (xy 61.115355 -340.07597) (xy 61.1463 -340.011711) (xy 61.184246 -339.95132)
			(xy 61.228715 -339.895558) (xy 61.279148 -339.845125) (xy 61.33491 -339.800656) (xy 61.395301 -339.76271)
			(xy 61.45956 -339.731765) (xy 61.52688 -339.708208) (xy 61.596415 -339.692338) (xy 61.667289 -339.684352)
			(xy 61.70295 -339.683852) (xy 61.738611 -339.684352) (xy 61.809485 -339.692338) (xy 61.87902 -339.708208)
			(xy 61.94634 -339.731765) (xy 62.010599 -339.76271) (xy 62.07099 -339.800656) (xy 62.126752 -339.845125)
			(xy 62.177185 -339.895558) (xy 62.221654 -339.95132) (xy 62.2596 -340.011711) (xy 62.290545 -340.07597)
			(xy 62.314102 -340.14329) (xy 62.329972 -340.212825) (xy 62.337958 -340.283699) (xy 62.337958 -340.355021)
			(xy 62.329972 -340.425895) (xy 62.314102 -340.49543) (xy 62.290545 -340.56275) (xy 62.2596 -340.627009)
			(xy 62.221654 -340.6874) (xy 62.177185 -340.743162) (xy 62.126752 -340.793595) (xy 62.07099 -340.838064)
			(xy 62.010599 -340.87601) (xy 61.94634 -340.906955) (xy 61.87902 -340.930512) (xy 61.809485 -340.946382)
			(xy 61.738611 -340.954368) (xy 61.667289 -340.954368) (xy 61.596415 -340.946382) (xy 61.52688 -340.930512)
			(xy 61.45956 -340.906955) (xy 61.395301 -340.87601) (xy 61.33491 -340.838064) (xy 61.279148 -340.793595)
			(xy 61.228715 -340.743162) (xy 61.184246 -340.6874) (xy 61.1463 -340.627009) (xy 61.115355 -340.56275)
			(xy 61.091798 -340.49543) (xy 61.075928 -340.425895) (xy 61.067942 -340.355021) (xy 60.433974 -340.355021)
			(xy 60.425988 -340.425895) (xy 60.410118 -340.49543) (xy 60.386561 -340.56275) (xy 60.355616 -340.627009)
			(xy 60.31767 -340.6874) (xy 60.273201 -340.743162) (xy 60.222768 -340.793595) (xy 60.167006 -340.838064)
			(xy 60.106615 -340.87601) (xy 60.042356 -340.906955) (xy 59.975036 -340.930512) (xy 59.905501 -340.946382)
			(xy 59.834627 -340.954368) (xy 59.763305 -340.954368) (xy 59.692431 -340.946382) (xy 59.622896 -340.930512)
			(xy 59.555576 -340.906955) (xy 59.491317 -340.87601) (xy 59.430926 -340.838064) (xy 59.375164 -340.793595)
			(xy 59.324731 -340.743162) (xy 59.280262 -340.6874) (xy 59.242316 -340.627009) (xy 59.211371 -340.56275)
			(xy 59.187814 -340.49543) (xy 59.171944 -340.425895) (xy 59.163958 -340.355021) (xy 58.192932 -340.355021)
			(xy 58.184946 -340.425895) (xy 58.169076 -340.49543) (xy 58.145519 -340.56275) (xy 58.114574 -340.627009)
			(xy 58.076628 -340.6874) (xy 58.032159 -340.743162) (xy 57.981726 -340.793595) (xy 57.925964 -340.838064)
			(xy 57.865573 -340.87601) (xy 57.801314 -340.906955) (xy 57.733994 -340.930512) (xy 57.664459 -340.946382)
			(xy 57.593585 -340.954368) (xy 57.522263 -340.954368) (xy 57.451389 -340.946382) (xy 57.381854 -340.930512)
			(xy 57.314534 -340.906955) (xy 57.250275 -340.87601) (xy 57.189884 -340.838064) (xy 57.134122 -340.793595)
			(xy 57.083689 -340.743162) (xy 57.03922 -340.6874) (xy 57.001274 -340.627009) (xy 56.970329 -340.56275)
			(xy 56.946772 -340.49543) (xy 56.930902 -340.425895) (xy 56.922916 -340.355021) (xy 56.30622 -340.355021)
			(xy 56.298234 -340.425895) (xy 56.282364 -340.49543) (xy 56.258807 -340.56275) (xy 56.227862 -340.627009)
			(xy 56.189916 -340.6874) (xy 56.145447 -340.743162) (xy 56.095014 -340.793595) (xy 56.039252 -340.838064)
			(xy 55.978861 -340.87601) (xy 55.914602 -340.906955) (xy 55.847282 -340.930512) (xy 55.777747 -340.946382)
			(xy 55.706873 -340.954368) (xy 55.635551 -340.954368) (xy 55.564677 -340.946382) (xy 55.495142 -340.930512)
			(xy 55.427822 -340.906955) (xy 55.363563 -340.87601) (xy 55.303172 -340.838064) (xy 55.24741 -340.793595)
			(xy 55.196977 -340.743162) (xy 55.152508 -340.6874) (xy 55.114562 -340.627009) (xy 55.083617 -340.56275)
			(xy 55.06006 -340.49543) (xy 55.04419 -340.425895) (xy 55.036204 -340.355021) (xy 39.976617 -340.355021)
			(xy 39.928286 -340.393564) (xy 39.867895 -340.43151) (xy 39.803636 -340.462455) (xy 39.736316 -340.486012)
			(xy 39.666781 -340.501882) (xy 39.595907 -340.509868) (xy 39.524585 -340.509868) (xy 39.453711 -340.501882)
			(xy 39.384176 -340.486012) (xy 39.316856 -340.462455) (xy 39.252597 -340.43151) (xy 39.192206 -340.393564)
			(xy 39.136444 -340.349095) (xy 39.086011 -340.298662) (xy 39.041542 -340.2429) (xy 39.003596 -340.182509)
			(xy 38.972651 -340.11825) (xy 38.949094 -340.05093) (xy 38.933224 -339.981395) (xy 38.925238 -339.910521)
			(xy 29.294836 -339.910521) (xy 29.294836 -340.137496) (xy 29.295314 -340.159621) (xy 29.30298 -340.203202)
			(xy 29.31808 -340.244796) (xy 29.340157 -340.283145) (xy 29.368545 -340.317089) (xy 29.402384 -340.345602)
			(xy 29.440651 -340.367822) (xy 29.482188 -340.383075) (xy 29.525741 -340.390902) (xy 29.569991 -340.391065)
			(xy 29.613599 -340.38356) (xy 29.655248 -340.368613) (xy 29.693678 -340.346676) (xy 29.727726 -340.318413)
			(xy 29.742384 -340.301834) (xy 29.770742 -340.269145) (xy 29.832533 -340.20855) (xy 29.899631 -340.153889)
			(xy 29.971467 -340.105624) (xy 30.047435 -340.064165) (xy 30.12689 -340.029861) (xy 30.209162 -340.003003)
			(xy 30.293553 -339.983819) (xy 30.379351 -339.97247) (xy 30.465828 -339.969053) (xy 30.552253 -339.973596)
			(xy 30.637895 -339.986062) (xy 30.722029 -340.006344) (xy 30.803944 -340.03427) (xy 30.882946 -340.069606)
			(xy 30.958367 -340.112052) (xy 31.029569 -340.161248) (xy 31.095949 -340.216778) (xy 31.156946 -340.278173)
			(xy 31.212043 -340.344913) (xy 31.260775 -340.416433) (xy 31.302729 -340.492129) (xy 31.33755 -340.571359)
			(xy 31.364944 -340.653454) (xy 31.384678 -340.737718) (xy 31.396586 -340.823439) (xy 31.400567 -340.909892)
			(xy 31.398566 -340.95336) (xy 34.599874 -340.95336) (xy 34.599874 -340.86646) (xy 34.607892 -340.779931)
			(xy 34.62386 -340.694511) (xy 34.647641 -340.610929) (xy 34.679033 -340.529897) (xy 34.717767 -340.452108)
			(xy 34.763514 -340.378224) (xy 34.815883 -340.308877) (xy 34.874427 -340.244657) (xy 34.938647 -340.186113)
			(xy 35.007994 -340.133744) (xy 35.081878 -340.087997) (xy 35.159667 -340.049263) (xy 35.240699 -340.017871)
			(xy 35.324281 -339.99409) (xy 35.409701 -339.978122) (xy 35.49623 -339.970104) (xy 35.53968 -339.969602)
			(xy 35.58313 -339.970104) (xy 35.669659 -339.978122) (xy 35.755079 -339.99409) (xy 35.838661 -340.017871)
			(xy 35.919693 -340.049263) (xy 35.997482 -340.087997) (xy 36.071366 -340.133744) (xy 36.140713 -340.186113)
			(xy 36.204933 -340.244657) (xy 36.263477 -340.308877) (xy 36.315846 -340.378224) (xy 36.361593 -340.452108)
			(xy 36.400327 -340.529897) (xy 36.431719 -340.610929) (xy 36.4555 -340.694511) (xy 36.471468 -340.779931)
			(xy 36.479486 -340.86646) (xy 36.479486 -340.95336) (xy 36.471468 -341.039889) (xy 36.4555 -341.125309)
			(xy 36.431719 -341.208891) (xy 36.400327 -341.289923) (xy 36.361593 -341.367712) (xy 36.315846 -341.441596)
			(xy 36.263477 -341.510943) (xy 36.204933 -341.575163) (xy 36.140713 -341.633707) (xy 36.071366 -341.686076)
			(xy 35.997482 -341.731823) (xy 35.919693 -341.770557) (xy 35.838661 -341.801949) (xy 35.755079 -341.82573)
			(xy 35.669659 -341.841698) (xy 35.58313 -341.849716) (xy 35.49623 -341.849716) (xy 35.409701 -341.841698)
			(xy 35.324281 -341.82573) (xy 35.240699 -341.801949) (xy 35.159667 -341.770557) (xy 35.081878 -341.731823)
			(xy 35.007994 -341.686076) (xy 34.938647 -341.633707) (xy 34.874427 -341.575163) (xy 34.815883 -341.510943)
			(xy 34.763514 -341.441596) (xy 34.717767 -341.367712) (xy 34.679033 -341.289923) (xy 34.647641 -341.208891)
			(xy 34.62386 -341.125309) (xy 34.607892 -341.039889) (xy 34.599874 -340.95336) (xy 31.398566 -340.95336)
			(xy 31.396587 -340.996345) (xy 31.384681 -341.082067) (xy 31.364948 -341.166332) (xy 31.337556 -341.248427)
			(xy 31.302736 -341.327658) (xy 31.260783 -341.403354) (xy 31.212052 -341.474875) (xy 31.156956 -341.541616)
			(xy 31.09596 -341.603012) (xy 31.029581 -341.658543) (xy 30.95838 -341.70774) (xy 30.88296 -341.750187)
			(xy 30.803958 -341.785524) (xy 30.722044 -341.813452) (xy 30.63791 -341.833736) (xy 30.552268 -341.846202)
			(xy 30.465843 -341.850747) (xy 30.379366 -341.847331) (xy 30.293568 -341.835984) (xy 30.209177 -341.816801)
			(xy 30.126905 -341.789944) (xy 30.047448 -341.755642) (xy 29.97148 -341.714184) (xy 29.899643 -341.66592)
			(xy 29.832544 -341.611261) (xy 29.770752 -341.550666) (xy 29.742384 -341.517986) (xy 29.727699 -341.501435)
			(xy 29.693651 -341.473183) (xy 29.655223 -341.451256) (xy 29.613579 -341.436317) (xy 29.569976 -341.428816)
			(xy 29.525734 -341.428981) (xy 29.482188 -341.436806) (xy 29.440656 -341.452056) (xy 29.402394 -341.474269)
			(xy 29.368557 -341.502774) (xy 29.340168 -341.536708) (xy 29.318087 -341.575047) (xy 29.30298 -341.616631)
			(xy 29.295303 -341.660203) (xy 29.294836 -341.682324) (xy 29.294836 -341.873433) (xy 38.925238 -341.873433)
			(xy 38.925238 -341.802111) (xy 38.933224 -341.731237) (xy 38.949094 -341.661702) (xy 38.972651 -341.594382)
			(xy 39.003596 -341.530123) (xy 39.041542 -341.469732) (xy 39.086011 -341.41397) (xy 39.136444 -341.363537)
			(xy 39.192206 -341.319068) (xy 39.252597 -341.281122) (xy 39.316856 -341.250177) (xy 39.384176 -341.22662)
			(xy 39.453711 -341.21075) (xy 39.524585 -341.202764) (xy 39.560246 -341.202264) (xy 39.595907 -341.202764)
			(xy 39.666781 -341.21075) (xy 39.736316 -341.22662) (xy 39.803636 -341.250177) (xy 39.867895 -341.281122)
			(xy 39.898024 -341.300053) (xy 72.999096 -341.300053) (xy 73.001098 -341.099925) (xy 73.011106 -340.900037)
			(xy 73.029103 -340.70071) (xy 73.055061 -340.502262) (xy 73.088938 -340.305012) (xy 73.13068 -340.109275)
			(xy 73.180219 -339.915365) (xy 73.237477 -339.723592) (xy 73.302362 -339.534263) (xy 73.37477 -339.347683)
			(xy 73.454586 -339.164148) (xy 73.54168 -338.983954) (xy 73.635914 -338.807389) (xy 73.737137 -338.634736)
			(xy 73.845187 -338.466271) (xy 73.95989 -338.302263) (xy 74.081064 -338.142976) (xy 74.208513 -337.988665)
			(xy 74.342034 -337.839577) (xy 74.481414 -337.69595) (xy 74.626428 -337.558014) (xy 74.776845 -337.425991)
			(xy 74.932423 -337.300092) (xy 75.092915 -337.180518) (xy 75.258061 -337.067462) (xy 75.427599 -336.961103)
			(xy 75.601257 -336.861612) (xy 75.778756 -336.769149) (xy 75.959812 -336.683862) (xy 76.144136 -336.605887)
			(xy 76.331432 -336.53535) (xy 76.5214 -336.472362) (xy 76.713736 -336.417025) (xy 76.908132 -336.369428)
			(xy 77.104277 -336.329647) (xy 77.301856 -336.297745) (xy 77.500553 -336.273774) (xy 77.700051 -336.257772)
			(xy 77.900029 -336.249765) (xy 78.000098 -336.249264) (xy 78.100167 -336.249765) (xy 78.300145 -336.257772)
			(xy 78.499643 -336.273774) (xy 78.69834 -336.297745) (xy 78.895919 -336.329647) (xy 79.092064 -336.369428)
			(xy 79.28646 -336.417025) (xy 79.478796 -336.472362) (xy 79.668764 -336.53535) (xy 79.85606 -336.605887)
			(xy 80.040384 -336.683862) (xy 80.22144 -336.769149) (xy 80.398939 -336.861612) (xy 80.572597 -336.961103)
			(xy 80.742135 -337.067462) (xy 80.907281 -337.180518) (xy 81.067773 -337.300092) (xy 81.223351 -337.425991)
			(xy 81.373768 -337.558014) (xy 81.518782 -337.69595) (xy 81.658162 -337.839577) (xy 81.791683 -337.988665)
			(xy 81.919132 -338.142976) (xy 82.040306 -338.302263) (xy 82.155009 -338.466271) (xy 82.263059 -338.634736)
			(xy 82.364282 -338.807389) (xy 82.458516 -338.983954) (xy 82.54561 -339.164148) (xy 82.625426 -339.347683)
			(xy 82.697834 -339.534263) (xy 82.762719 -339.723592) (xy 82.819977 -339.915365) (xy 82.869516 -340.109275)
			(xy 82.911258 -340.305012) (xy 82.945135 -340.502262) (xy 82.971093 -340.70071) (xy 82.98909 -340.900037)
			(xy 82.999098 -341.099925) (xy 83.0011 -341.300053) (xy 82.995094 -341.500101) (xy 82.981089 -341.699749)
			(xy 82.959107 -341.898676) (xy 82.929183 -342.096565) (xy 82.891366 -342.293098) (xy 82.845717 -342.48796)
			(xy 82.792307 -342.68084) (xy 82.731223 -342.871429) (xy 82.662563 -343.059421) (xy 82.586436 -343.244516)
			(xy 82.502965 -343.426416) (xy 82.412282 -343.604832) (xy 82.314534 -343.779476) (xy 82.209877 -343.950069)
			(xy 82.098478 -344.116339) (xy 81.980516 -344.278018) (xy 81.85618 -344.434849) (xy 81.725668 -344.586579)
			(xy 81.589191 -344.732966) (xy 81.446965 -344.873775) (xy 81.29922 -345.008782) (xy 81.146192 -345.137769)
			(xy 80.988125 -345.26053) (xy 80.825274 -345.376868) (xy 80.657898 -345.486598) (xy 80.486266 -345.589543)
			(xy 80.310652 -345.685539) (xy 80.131339 -345.774432) (xy 79.948612 -345.856079) (xy 79.762765 -345.930351)
			(xy 79.574095 -345.997127) (xy 79.382905 -346.056301) (xy 79.1895 -346.107778) (xy 78.994191 -346.151476)
			(xy 78.797289 -346.187324) (xy 78.599111 -346.215266) (xy 78.399974 -346.235257) (xy 78.200196 -346.247264)
			(xy 78.000098 -346.251269) (xy 77.8 -346.247264) (xy 77.600222 -346.235257) (xy 77.401085 -346.215266)
			(xy 77.202907 -346.187324) (xy 77.006005 -346.151476) (xy 76.810696 -346.107778) (xy 76.617291 -346.056301)
			(xy 76.426101 -345.997127) (xy 76.237431 -345.930351) (xy 76.051584 -345.856079) (xy 75.868857 -345.774432)
			(xy 75.689544 -345.685539) (xy 75.51393 -345.589543) (xy 75.342298 -345.486598) (xy 75.174922 -345.376868)
			(xy 75.012071 -345.26053) (xy 74.854004 -345.137769) (xy 74.700976 -345.008782) (xy 74.553231 -344.873775)
			(xy 74.411005 -344.732966) (xy 74.274528 -344.586579) (xy 74.144016 -344.434849) (xy 74.01968 -344.278018)
			(xy 73.901718 -344.116339) (xy 73.790319 -343.950069) (xy 73.685662 -343.779476) (xy 73.587914 -343.604832)
			(xy 73.497231 -343.426416) (xy 73.41376 -343.244516) (xy 73.337633 -343.059421) (xy 73.268973 -342.871429)
			(xy 73.207889 -342.68084) (xy 73.154479 -342.48796) (xy 73.10883 -342.293098) (xy 73.071013 -342.096565)
			(xy 73.041089 -341.898676) (xy 73.019107 -341.699749) (xy 73.005102 -341.500101) (xy 72.999096 -341.300053)
			(xy 39.898024 -341.300053) (xy 39.928286 -341.319068) (xy 39.984048 -341.363537) (xy 40.034481 -341.41397)
			(xy 40.07895 -341.469732) (xy 40.116896 -341.530123) (xy 40.147841 -341.594382) (xy 40.171398 -341.661702)
			(xy 40.187268 -341.731237) (xy 40.195254 -341.802111) (xy 40.195254 -341.873433) (xy 40.187268 -341.944307)
			(xy 40.171398 -342.013842) (xy 40.147841 -342.081162) (xy 40.116896 -342.145421) (xy 40.07895 -342.205812)
			(xy 40.034481 -342.261574) (xy 39.984048 -342.312007) (xy 39.928286 -342.356476) (xy 39.867895 -342.394422)
			(xy 39.803636 -342.425367) (xy 39.736316 -342.448924) (xy 39.666781 -342.464794) (xy 39.595907 -342.47278)
			(xy 39.524585 -342.47278) (xy 39.453711 -342.464794) (xy 39.384176 -342.448924) (xy 39.316856 -342.425367)
			(xy 39.252597 -342.394422) (xy 39.192206 -342.356476) (xy 39.136444 -342.312007) (xy 39.086011 -342.261574)
			(xy 39.041542 -342.205812) (xy 39.003596 -342.145421) (xy 38.972651 -342.081162) (xy 38.949094 -342.013842)
			(xy 38.933224 -341.944307) (xy 38.925238 -341.873433) (xy 29.294836 -341.873433) (xy 29.294836 -342.677496)
			(xy 29.295314 -342.699621) (xy 29.30298 -342.743202) (xy 29.31808 -342.784796) (xy 29.340157 -342.823145)
			(xy 29.368545 -342.857089) (xy 29.402384 -342.885602) (xy 29.440651 -342.907822) (xy 29.482188 -342.923075)
			(xy 29.525741 -342.930902) (xy 29.569991 -342.931065) (xy 29.613599 -342.92356) (xy 29.655248 -342.908613)
			(xy 29.693678 -342.886676) (xy 29.727726 -342.858413) (xy 29.742384 -342.841834) (xy 29.770742 -342.809145)
			(xy 29.832533 -342.74855) (xy 29.899631 -342.693889) (xy 29.971467 -342.645624) (xy 30.047435 -342.604165)
			(xy 30.12689 -342.569861) (xy 30.209162 -342.543003) (xy 30.293553 -342.523819) (xy 30.379351 -342.51247)
			(xy 30.465828 -342.509053) (xy 30.552253 -342.513596) (xy 30.637895 -342.526062) (xy 30.722029 -342.546344)
			(xy 30.803944 -342.57427) (xy 30.882946 -342.609606) (xy 30.958367 -342.652052) (xy 31.029569 -342.701248)
			(xy 31.095949 -342.756778) (xy 31.156946 -342.818173) (xy 31.212043 -342.884913) (xy 31.260775 -342.956433)
			(xy 31.302729 -343.032129) (xy 31.33755 -343.111359) (xy 31.364944 -343.193454) (xy 31.384678 -343.277718)
			(xy 31.396586 -343.363439) (xy 31.400567 -343.449892) (xy 31.398566 -343.49336) (xy 34.599874 -343.49336)
			(xy 34.599874 -343.40646) (xy 34.607892 -343.319931) (xy 34.62386 -343.234511) (xy 34.647641 -343.150929)
			(xy 34.679033 -343.069897) (xy 34.717767 -342.992108) (xy 34.763514 -342.918224) (xy 34.815883 -342.848877)
			(xy 34.874427 -342.784657) (xy 34.938647 -342.726113) (xy 35.007994 -342.673744) (xy 35.081878 -342.627997)
			(xy 35.159667 -342.589263) (xy 35.240699 -342.557871) (xy 35.324281 -342.53409) (xy 35.409701 -342.518122)
			(xy 35.49623 -342.510104) (xy 35.53968 -342.509602) (xy 35.58313 -342.510104) (xy 35.669659 -342.518122)
			(xy 35.755079 -342.53409) (xy 35.838661 -342.557871) (xy 35.919693 -342.589263) (xy 35.997482 -342.627997)
			(xy 36.071366 -342.673744) (xy 36.140713 -342.726113) (xy 36.204933 -342.784657) (xy 36.263477 -342.848877)
			(xy 36.315846 -342.918224) (xy 36.361593 -342.992108) (xy 36.400327 -343.069897) (xy 36.431719 -343.150929)
			(xy 36.4555 -343.234511) (xy 36.471468 -343.319931) (xy 36.479486 -343.40646) (xy 36.479486 -343.49336)
			(xy 36.471468 -343.579889) (xy 36.4555 -343.665309) (xy 36.431719 -343.748891) (xy 36.400327 -343.829923)
			(xy 36.361593 -343.907712) (xy 36.315846 -343.981596) (xy 36.289156 -344.016939) (xy 38.925238 -344.016939)
			(xy 38.925238 -343.945617) (xy 38.933224 -343.874743) (xy 38.949094 -343.805208) (xy 38.972651 -343.737888)
			(xy 39.003596 -343.673629) (xy 39.041542 -343.613238) (xy 39.086011 -343.557476) (xy 39.136444 -343.507043)
			(xy 39.192206 -343.462574) (xy 39.252597 -343.424628) (xy 39.316856 -343.393683) (xy 39.384176 -343.370126)
			(xy 39.453711 -343.354256) (xy 39.524585 -343.34627) (xy 39.560246 -343.34577) (xy 39.595907 -343.34627)
			(xy 39.666781 -343.354256) (xy 39.736316 -343.370126) (xy 39.803636 -343.393683) (xy 39.867895 -343.424628)
			(xy 39.928286 -343.462574) (xy 39.984048 -343.507043) (xy 40.034481 -343.557476) (xy 40.07895 -343.613238)
			(xy 40.116896 -343.673629) (xy 40.147841 -343.737888) (xy 40.171398 -343.805208) (xy 40.187268 -343.874743)
			(xy 40.195254 -343.945617) (xy 40.195254 -344.016939) (xy 40.187268 -344.087813) (xy 40.171398 -344.157348)
			(xy 40.147841 -344.224668) (xy 40.116896 -344.288927) (xy 40.07895 -344.349318) (xy 40.034481 -344.40508)
			(xy 39.984048 -344.455513) (xy 39.928286 -344.499982) (xy 39.867895 -344.537928) (xy 39.803636 -344.568873)
			(xy 39.736316 -344.59243) (xy 39.666781 -344.6083) (xy 39.595907 -344.616286) (xy 39.524585 -344.616286)
			(xy 39.453711 -344.6083) (xy 39.384176 -344.59243) (xy 39.316856 -344.568873) (xy 39.252597 -344.537928)
			(xy 39.192206 -344.499982) (xy 39.136444 -344.455513) (xy 39.086011 -344.40508) (xy 39.041542 -344.349318)
			(xy 39.003596 -344.288927) (xy 38.972651 -344.224668) (xy 38.949094 -344.157348) (xy 38.933224 -344.087813)
			(xy 38.925238 -344.016939) (xy 36.289156 -344.016939) (xy 36.263477 -344.050943) (xy 36.204933 -344.115163)
			(xy 36.140713 -344.173707) (xy 36.071366 -344.226076) (xy 35.997482 -344.271823) (xy 35.919693 -344.310557)
			(xy 35.838661 -344.341949) (xy 35.755079 -344.36573) (xy 35.669659 -344.381698) (xy 35.58313 -344.389716)
			(xy 35.49623 -344.389716) (xy 35.409701 -344.381698) (xy 35.324281 -344.36573) (xy 35.240699 -344.341949)
			(xy 35.159667 -344.310557) (xy 35.081878 -344.271823) (xy 35.007994 -344.226076) (xy 34.938647 -344.173707)
			(xy 34.874427 -344.115163) (xy 34.815883 -344.050943) (xy 34.763514 -343.981596) (xy 34.717767 -343.907712)
			(xy 34.679033 -343.829923) (xy 34.647641 -343.748891) (xy 34.62386 -343.665309) (xy 34.607892 -343.579889)
			(xy 34.599874 -343.49336) (xy 31.398566 -343.49336) (xy 31.396587 -343.536345) (xy 31.384681 -343.622067)
			(xy 31.364948 -343.706332) (xy 31.337556 -343.788427) (xy 31.302736 -343.867658) (xy 31.260783 -343.943354)
			(xy 31.212052 -344.014875) (xy 31.156956 -344.081616) (xy 31.09596 -344.143012) (xy 31.029581 -344.198543)
			(xy 30.95838 -344.24774) (xy 30.88296 -344.290187) (xy 30.803958 -344.325524) (xy 30.722044 -344.353452)
			(xy 30.63791 -344.373736) (xy 30.552268 -344.386202) (xy 30.465843 -344.390747) (xy 30.379366 -344.387331)
			(xy 30.293568 -344.375984) (xy 30.209177 -344.356801) (xy 30.126905 -344.329944) (xy 30.047448 -344.295642)
			(xy 29.97148 -344.254184) (xy 29.899643 -344.20592) (xy 29.832544 -344.151261) (xy 29.770752 -344.090666)
			(xy 29.742384 -344.057986) (xy 29.727699 -344.041435) (xy 29.693651 -344.013183) (xy 29.655223 -343.991256)
			(xy 29.613579 -343.976317) (xy 29.569976 -343.968816) (xy 29.525734 -343.968981) (xy 29.482188 -343.976806)
			(xy 29.440656 -343.992056) (xy 29.402394 -344.014269) (xy 29.368557 -344.042774) (xy 29.340168 -344.076708)
			(xy 29.318087 -344.115047) (xy 29.30298 -344.156631) (xy 29.295303 -344.200203) (xy 29.294836 -344.222324)
			(xy 29.294836 -345.217496) (xy 29.295314 -345.239621) (xy 29.30298 -345.283202) (xy 29.31808 -345.324796)
			(xy 29.340157 -345.363145) (xy 29.368545 -345.397089) (xy 29.402384 -345.425602) (xy 29.440651 -345.447822)
			(xy 29.482188 -345.463075) (xy 29.525741 -345.470902) (xy 29.569991 -345.471065) (xy 29.613599 -345.46356)
			(xy 29.655248 -345.448613) (xy 29.693678 -345.426676) (xy 29.727726 -345.398413) (xy 29.742384 -345.381834)
			(xy 29.770742 -345.349145) (xy 29.832533 -345.28855) (xy 29.899631 -345.233889) (xy 29.971467 -345.185624)
			(xy 30.047435 -345.144165) (xy 30.12689 -345.109861) (xy 30.209162 -345.083003) (xy 30.293553 -345.063819)
			(xy 30.379351 -345.05247) (xy 30.465828 -345.049053) (xy 30.552253 -345.053596) (xy 30.637895 -345.066062)
			(xy 30.722029 -345.086344) (xy 30.803944 -345.11427) (xy 30.882946 -345.149606) (xy 30.958367 -345.192052)
			(xy 31.029569 -345.241248) (xy 31.095949 -345.296778) (xy 31.156946 -345.358173) (xy 31.212043 -345.424913)
			(xy 31.260775 -345.496433) (xy 31.302729 -345.572129) (xy 31.33755 -345.651359) (xy 31.364944 -345.733454)
			(xy 31.384678 -345.817718) (xy 31.396586 -345.903439) (xy 31.400567 -345.989892) (xy 31.398566 -346.03336)
			(xy 34.599874 -346.03336) (xy 34.599874 -345.94646) (xy 34.607892 -345.859931) (xy 34.62386 -345.774511)
			(xy 34.647641 -345.690929) (xy 34.679033 -345.609897) (xy 34.717767 -345.532108) (xy 34.763514 -345.458224)
			(xy 34.815883 -345.388877) (xy 34.874427 -345.324657) (xy 34.938647 -345.266113) (xy 35.007994 -345.213744)
			(xy 35.081878 -345.167997) (xy 35.159667 -345.129263) (xy 35.240699 -345.097871) (xy 35.324281 -345.07409)
			(xy 35.409701 -345.058122) (xy 35.49623 -345.050104) (xy 35.53968 -345.049602) (xy 35.58313 -345.050104)
			(xy 35.669659 -345.058122) (xy 35.755079 -345.07409) (xy 35.838661 -345.097871) (xy 35.919693 -345.129263)
			(xy 35.997482 -345.167997) (xy 36.071366 -345.213744) (xy 36.140713 -345.266113) (xy 36.204933 -345.324657)
			(xy 36.263477 -345.388877) (xy 36.315846 -345.458224) (xy 36.361593 -345.532108) (xy 36.400327 -345.609897)
			(xy 36.431719 -345.690929) (xy 36.4555 -345.774511) (xy 36.471468 -345.859931) (xy 36.479486 -345.94646)
			(xy 36.479486 -346.03336) (xy 36.471468 -346.119889) (xy 36.4555 -346.205309) (xy 36.431719 -346.288891)
			(xy 36.400327 -346.369923) (xy 36.361593 -346.447712) (xy 36.315846 -346.521596) (xy 36.263477 -346.590943)
			(xy 36.204933 -346.655163) (xy 36.140713 -346.713707) (xy 36.071366 -346.766076) (xy 35.997482 -346.811823)
			(xy 35.919693 -346.850557) (xy 35.838661 -346.881949) (xy 35.755079 -346.90573) (xy 35.669659 -346.921698)
			(xy 35.58313 -346.929716) (xy 35.49623 -346.929716) (xy 35.409701 -346.921698) (xy 35.324281 -346.90573)
			(xy 35.240699 -346.881949) (xy 35.159667 -346.850557) (xy 35.081878 -346.811823) (xy 35.007994 -346.766076)
			(xy 34.938647 -346.713707) (xy 34.874427 -346.655163) (xy 34.815883 -346.590943) (xy 34.763514 -346.521596)
			(xy 34.717767 -346.447712) (xy 34.679033 -346.369923) (xy 34.647641 -346.288891) (xy 34.62386 -346.205309)
			(xy 34.607892 -346.119889) (xy 34.599874 -346.03336) (xy 31.398566 -346.03336) (xy 31.396587 -346.076345)
			(xy 31.384681 -346.162067) (xy 31.364948 -346.246332) (xy 31.337556 -346.328427) (xy 31.302736 -346.407658)
			(xy 31.260783 -346.483354) (xy 31.212052 -346.554875) (xy 31.156956 -346.621616) (xy 31.09596 -346.683012)
			(xy 31.029581 -346.738543) (xy 30.95838 -346.78774) (xy 30.88296 -346.830187) (xy 30.803958 -346.865524)
			(xy 30.722044 -346.893452) (xy 30.63791 -346.913736) (xy 30.552268 -346.926202) (xy 30.465843 -346.930747)
			(xy 30.379366 -346.927331) (xy 30.293568 -346.915984) (xy 30.209177 -346.896801) (xy 30.126905 -346.869944)
			(xy 30.047448 -346.835642) (xy 29.97148 -346.794184) (xy 29.899643 -346.74592) (xy 29.832544 -346.691261)
			(xy 29.770752 -346.630666) (xy 29.742384 -346.597986) (xy 29.727699 -346.581435) (xy 29.693651 -346.553183)
			(xy 29.655223 -346.531256) (xy 29.613579 -346.516317) (xy 29.569976 -346.508816) (xy 29.525734 -346.508981)
			(xy 29.482188 -346.516806) (xy 29.440656 -346.532056) (xy 29.402394 -346.554269) (xy 29.368557 -346.582774)
			(xy 29.340168 -346.616708) (xy 29.318087 -346.655047) (xy 29.30298 -346.696631) (xy 29.295303 -346.740203)
			(xy 29.294836 -346.762324) (xy 29.294836 -347.462856) (xy 29.295325 -347.479513) (xy 29.30394 -347.511693)
			(xy 29.320593 -347.540546) (xy 29.344148 -347.564103) (xy 29.372999 -347.580757) (xy 29.405179 -347.589374)
			(xy 29.421836 -347.589856) (xy 31.399988 -347.589856) (xy 31.399988 -348.57336) (xy 34.599874 -348.57336)
			(xy 34.599874 -348.48646) (xy 34.607892 -348.399931) (xy 34.62386 -348.314511) (xy 34.647641 -348.230929)
			(xy 34.679033 -348.149897) (xy 34.717767 -348.072108) (xy 34.763514 -347.998224) (xy 34.815883 -347.928877)
			(xy 34.874427 -347.864657) (xy 34.938647 -347.806113) (xy 35.007994 -347.753744) (xy 35.081878 -347.707997)
			(xy 35.159667 -347.669263) (xy 35.240699 -347.637871) (xy 35.324281 -347.61409) (xy 35.409701 -347.598122)
			(xy 35.49623 -347.590104) (xy 35.53968 -347.589602) (xy 35.58313 -347.590104) (xy 35.669659 -347.598122)
			(xy 35.755079 -347.61409) (xy 35.838661 -347.637871) (xy 35.919693 -347.669263) (xy 35.997482 -347.707997)
			(xy 36.071366 -347.753744) (xy 36.140713 -347.806113) (xy 36.204933 -347.864657) (xy 36.263477 -347.928877)
			(xy 36.315846 -347.998224) (xy 36.361593 -348.072108) (xy 36.400327 -348.149897) (xy 36.431719 -348.230929)
			(xy 36.4555 -348.314511) (xy 36.471468 -348.399931) (xy 36.479486 -348.48646) (xy 36.479486 -348.57336)
			(xy 36.471468 -348.659889) (xy 36.4555 -348.745309) (xy 36.431719 -348.828891) (xy 36.400327 -348.909923)
			(xy 36.361593 -348.987712) (xy 36.315846 -349.061596) (xy 36.263477 -349.130943) (xy 36.204933 -349.195163)
			(xy 36.140713 -349.253707) (xy 36.071366 -349.306076) (xy 35.997482 -349.351823) (xy 35.919693 -349.390557)
			(xy 35.838661 -349.421949) (xy 35.755079 -349.44573) (xy 35.669659 -349.461698) (xy 35.58313 -349.469716)
			(xy 35.49623 -349.469716) (xy 35.409701 -349.461698) (xy 35.324281 -349.44573) (xy 35.240699 -349.421949)
			(xy 35.159667 -349.390557) (xy 35.081878 -349.351823) (xy 35.007994 -349.306076) (xy 34.938647 -349.253707)
			(xy 34.874427 -349.195163) (xy 34.815883 -349.130943) (xy 34.763514 -349.061596) (xy 34.717767 -348.987712)
			(xy 34.679033 -348.909923) (xy 34.647641 -348.828891) (xy 34.62386 -348.745309) (xy 34.607892 -348.659889)
			(xy 34.599874 -348.57336) (xy 31.399988 -348.57336) (xy 31.399988 -349.469964) (xy 29.421836 -349.469964)
			(xy 29.405183 -349.470503) (xy 29.373009 -349.479114) (xy 29.34416 -349.495759) (xy 29.320603 -349.519303)
			(xy 29.303942 -349.548142) (xy 29.295312 -349.580311) (xy 29.294836 -349.596964) (xy 29.294836 -349.939356)
			(xy 51.07432 -349.939356) (xy 52.726336 -349.939356) (xy 52.726336 -351.591372) (xy 51.07432 -351.591372)
			(xy 51.07432 -349.939356) (xy 29.294836 -349.939356) (xy 29.294836 -350.508062) (xy 32.333184 -353.546664)
			(xy 38.095428 -353.546664) (xy 39.647114 -355.09835) (xy 39.664243 -355.114742) (xy 39.703392 -355.141474)
			(xy 39.746823 -355.160475) (xy 39.793026 -355.171086) (xy 39.840395 -355.172938) (xy 39.887285 -355.165966)
			(xy 39.932066 -355.150412) (xy 39.973183 -355.126818) (xy 39.991538 -355.111812) (xy 40.014641 -355.092677)
			(xy 40.064936 -355.059982) (xy 40.119072 -355.034138) (xy 40.17612 -355.015587) (xy 40.235102 -355.004646)
			(xy 40.295008 -355.001505) (xy 40.354811 -355.006216) (xy 40.413487 -355.018699) (xy 40.470028 -355.03874)
			(xy 40.523468 -355.065995) (xy 40.572889 -355.099997) (xy 40.617444 -355.140164) (xy 40.656371 -355.185808)
			(xy 40.689002 -355.236145) (xy 40.714778 -355.290313) (xy 40.733257 -355.347385) (xy 40.744122 -355.406381)
			(xy 40.747187 -355.466291) (xy 40.7424 -355.526088) (xy 40.729842 -355.584747) (xy 40.70973 -355.641263)
			(xy 40.68614 -355.687372) (xy 41.20818 -355.687372) (xy 41.20818 -355.627436) (xy 41.216003 -355.568014)
			(xy 41.231516 -355.510121) (xy 41.254452 -355.454748) (xy 41.284419 -355.402842) (xy 41.320906 -355.355292)
			(xy 41.363286 -355.312912) (xy 41.410836 -355.276425) (xy 41.462742 -355.246458) (xy 41.518115 -355.223522)
			(xy 41.576008 -355.208009) (xy 41.63543 -355.200186) (xy 41.665398 -355.199696) (xy 41.695366 -355.200186)
			(xy 41.754788 -355.208009) (xy 41.812681 -355.223522) (xy 41.868054 -355.246458) (xy 41.91996 -355.276425)
			(xy 41.96751 -355.312912) (xy 42.00989 -355.355292) (xy 42.046377 -355.402842) (xy 42.047579 -355.404924)
			(xy 82.254326 -355.404924) (xy 82.254326 -355.344988) (xy 82.262149 -355.285566) (xy 82.277662 -355.227673)
			(xy 82.300598 -355.1723) (xy 82.330565 -355.120394) (xy 82.367052 -355.072844) (xy 82.409432 -355.030464)
			(xy 82.456982 -354.993977) (xy 82.508888 -354.96401) (xy 82.564261 -354.941074) (xy 82.622154 -354.925561)
			(xy 82.681576 -354.917738) (xy 82.711544 -354.917248) (xy 82.741512 -354.917738) (xy 82.800934 -354.925561)
			(xy 82.858827 -354.941074) (xy 82.9142 -354.96401) (xy 82.966106 -354.993977) (xy 83.013656 -355.030464)
			(xy 83.056036 -355.072844) (xy 83.092523 -355.120394) (xy 83.12249 -355.1723) (xy 83.145426 -355.227673)
			(xy 83.160939 -355.285566) (xy 83.168762 -355.344988) (xy 83.168762 -355.404924) (xy 83.160939 -355.464346)
			(xy 83.145426 -355.522239) (xy 83.12249 -355.577612) (xy 83.092523 -355.629518) (xy 83.056036 -355.677068)
			(xy 83.013656 -355.719448) (xy 82.966106 -355.755935) (xy 82.9142 -355.785902) (xy 82.858827 -355.808838)
			(xy 82.800934 -355.824351) (xy 82.741512 -355.832174) (xy 82.681576 -355.832174) (xy 82.622154 -355.824351)
			(xy 82.564261 -355.808838) (xy 82.508888 -355.785902) (xy 82.456982 -355.755935) (xy 82.409432 -355.719448)
			(xy 82.367052 -355.677068) (xy 82.330565 -355.629518) (xy 82.300598 -355.577612) (xy 82.277662 -355.522239)
			(xy 82.262149 -355.464346) (xy 82.254326 -355.404924) (xy 42.047579 -355.404924) (xy 42.076344 -355.454748)
			(xy 42.09928 -355.510121) (xy 42.114793 -355.568014) (xy 42.122616 -355.627436) (xy 42.122616 -355.687372)
			(xy 42.114793 -355.746794) (xy 42.09928 -355.804687) (xy 42.076344 -355.86006) (xy 42.046377 -355.911966)
			(xy 42.00989 -355.959516) (xy 42.003142 -355.966264) (xy 42.811936 -355.966264) (xy 42.811936 -355.906328)
			(xy 42.819759 -355.846906) (xy 42.835272 -355.789013) (xy 42.858208 -355.73364) (xy 42.888175 -355.681734)
			(xy 42.924662 -355.634184) (xy 42.967042 -355.591804) (xy 43.014592 -355.555317) (xy 43.066498 -355.52535)
			(xy 43.121871 -355.502414) (xy 43.179764 -355.486901) (xy 43.239186 -355.479078) (xy 43.269154 -355.478588)
			(xy 43.299122 -355.479078) (xy 43.358544 -355.486901) (xy 43.416437 -355.502414) (xy 43.47181 -355.52535)
			(xy 43.523716 -355.555317) (xy 43.571266 -355.591804) (xy 43.613646 -355.634184) (xy 43.650133 -355.681734)
			(xy 43.6801 -355.73364) (xy 43.703036 -355.789013) (xy 43.718549 -355.846906) (xy 43.726372 -355.906328)
			(xy 43.726372 -355.966264) (xy 43.718549 -356.025686) (xy 43.703036 -356.083579) (xy 43.6801 -356.138952)
			(xy 43.650133 -356.190858) (xy 43.628153 -356.219502) (xy 44.267864 -356.219502) (xy 44.267864 -356.159566)
			(xy 44.275687 -356.100144) (xy 44.2912 -356.042251) (xy 44.314136 -355.986878) (xy 44.344103 -355.934972)
			(xy 44.38059 -355.887422) (xy 44.42297 -355.845042) (xy 44.47052 -355.808555) (xy 44.522426 -355.778588)
			(xy 44.577799 -355.755652) (xy 44.635692 -355.740139) (xy 44.695114 -355.732316) (xy 44.725082 -355.731826)
			(xy 44.75505 -355.732316) (xy 44.814472 -355.740139) (xy 44.872365 -355.755652) (xy 44.927738 -355.778588)
			(xy 44.979644 -355.808555) (xy 45.027194 -355.845042) (xy 45.069574 -355.887422) (xy 45.106061 -355.934972)
			(xy 45.127353 -355.971852) (xy 80.671398 -355.971852) (xy 80.671398 -355.911916) (xy 80.679221 -355.852494)
			(xy 80.694734 -355.794601) (xy 80.71767 -355.739228) (xy 80.747637 -355.687322) (xy 80.784124 -355.639772)
			(xy 80.826504 -355.597392) (xy 80.874054 -355.560905) (xy 80.92596 -355.530938) (xy 80.981333 -355.508002)
			(xy 81.039226 -355.492489) (xy 81.098648 -355.484666) (xy 81.128616 -355.484176) (xy 81.158584 -355.484666)
			(xy 81.218006 -355.492489) (xy 81.275899 -355.508002) (xy 81.331272 -355.530938) (xy 81.383178 -355.560905)
			(xy 81.430728 -355.597392) (xy 81.473108 -355.639772) (xy 81.509595 -355.687322) (xy 81.539562 -355.739228)
			(xy 81.562498 -355.794601) (xy 81.573105 -355.834184) (xy 84.542866 -355.834184) (xy 84.542866 -355.774248)
			(xy 84.550689 -355.714826) (xy 84.566202 -355.656933) (xy 84.589138 -355.60156) (xy 84.619105 -355.549654)
			(xy 84.655592 -355.502104) (xy 84.697972 -355.459724) (xy 84.745522 -355.423237) (xy 84.797428 -355.39327)
			(xy 84.852801 -355.370334) (xy 84.910694 -355.354821) (xy 84.970116 -355.346998) (xy 85.000084 -355.346508)
			(xy 85.030052 -355.346998) (xy 85.089474 -355.354821) (xy 85.147367 -355.370334) (xy 85.20274 -355.39327)
			(xy 85.254646 -355.423237) (xy 85.302196 -355.459724) (xy 85.344576 -355.502104) (xy 85.381063 -355.549654)
			(xy 85.41103 -355.60156) (xy 85.433966 -355.656933) (xy 85.449479 -355.714826) (xy 85.457302 -355.774248)
			(xy 85.457302 -355.834184) (xy 85.449479 -355.893606) (xy 85.433966 -355.951499) (xy 85.41103 -356.006872)
			(xy 85.383736 -356.054148) (xy 86.951802 -356.054148) (xy 86.951802 -355.994212) (xy 86.959625 -355.93479)
			(xy 86.975138 -355.876897) (xy 86.998074 -355.821524) (xy 87.028041 -355.769618) (xy 87.064528 -355.722068)
			(xy 87.106908 -355.679688) (xy 87.154458 -355.643201) (xy 87.206364 -355.613234) (xy 87.261737 -355.590298)
			(xy 87.31963 -355.574785) (xy 87.379052 -355.566962) (xy 87.40902 -355.566472) (xy 87.438988 -355.566962)
			(xy 87.49841 -355.574785) (xy 87.556303 -355.590298) (xy 87.611676 -355.613234) (xy 87.663582 -355.643201)
			(xy 87.711132 -355.679688) (xy 87.753512 -355.722068) (xy 87.789999 -355.769618) (xy 87.819966 -355.821524)
			(xy 87.842902 -355.876897) (xy 87.858415 -355.93479) (xy 87.866238 -355.994212) (xy 87.866238 -356.054148)
			(xy 87.858415 -356.11357) (xy 87.842902 -356.171463) (xy 87.819966 -356.226836) (xy 87.789999 -356.278742)
			(xy 87.753512 -356.326292) (xy 87.711132 -356.368672) (xy 87.663582 -356.405159) (xy 87.611676 -356.435126)
			(xy 87.566858 -356.45369) (xy 88.618042 -356.45369) (xy 88.618042 -356.393754) (xy 88.625865 -356.334332)
			(xy 88.641378 -356.276439) (xy 88.664314 -356.221066) (xy 88.694281 -356.16916) (xy 88.730768 -356.12161)
			(xy 88.773148 -356.07923) (xy 88.820698 -356.042743) (xy 88.872604 -356.012776) (xy 88.927977 -355.98984)
			(xy 88.98587 -355.974327) (xy 89.045292 -355.966504) (xy 89.07526 -355.966014) (xy 89.105228 -355.966504)
			(xy 89.16465 -355.974327) (xy 89.222543 -355.98984) (xy 89.277916 -356.012776) (xy 89.329822 -356.042743)
			(xy 89.377372 -356.07923) (xy 89.419752 -356.12161) (xy 89.456239 -356.16916) (xy 89.486206 -356.221066)
			(xy 89.509142 -356.276439) (xy 89.524655 -356.334332) (xy 89.532478 -356.393754) (xy 89.532478 -356.45369)
			(xy 89.524655 -356.513112) (xy 89.509142 -356.571005) (xy 89.486206 -356.626378) (xy 89.456239 -356.678284)
			(xy 89.419752 -356.725834) (xy 89.377372 -356.768214) (xy 89.329822 -356.804701) (xy 89.277916 -356.834668)
			(xy 89.222543 -356.857604) (xy 89.16465 -356.873117) (xy 89.105228 -356.88094) (xy 89.045292 -356.88094)
			(xy 88.98587 -356.873117) (xy 88.927977 -356.857604) (xy 88.872604 -356.834668) (xy 88.820698 -356.804701)
			(xy 88.773148 -356.768214) (xy 88.730768 -356.725834) (xy 88.694281 -356.678284) (xy 88.664314 -356.626378)
			(xy 88.641378 -356.571005) (xy 88.625865 -356.513112) (xy 88.618042 -356.45369) (xy 87.566858 -356.45369)
			(xy 87.556303 -356.458062) (xy 87.49841 -356.473575) (xy 87.438988 -356.481398) (xy 87.379052 -356.481398)
			(xy 87.31963 -356.473575) (xy 87.261737 -356.458062) (xy 87.206364 -356.435126) (xy 87.154458 -356.405159)
			(xy 87.106908 -356.368672) (xy 87.064528 -356.326292) (xy 87.028041 -356.278742) (xy 86.998074 -356.226836)
			(xy 86.975138 -356.171463) (xy 86.959625 -356.11357) (xy 86.951802 -356.054148) (xy 85.383736 -356.054148)
			(xy 85.381063 -356.058778) (xy 85.344576 -356.106328) (xy 85.302196 -356.148708) (xy 85.254646 -356.185195)
			(xy 85.20274 -356.215162) (xy 85.147367 -356.238098) (xy 85.089474 -356.253611) (xy 85.030052 -356.261434)
			(xy 84.970116 -356.261434) (xy 84.910694 -356.253611) (xy 84.852801 -356.238098) (xy 84.797428 -356.215162)
			(xy 84.745522 -356.185195) (xy 84.697972 -356.148708) (xy 84.655592 -356.106328) (xy 84.619105 -356.058778)
			(xy 84.589138 -356.006872) (xy 84.566202 -355.951499) (xy 84.550689 -355.893606) (xy 84.542866 -355.834184)
			(xy 81.573105 -355.834184) (xy 81.578011 -355.852494) (xy 81.585834 -355.911916) (xy 81.585834 -355.971852)
			(xy 81.578011 -356.031274) (xy 81.562498 -356.089167) (xy 81.539562 -356.14454) (xy 81.509595 -356.196446)
			(xy 81.473108 -356.243996) (xy 81.430728 -356.286376) (xy 81.383178 -356.322863) (xy 81.331272 -356.35283)
			(xy 81.275899 -356.375766) (xy 81.218006 -356.391279) (xy 81.158584 -356.399102) (xy 81.098648 -356.399102)
			(xy 81.039226 -356.391279) (xy 80.981333 -356.375766) (xy 80.92596 -356.35283) (xy 80.874054 -356.322863)
			(xy 80.826504 -356.286376) (xy 80.784124 -356.243996) (xy 80.747637 -356.196446) (xy 80.71767 -356.14454)
			(xy 80.694734 -356.089167) (xy 80.679221 -356.031274) (xy 80.671398 -355.971852) (xy 45.127353 -355.971852)
			(xy 45.136028 -355.986878) (xy 45.158964 -356.042251) (xy 45.174477 -356.100144) (xy 45.1823 -356.159566)
			(xy 45.1823 -356.219502) (xy 45.174477 -356.278924) (xy 45.158964 -356.336817) (xy 45.136028 -356.39219)
			(xy 45.106061 -356.444096) (xy 45.069574 -356.491646) (xy 45.06181 -356.49941) (xy 79.345264 -356.49941)
			(xy 79.345264 -356.439474) (xy 79.353087 -356.380052) (xy 79.3686 -356.322159) (xy 79.391536 -356.266786)
			(xy 79.421503 -356.21488) (xy 79.45799 -356.16733) (xy 79.50037 -356.12495) (xy 79.54792 -356.088463)
			(xy 79.599826 -356.058496) (xy 79.655199 -356.03556) (xy 79.713092 -356.020047) (xy 79.772514 -356.012224)
			(xy 79.802482 -356.011734) (xy 79.83245 -356.012224) (xy 79.891872 -356.020047) (xy 79.949765 -356.03556)
			(xy 80.005138 -356.058496) (xy 80.057044 -356.088463) (xy 80.104594 -356.12495) (xy 80.146974 -356.16733)
			(xy 80.183461 -356.21488) (xy 80.213428 -356.266786) (xy 80.236364 -356.322159) (xy 80.251877 -356.380052)
			(xy 80.2597 -356.439474) (xy 80.2597 -356.49941) (xy 80.251877 -356.558832) (xy 80.236364 -356.616725)
			(xy 80.213428 -356.672098) (xy 80.183461 -356.724004) (xy 80.146974 -356.771554) (xy 80.104594 -356.813934)
			(xy 80.057044 -356.850421) (xy 80.005138 -356.880388) (xy 79.949765 -356.903324) (xy 79.891872 -356.918837)
			(xy 79.83245 -356.92666) (xy 79.772514 -356.92666) (xy 79.713092 -356.918837) (xy 79.655199 -356.903324)
			(xy 79.599826 -356.880388) (xy 79.54792 -356.850421) (xy 79.50037 -356.813934) (xy 79.45799 -356.771554)
			(xy 79.421503 -356.724004) (xy 79.391536 -356.672098) (xy 79.3686 -356.616725) (xy 79.353087 -356.558832)
			(xy 79.345264 -356.49941) (xy 45.06181 -356.49941) (xy 45.027194 -356.534026) (xy 44.979644 -356.570513)
			(xy 44.927738 -356.60048) (xy 44.872365 -356.623416) (xy 44.814472 -356.638929) (xy 44.75505 -356.646752)
			(xy 44.695114 -356.646752) (xy 44.635692 -356.638929) (xy 44.577799 -356.623416) (xy 44.522426 -356.60048)
			(xy 44.47052 -356.570513) (xy 44.42297 -356.534026) (xy 44.38059 -356.491646) (xy 44.344103 -356.444096)
			(xy 44.314136 -356.39219) (xy 44.2912 -356.336817) (xy 44.275687 -356.278924) (xy 44.267864 -356.219502)
			(xy 43.628153 -356.219502) (xy 43.613646 -356.238408) (xy 43.571266 -356.280788) (xy 43.523716 -356.317275)
			(xy 43.47181 -356.347242) (xy 43.416437 -356.370178) (xy 43.358544 -356.385691) (xy 43.299122 -356.393514)
			(xy 43.239186 -356.393514) (xy 43.179764 -356.385691) (xy 43.121871 -356.370178) (xy 43.066498 -356.347242)
			(xy 43.014592 -356.317275) (xy 42.967042 -356.280788) (xy 42.924662 -356.238408) (xy 42.888175 -356.190858)
			(xy 42.858208 -356.138952) (xy 42.835272 -356.083579) (xy 42.819759 -356.025686) (xy 42.811936 -355.966264)
			(xy 42.003142 -355.966264) (xy 41.96751 -356.001896) (xy 41.91996 -356.038383) (xy 41.868054 -356.06835)
			(xy 41.812681 -356.091286) (xy 41.754788 -356.106799) (xy 41.695366 -356.114622) (xy 41.63543 -356.114622)
			(xy 41.576008 -356.106799) (xy 41.518115 -356.091286) (xy 41.462742 -356.06835) (xy 41.410836 -356.038383)
			(xy 41.363286 -356.001896) (xy 41.320906 -355.959516) (xy 41.284419 -355.911966) (xy 41.254452 -355.86006)
			(xy 41.231516 -355.804687) (xy 41.216003 -355.746794) (xy 41.20818 -355.687372) (xy 40.68614 -355.687372)
			(xy 40.682407 -355.694668) (xy 40.648341 -355.744046) (xy 40.608118 -355.78855) (xy 40.562425 -355.827419)
			(xy 40.512046 -355.859986) (xy 40.457845 -355.885693) (xy 40.40075 -355.904099) (xy 40.34174 -355.914889)
			(xy 40.281827 -355.917878) (xy 40.251888 -355.915976) (xy 40.228603 -355.914629) (xy 40.182214 -355.91943)
			(xy 40.137481 -355.932616) (xy 40.095905 -355.953744) (xy 40.058883 -355.982104) (xy 40.027657 -356.016744)
			(xy 40.003278 -356.056501) (xy 39.986562 -356.100039) (xy 39.978072 -356.145896) (xy 39.977568 -356.169214)
			(xy 39.977568 -361.049062) (xy 39.978034 -361.071403) (xy 39.985844 -361.115398) (xy 40.001229 -361.157348)
			(xy 40.023716 -361.19596) (xy 40.05261 -361.230043) (xy 40.08702 -361.258546) (xy 40.125886 -361.280591)
			(xy 40.168009 -361.295496) (xy 40.21209 -361.302804) (xy 40.25677 -361.302287) (xy 40.30067 -361.293963)
			(xy 40.342437 -361.278087) (xy 40.380783 -361.255151) (xy 40.397938 -361.240832) (xy 40.442225 -361.203042)
			(xy 40.535221 -361.132983) (xy 40.632843 -361.069528) (xy 40.734622 -361.012981) (xy 40.840071 -360.963613)
			(xy 40.948683 -360.921662) (xy 41.059939 -360.887329) (xy 41.173304 -360.860778) (xy 41.288234 -360.842136)
			(xy 41.40418 -360.831493) (xy 41.520583 -360.8289) (xy 41.636888 -360.83437) (xy 41.752534 -360.847876)
			(xy 41.866969 -360.869353) (xy 41.979643 -360.898698) (xy 42.090016 -360.935772) (xy 42.197558 -360.980395)
			(xy 42.301754 -361.032354) (xy 42.402105 -361.0914) (xy 42.47458 -361.141101) (xy 63.647829 -361.141101)
			(xy 63.653878 -361.065531) (xy 63.667925 -360.991033) (xy 63.689811 -360.91845) (xy 63.719288 -360.848604)
			(xy 63.756023 -360.782287) (xy 63.799598 -360.720251) (xy 63.84952 -360.663198) (xy 63.905224 -360.611774)
			(xy 63.966079 -360.566563) (xy 64.031394 -360.528076) (xy 64.10043 -360.49675) (xy 64.172405 -360.47294)
			(xy 64.246503 -360.456915) (xy 64.321884 -360.448856) (xy 64.35979 -360.448352) (xy 64.397696 -360.448856)
			(xy 64.473077 -360.456915) (xy 64.547175 -360.47294) (xy 64.61915 -360.49675) (xy 64.688186 -360.528076)
			(xy 64.753501 -360.566563) (xy 64.814356 -360.611774) (xy 64.87006 -360.663198) (xy 64.919982 -360.720251)
			(xy 64.963557 -360.782287) (xy 65.000292 -360.848604) (xy 65.029769 -360.91845) (xy 65.051655 -360.991033)
			(xy 65.065702 -361.065531) (xy 65.071751 -361.141101) (xy 66.187829 -361.141101) (xy 66.193878 -361.065531)
			(xy 66.207925 -360.991033) (xy 66.229811 -360.91845) (xy 66.259288 -360.848604) (xy 66.296023 -360.782287)
			(xy 66.339598 -360.720251) (xy 66.38952 -360.663198) (xy 66.445224 -360.611774) (xy 66.506079 -360.566563)
			(xy 66.571394 -360.528076) (xy 66.64043 -360.49675) (xy 66.712405 -360.47294) (xy 66.786503 -360.456915)
			(xy 66.861884 -360.448856) (xy 66.89979 -360.448352) (xy 66.937696 -360.448856) (xy 67.013077 -360.456915)
			(xy 67.087175 -360.47294) (xy 67.15915 -360.49675) (xy 67.228186 -360.528076) (xy 67.293501 -360.566563)
			(xy 67.354356 -360.611774) (xy 67.41006 -360.663198) (xy 67.459982 -360.720251) (xy 67.503557 -360.782287)
			(xy 67.540292 -360.848604) (xy 67.569769 -360.91845) (xy 67.591655 -360.991033) (xy 67.605702 -361.065531)
			(xy 67.611751 -361.141101) (xy 68.727829 -361.141101) (xy 68.733878 -361.065531) (xy 68.747925 -360.991033)
			(xy 68.769811 -360.91845) (xy 68.799288 -360.848604) (xy 68.836023 -360.782287) (xy 68.879598 -360.720251)
			(xy 68.92952 -360.663198) (xy 68.985224 -360.611774) (xy 69.046079 -360.566563) (xy 69.111394 -360.528076)
			(xy 69.18043 -360.49675) (xy 69.252405 -360.47294) (xy 69.326503 -360.456915) (xy 69.401884 -360.448856)
			(xy 69.43979 -360.448352) (xy 69.477696 -360.448856) (xy 69.553077 -360.456915) (xy 69.627175 -360.47294)
			(xy 69.69915 -360.49675) (xy 69.768186 -360.528076) (xy 69.833501 -360.566563) (xy 69.894356 -360.611774)
			(xy 69.95006 -360.663198) (xy 69.999982 -360.720251) (xy 70.043557 -360.782287) (xy 70.080292 -360.848604)
			(xy 70.109769 -360.91845) (xy 70.131655 -360.991033) (xy 70.145702 -361.065531) (xy 70.151751 -361.141101)
			(xy 71.267829 -361.141101) (xy 71.273878 -361.065531) (xy 71.287925 -360.991033) (xy 71.309811 -360.91845)
			(xy 71.339288 -360.848604) (xy 71.376023 -360.782287) (xy 71.419598 -360.720251) (xy 71.46952 -360.663198)
			(xy 71.525224 -360.611774) (xy 71.586079 -360.566563) (xy 71.651394 -360.528076) (xy 71.72043 -360.49675)
			(xy 71.792405 -360.47294) (xy 71.866503 -360.456915) (xy 71.941884 -360.448856) (xy 71.97979 -360.448352)
			(xy 72.017696 -360.448856) (xy 72.093077 -360.456915) (xy 72.167175 -360.47294) (xy 72.23915 -360.49675)
			(xy 72.308186 -360.528076) (xy 72.373501 -360.566563) (xy 72.434356 -360.611774) (xy 72.49006 -360.663198)
			(xy 72.539982 -360.720251) (xy 72.583557 -360.782287) (xy 72.620292 -360.848604) (xy 72.649769 -360.91845)
			(xy 72.671655 -360.991033) (xy 72.685702 -361.065531) (xy 72.691751 -361.141101) (xy 73.807829 -361.141101)
			(xy 73.813878 -361.065531) (xy 73.827925 -360.991033) (xy 73.849811 -360.91845) (xy 73.879288 -360.848604)
			(xy 73.916023 -360.782287) (xy 73.959598 -360.720251) (xy 74.00952 -360.663198) (xy 74.065224 -360.611774)
			(xy 74.126079 -360.566563) (xy 74.191394 -360.528076) (xy 74.26043 -360.49675) (xy 74.332405 -360.47294)
			(xy 74.406503 -360.456915) (xy 74.481884 -360.448856) (xy 74.51979 -360.448352) (xy 74.557696 -360.448856)
			(xy 74.633077 -360.456915) (xy 74.707175 -360.47294) (xy 74.77915 -360.49675) (xy 74.848186 -360.528076)
			(xy 74.913501 -360.566563) (xy 74.974356 -360.611774) (xy 75.03006 -360.663198) (xy 75.079982 -360.720251)
			(xy 75.123557 -360.782287) (xy 75.160292 -360.848604) (xy 75.189769 -360.91845) (xy 75.211655 -360.991033)
			(xy 75.225702 -361.065531) (xy 75.231751 -361.141101) (xy 76.347829 -361.141101) (xy 76.353878 -361.065531)
			(xy 76.367925 -360.991033) (xy 76.389811 -360.91845) (xy 76.419288 -360.848604) (xy 76.456023 -360.782287)
			(xy 76.499598 -360.720251) (xy 76.54952 -360.663198) (xy 76.605224 -360.611774) (xy 76.666079 -360.566563)
			(xy 76.731394 -360.528076) (xy 76.80043 -360.49675) (xy 76.872405 -360.47294) (xy 76.946503 -360.456915)
			(xy 77.021884 -360.448856) (xy 77.05979 -360.448352) (xy 77.097696 -360.448856) (xy 77.173077 -360.456915)
			(xy 77.247175 -360.47294) (xy 77.31915 -360.49675) (xy 77.388186 -360.528076) (xy 77.453501 -360.566563)
			(xy 77.514356 -360.611774) (xy 77.57006 -360.663198) (xy 77.619982 -360.720251) (xy 77.663557 -360.782287)
			(xy 77.700292 -360.848604) (xy 77.729769 -360.91845) (xy 77.751655 -360.991033) (xy 77.765702 -361.065531)
			(xy 77.771751 -361.141101) (xy 78.887829 -361.141101) (xy 78.893878 -361.065531) (xy 78.907925 -360.991033)
			(xy 78.929811 -360.91845) (xy 78.959288 -360.848604) (xy 78.996023 -360.782287) (xy 79.039598 -360.720251)
			(xy 79.08952 -360.663198) (xy 79.145224 -360.611774) (xy 79.206079 -360.566563) (xy 79.271394 -360.528076)
			(xy 79.34043 -360.49675) (xy 79.412405 -360.47294) (xy 79.486503 -360.456915) (xy 79.561884 -360.448856)
			(xy 79.59979 -360.448352) (xy 79.637696 -360.448856) (xy 79.713077 -360.456915) (xy 79.787175 -360.47294)
			(xy 79.85915 -360.49675) (xy 79.928186 -360.528076) (xy 79.993501 -360.566563) (xy 80.054356 -360.611774)
			(xy 80.11006 -360.663198) (xy 80.159982 -360.720251) (xy 80.203557 -360.782287) (xy 80.240292 -360.848604)
			(xy 80.269769 -360.91845) (xy 80.291655 -360.991033) (xy 80.305702 -361.065531) (xy 80.311751 -361.141101)
			(xy 81.427829 -361.141101) (xy 81.433878 -361.065531) (xy 81.447925 -360.991033) (xy 81.469811 -360.91845)
			(xy 81.499288 -360.848604) (xy 81.536023 -360.782287) (xy 81.579598 -360.720251) (xy 81.62952 -360.663198)
			(xy 81.685224 -360.611774) (xy 81.746079 -360.566563) (xy 81.811394 -360.528076) (xy 81.88043 -360.49675)
			(xy 81.952405 -360.47294) (xy 82.026503 -360.456915) (xy 82.101884 -360.448856) (xy 82.13979 -360.448352)
			(xy 82.177696 -360.448856) (xy 82.253077 -360.456915) (xy 82.327175 -360.47294) (xy 82.39915 -360.49675)
			(xy 82.468186 -360.528076) (xy 82.533501 -360.566563) (xy 82.559813 -360.586111) (xy 86.197949 -360.586111)
			(xy 86.203998 -360.510541) (xy 86.218045 -360.436043) (xy 86.239931 -360.36346) (xy 86.269408 -360.293614)
			(xy 86.306143 -360.227297) (xy 86.349718 -360.165261) (xy 86.39964 -360.108208) (xy 86.455344 -360.056784)
			(xy 86.516199 -360.011573) (xy 86.581514 -359.973086) (xy 86.65055 -359.94176) (xy 86.722525 -359.91795)
			(xy 86.796623 -359.901925) (xy 86.872004 -359.893866) (xy 86.90991 -359.893362) (xy 86.947816 -359.893866)
			(xy 87.023197 -359.901925) (xy 87.097295 -359.91795) (xy 87.16927 -359.94176) (xy 87.238306 -359.973086)
			(xy 87.303621 -360.011573) (xy 87.364476 -360.056784) (xy 87.42018 -360.108208) (xy 87.470102 -360.165261)
			(xy 87.513677 -360.227297) (xy 87.550412 -360.293614) (xy 87.579889 -360.36346) (xy 87.601775 -360.436043)
			(xy 87.615822 -360.510541) (xy 87.621871 -360.586111) (xy 88.737949 -360.586111) (xy 88.743998 -360.510541)
			(xy 88.758045 -360.436043) (xy 88.779931 -360.36346) (xy 88.809408 -360.293614) (xy 88.846143 -360.227297)
			(xy 88.889718 -360.165261) (xy 88.93964 -360.108208) (xy 88.995344 -360.056784) (xy 89.056199 -360.011573)
			(xy 89.121514 -359.973086) (xy 89.19055 -359.94176) (xy 89.262525 -359.91795) (xy 89.336623 -359.901925)
			(xy 89.412004 -359.893866) (xy 89.44991 -359.893362) (xy 89.487816 -359.893866) (xy 89.563197 -359.901925)
			(xy 89.637295 -359.91795) (xy 89.70927 -359.94176) (xy 89.778306 -359.973086) (xy 89.843621 -360.011573)
			(xy 89.904476 -360.056784) (xy 89.96018 -360.108208) (xy 90.010102 -360.165261) (xy 90.053677 -360.227297)
			(xy 90.090412 -360.293614) (xy 90.119889 -360.36346) (xy 90.141775 -360.436043) (xy 90.155822 -360.510541)
			(xy 90.161871 -360.586111) (xy 91.277949 -360.586111) (xy 91.283998 -360.510541) (xy 91.298045 -360.436043)
			(xy 91.319931 -360.36346) (xy 91.349408 -360.293614) (xy 91.386143 -360.227297) (xy 91.429718 -360.165261)
			(xy 91.47964 -360.108208) (xy 91.535344 -360.056784) (xy 91.596199 -360.011573) (xy 91.661514 -359.973086)
			(xy 91.73055 -359.94176) (xy 91.802525 -359.91795) (xy 91.876623 -359.901925) (xy 91.952004 -359.893866)
			(xy 91.98991 -359.893362) (xy 92.027816 -359.893866) (xy 92.103197 -359.901925) (xy 92.177295 -359.91795)
			(xy 92.24927 -359.94176) (xy 92.318306 -359.973086) (xy 92.383621 -360.011573) (xy 92.444476 -360.056784)
			(xy 92.50018 -360.108208) (xy 92.550102 -360.165261) (xy 92.593677 -360.227297) (xy 92.630412 -360.293614)
			(xy 92.659889 -360.36346) (xy 92.681775 -360.436043) (xy 92.695822 -360.510541) (xy 92.701871 -360.586111)
			(xy 92.699852 -360.661895) (xy 92.68979 -360.737035) (xy 92.671798 -360.81068) (xy 92.64608 -360.881996)
			(xy 92.612928 -360.950173) (xy 92.572716 -361.014441) (xy 92.525901 -361.07407) (xy 92.473013 -361.128386)
			(xy 92.414651 -361.176772) (xy 92.351476 -361.21868) (xy 92.284205 -361.253636) (xy 92.2136 -361.281243)
			(xy 92.140459 -361.301189) (xy 92.065614 -361.313248) (xy 91.98991 -361.317283) (xy 91.914206 -361.313248)
			(xy 91.839361 -361.301189) (xy 91.76622 -361.281243) (xy 91.695615 -361.253636) (xy 91.628344 -361.21868)
			(xy 91.565169 -361.176772) (xy 91.506807 -361.128386) (xy 91.453919 -361.07407) (xy 91.407104 -361.014441)
			(xy 91.366892 -360.950173) (xy 91.33374 -360.881996) (xy 91.308022 -360.81068) (xy 91.29003 -360.737035)
			(xy 91.279968 -360.661895) (xy 91.277949 -360.586111) (xy 90.161871 -360.586111) (xy 90.159852 -360.661895)
			(xy 90.14979 -360.737035) (xy 90.131798 -360.81068) (xy 90.10608 -360.881996) (xy 90.072928 -360.950173)
			(xy 90.032716 -361.014441) (xy 89.985901 -361.07407) (xy 89.933013 -361.128386) (xy 89.874651 -361.176772)
			(xy 89.811476 -361.21868) (xy 89.744205 -361.253636) (xy 89.6736 -361.281243) (xy 89.600459 -361.301189)
			(xy 89.525614 -361.313248) (xy 89.44991 -361.317283) (xy 89.374206 -361.313248) (xy 89.299361 -361.301189)
			(xy 89.22622 -361.281243) (xy 89.155615 -361.253636) (xy 89.088344 -361.21868) (xy 89.025169 -361.176772)
			(xy 88.966807 -361.128386) (xy 88.913919 -361.07407) (xy 88.867104 -361.014441) (xy 88.826892 -360.950173)
			(xy 88.79374 -360.881996) (xy 88.768022 -360.81068) (xy 88.75003 -360.737035) (xy 88.739968 -360.661895)
			(xy 88.737949 -360.586111) (xy 87.621871 -360.586111) (xy 87.619852 -360.661895) (xy 87.60979 -360.737035)
			(xy 87.591798 -360.81068) (xy 87.56608 -360.881996) (xy 87.532928 -360.950173) (xy 87.492716 -361.014441)
			(xy 87.445901 -361.07407) (xy 87.393013 -361.128386) (xy 87.334651 -361.176772) (xy 87.271476 -361.21868)
			(xy 87.204205 -361.253636) (xy 87.1336 -361.281243) (xy 87.060459 -361.301189) (xy 86.985614 -361.313248)
			(xy 86.90991 -361.317283) (xy 86.834206 -361.313248) (xy 86.759361 -361.301189) (xy 86.68622 -361.281243)
			(xy 86.615615 -361.253636) (xy 86.548344 -361.21868) (xy 86.485169 -361.176772) (xy 86.426807 -361.128386)
			(xy 86.373919 -361.07407) (xy 86.327104 -361.014441) (xy 86.286892 -360.950173) (xy 86.25374 -360.881996)
			(xy 86.228022 -360.81068) (xy 86.21003 -360.737035) (xy 86.199968 -360.661895) (xy 86.197949 -360.586111)
			(xy 82.559813 -360.586111) (xy 82.594356 -360.611774) (xy 82.65006 -360.663198) (xy 82.699982 -360.720251)
			(xy 82.743557 -360.782287) (xy 82.780292 -360.848604) (xy 82.809769 -360.91845) (xy 82.831655 -360.991033)
			(xy 82.845702 -361.065531) (xy 82.851751 -361.141101) (xy 82.849732 -361.216885) (xy 82.83967 -361.292025)
			(xy 82.821678 -361.36567) (xy 82.79596 -361.436986) (xy 82.762808 -361.505163) (xy 82.722596 -361.569431)
			(xy 82.675781 -361.62906) (xy 82.622893 -361.683376) (xy 82.564531 -361.731762) (xy 82.501356 -361.77367)
			(xy 82.434085 -361.808626) (xy 82.36348 -361.836233) (xy 82.290588 -361.856111) (xy 84.927949 -361.856111)
			(xy 84.933998 -361.780541) (xy 84.948045 -361.706043) (xy 84.969931 -361.63346) (xy 84.999408 -361.563614)
			(xy 85.036143 -361.497297) (xy 85.079718 -361.435261) (xy 85.12964 -361.378208) (xy 85.185344 -361.326784)
			(xy 85.246199 -361.281573) (xy 85.311514 -361.243086) (xy 85.38055 -361.21176) (xy 85.452525 -361.18795)
			(xy 85.526623 -361.171925) (xy 85.602004 -361.163866) (xy 85.63991 -361.163362) (xy 85.677816 -361.163866)
			(xy 85.753197 -361.171925) (xy 85.827295 -361.18795) (xy 85.89927 -361.21176) (xy 85.968306 -361.243086)
			(xy 86.033621 -361.281573) (xy 86.094476 -361.326784) (xy 86.15018 -361.378208) (xy 86.200102 -361.435261)
			(xy 86.243677 -361.497297) (xy 86.280412 -361.563614) (xy 86.309889 -361.63346) (xy 86.331775 -361.706043)
			(xy 86.345822 -361.780541) (xy 86.351871 -361.856111) (xy 87.467949 -361.856111) (xy 87.473998 -361.780541)
			(xy 87.488045 -361.706043) (xy 87.509931 -361.63346) (xy 87.539408 -361.563614) (xy 87.576143 -361.497297)
			(xy 87.619718 -361.435261) (xy 87.66964 -361.378208) (xy 87.725344 -361.326784) (xy 87.786199 -361.281573)
			(xy 87.851514 -361.243086) (xy 87.92055 -361.21176) (xy 87.992525 -361.18795) (xy 88.066623 -361.171925)
			(xy 88.142004 -361.163866) (xy 88.17991 -361.163362) (xy 88.217816 -361.163866) (xy 88.293197 -361.171925)
			(xy 88.367295 -361.18795) (xy 88.43927 -361.21176) (xy 88.508306 -361.243086) (xy 88.573621 -361.281573)
			(xy 88.634476 -361.326784) (xy 88.69018 -361.378208) (xy 88.740102 -361.435261) (xy 88.783677 -361.497297)
			(xy 88.820412 -361.563614) (xy 88.849889 -361.63346) (xy 88.871775 -361.706043) (xy 88.885822 -361.780541)
			(xy 88.891871 -361.856111) (xy 90.007949 -361.856111) (xy 90.013998 -361.780541) (xy 90.028045 -361.706043)
			(xy 90.049931 -361.63346) (xy 90.079408 -361.563614) (xy 90.116143 -361.497297) (xy 90.159718 -361.435261)
			(xy 90.20964 -361.378208) (xy 90.265344 -361.326784) (xy 90.326199 -361.281573) (xy 90.391514 -361.243086)
			(xy 90.46055 -361.21176) (xy 90.532525 -361.18795) (xy 90.606623 -361.171925) (xy 90.682004 -361.163866)
			(xy 90.71991 -361.163362) (xy 90.757816 -361.163866) (xy 90.833197 -361.171925) (xy 90.907295 -361.18795)
			(xy 90.97927 -361.21176) (xy 91.048306 -361.243086) (xy 91.113621 -361.281573) (xy 91.174476 -361.326784)
			(xy 91.23018 -361.378208) (xy 91.280102 -361.435261) (xy 91.323677 -361.497297) (xy 91.360412 -361.563614)
			(xy 91.389889 -361.63346) (xy 91.411775 -361.706043) (xy 91.425822 -361.780541) (xy 91.431871 -361.856111)
			(xy 91.429852 -361.931895) (xy 91.41979 -362.007035) (xy 91.401798 -362.08068) (xy 91.37608 -362.151996)
			(xy 91.342928 -362.220173) (xy 91.302716 -362.284441) (xy 91.255901 -362.34407) (xy 91.203013 -362.398386)
			(xy 91.144651 -362.446772) (xy 91.081476 -362.48868) (xy 91.014205 -362.523636) (xy 90.9436 -362.551243)
			(xy 90.870459 -362.571189) (xy 90.795614 -362.583248) (xy 90.71991 -362.587283) (xy 90.644206 -362.583248)
			(xy 90.569361 -362.571189) (xy 90.49622 -362.551243) (xy 90.425615 -362.523636) (xy 90.358344 -362.48868)
			(xy 90.295169 -362.446772) (xy 90.236807 -362.398386) (xy 90.183919 -362.34407) (xy 90.137104 -362.284441)
			(xy 90.096892 -362.220173) (xy 90.06374 -362.151996) (xy 90.038022 -362.08068) (xy 90.02003 -362.007035)
			(xy 90.009968 -361.931895) (xy 90.007949 -361.856111) (xy 88.891871 -361.856111) (xy 88.889852 -361.931895)
			(xy 88.87979 -362.007035) (xy 88.861798 -362.08068) (xy 88.83608 -362.151996) (xy 88.802928 -362.220173)
			(xy 88.762716 -362.284441) (xy 88.715901 -362.34407) (xy 88.663013 -362.398386) (xy 88.604651 -362.446772)
			(xy 88.541476 -362.48868) (xy 88.474205 -362.523636) (xy 88.4036 -362.551243) (xy 88.330459 -362.571189)
			(xy 88.255614 -362.583248) (xy 88.17991 -362.587283) (xy 88.104206 -362.583248) (xy 88.029361 -362.571189)
			(xy 87.95622 -362.551243) (xy 87.885615 -362.523636) (xy 87.818344 -362.48868) (xy 87.755169 -362.446772)
			(xy 87.696807 -362.398386) (xy 87.643919 -362.34407) (xy 87.597104 -362.284441) (xy 87.556892 -362.220173)
			(xy 87.52374 -362.151996) (xy 87.498022 -362.08068) (xy 87.48003 -362.007035) (xy 87.469968 -361.931895)
			(xy 87.467949 -361.856111) (xy 86.351871 -361.856111) (xy 86.349852 -361.931895) (xy 86.33979 -362.007035)
			(xy 86.321798 -362.08068) (xy 86.29608 -362.151996) (xy 86.262928 -362.220173) (xy 86.222716 -362.284441)
			(xy 86.175901 -362.34407) (xy 86.123013 -362.398386) (xy 86.064651 -362.446772) (xy 86.001476 -362.48868)
			(xy 85.934205 -362.523636) (xy 85.8636 -362.551243) (xy 85.790459 -362.571189) (xy 85.715614 -362.583248)
			(xy 85.63991 -362.587283) (xy 85.564206 -362.583248) (xy 85.489361 -362.571189) (xy 85.41622 -362.551243)
			(xy 85.345615 -362.523636) (xy 85.278344 -362.48868) (xy 85.215169 -362.446772) (xy 85.156807 -362.398386)
			(xy 85.103919 -362.34407) (xy 85.057104 -362.284441) (xy 85.016892 -362.220173) (xy 84.98374 -362.151996)
			(xy 84.958022 -362.08068) (xy 84.94003 -362.007035) (xy 84.929968 -361.931895) (xy 84.927949 -361.856111)
			(xy 82.290588 -361.856111) (xy 82.290339 -361.856179) (xy 82.215494 -361.868238) (xy 82.13979 -361.872273)
			(xy 82.064086 -361.868238) (xy 81.989241 -361.856179) (xy 81.9161 -361.836233) (xy 81.845495 -361.808626)
			(xy 81.778224 -361.77367) (xy 81.715049 -361.731762) (xy 81.656687 -361.683376) (xy 81.603799 -361.62906)
			(xy 81.556984 -361.569431) (xy 81.516772 -361.505163) (xy 81.48362 -361.436986) (xy 81.457902 -361.36567)
			(xy 81.43991 -361.292025) (xy 81.429848 -361.216885) (xy 81.427829 -361.141101) (xy 80.311751 -361.141101)
			(xy 80.309732 -361.216885) (xy 80.29967 -361.292025) (xy 80.281678 -361.36567) (xy 80.25596 -361.436986)
			(xy 80.222808 -361.505163) (xy 80.182596 -361.569431) (xy 80.135781 -361.62906) (xy 80.082893 -361.683376)
			(xy 80.024531 -361.731762) (xy 79.961356 -361.77367) (xy 79.894085 -361.808626) (xy 79.82348 -361.836233)
			(xy 79.750339 -361.856179) (xy 79.675494 -361.868238) (xy 79.59979 -361.872273) (xy 79.524086 -361.868238)
			(xy 79.449241 -361.856179) (xy 79.3761 -361.836233) (xy 79.305495 -361.808626) (xy 79.238224 -361.77367)
			(xy 79.175049 -361.731762) (xy 79.116687 -361.683376) (xy 79.063799 -361.62906) (xy 79.016984 -361.569431)
			(xy 78.976772 -361.505163) (xy 78.94362 -361.436986) (xy 78.917902 -361.36567) (xy 78.89991 -361.292025)
			(xy 78.889848 -361.216885) (xy 78.887829 -361.141101) (xy 77.771751 -361.141101) (xy 77.769732 -361.216885)
			(xy 77.75967 -361.292025) (xy 77.741678 -361.36567) (xy 77.71596 -361.436986) (xy 77.682808 -361.505163)
			(xy 77.642596 -361.569431) (xy 77.595781 -361.62906) (xy 77.542893 -361.683376) (xy 77.484531 -361.731762)
			(xy 77.421356 -361.77367) (xy 77.354085 -361.808626) (xy 77.28348 -361.836233) (xy 77.210339 -361.856179)
			(xy 77.135494 -361.868238) (xy 77.05979 -361.872273) (xy 76.984086 -361.868238) (xy 76.909241 -361.856179)
			(xy 76.8361 -361.836233) (xy 76.765495 -361.808626) (xy 76.698224 -361.77367) (xy 76.635049 -361.731762)
			(xy 76.576687 -361.683376) (xy 76.523799 -361.62906) (xy 76.476984 -361.569431) (xy 76.436772 -361.505163)
			(xy 76.40362 -361.436986) (xy 76.377902 -361.36567) (xy 76.35991 -361.292025) (xy 76.349848 -361.216885)
			(xy 76.347829 -361.141101) (xy 75.231751 -361.141101) (xy 75.229732 -361.216885) (xy 75.21967 -361.292025)
			(xy 75.201678 -361.36567) (xy 75.17596 -361.436986) (xy 75.142808 -361.505163) (xy 75.102596 -361.569431)
			(xy 75.055781 -361.62906) (xy 75.002893 -361.683376) (xy 74.944531 -361.731762) (xy 74.881356 -361.77367)
			(xy 74.814085 -361.808626) (xy 74.74348 -361.836233) (xy 74.670339 -361.856179) (xy 74.595494 -361.868238)
			(xy 74.51979 -361.872273) (xy 74.444086 -361.868238) (xy 74.369241 -361.856179) (xy 74.2961 -361.836233)
			(xy 74.225495 -361.808626) (xy 74.158224 -361.77367) (xy 74.095049 -361.731762) (xy 74.036687 -361.683376)
			(xy 73.983799 -361.62906) (xy 73.936984 -361.569431) (xy 73.896772 -361.505163) (xy 73.86362 -361.436986)
			(xy 73.837902 -361.36567) (xy 73.81991 -361.292025) (xy 73.809848 -361.216885) (xy 73.807829 -361.141101)
			(xy 72.691751 -361.141101) (xy 72.689732 -361.216885) (xy 72.67967 -361.292025) (xy 72.661678 -361.36567)
			(xy 72.63596 -361.436986) (xy 72.602808 -361.505163) (xy 72.562596 -361.569431) (xy 72.515781 -361.62906)
			(xy 72.462893 -361.683376) (xy 72.404531 -361.731762) (xy 72.341356 -361.77367) (xy 72.274085 -361.808626)
			(xy 72.20348 -361.836233) (xy 72.130339 -361.856179) (xy 72.055494 -361.868238) (xy 71.97979 -361.872273)
			(xy 71.904086 -361.868238) (xy 71.829241 -361.856179) (xy 71.7561 -361.836233) (xy 71.685495 -361.808626)
			(xy 71.618224 -361.77367) (xy 71.555049 -361.731762) (xy 71.496687 -361.683376) (xy 71.443799 -361.62906)
			(xy 71.396984 -361.569431) (xy 71.356772 -361.505163) (xy 71.32362 -361.436986) (xy 71.297902 -361.36567)
			(xy 71.27991 -361.292025) (xy 71.269848 -361.216885) (xy 71.267829 -361.141101) (xy 70.151751 -361.141101)
			(xy 70.149732 -361.216885) (xy 70.13967 -361.292025) (xy 70.121678 -361.36567) (xy 70.09596 -361.436986)
			(xy 70.062808 -361.505163) (xy 70.022596 -361.569431) (xy 69.975781 -361.62906) (xy 69.922893 -361.683376)
			(xy 69.864531 -361.731762) (xy 69.801356 -361.77367) (xy 69.734085 -361.808626) (xy 69.66348 -361.836233)
			(xy 69.590339 -361.856179) (xy 69.515494 -361.868238) (xy 69.43979 -361.872273) (xy 69.364086 -361.868238)
			(xy 69.289241 -361.856179) (xy 69.2161 -361.836233) (xy 69.145495 -361.808626) (xy 69.078224 -361.77367)
			(xy 69.015049 -361.731762) (xy 68.956687 -361.683376) (xy 68.903799 -361.62906) (xy 68.856984 -361.569431)
			(xy 68.816772 -361.505163) (xy 68.78362 -361.436986) (xy 68.757902 -361.36567) (xy 68.73991 -361.292025)
			(xy 68.729848 -361.216885) (xy 68.727829 -361.141101) (xy 67.611751 -361.141101) (xy 67.609732 -361.216885)
			(xy 67.59967 -361.292025) (xy 67.581678 -361.36567) (xy 67.55596 -361.436986) (xy 67.522808 -361.505163)
			(xy 67.482596 -361.569431) (xy 67.435781 -361.62906) (xy 67.382893 -361.683376) (xy 67.324531 -361.731762)
			(xy 67.261356 -361.77367) (xy 67.194085 -361.808626) (xy 67.12348 -361.836233) (xy 67.050339 -361.856179)
			(xy 66.975494 -361.868238) (xy 66.89979 -361.872273) (xy 66.824086 -361.868238) (xy 66.749241 -361.856179)
			(xy 66.6761 -361.836233) (xy 66.605495 -361.808626) (xy 66.538224 -361.77367) (xy 66.475049 -361.731762)
			(xy 66.416687 -361.683376) (xy 66.363799 -361.62906) (xy 66.316984 -361.569431) (xy 66.276772 -361.505163)
			(xy 66.24362 -361.436986) (xy 66.217902 -361.36567) (xy 66.19991 -361.292025) (xy 66.189848 -361.216885)
			(xy 66.187829 -361.141101) (xy 65.071751 -361.141101) (xy 65.069732 -361.216885) (xy 65.05967 -361.292025)
			(xy 65.041678 -361.36567) (xy 65.01596 -361.436986) (xy 64.982808 -361.505163) (xy 64.942596 -361.569431)
			(xy 64.895781 -361.62906) (xy 64.842893 -361.683376) (xy 64.784531 -361.731762) (xy 64.721356 -361.77367)
			(xy 64.654085 -361.808626) (xy 64.58348 -361.836233) (xy 64.510339 -361.856179) (xy 64.435494 -361.868238)
			(xy 64.35979 -361.872273) (xy 64.284086 -361.868238) (xy 64.209241 -361.856179) (xy 64.1361 -361.836233)
			(xy 64.065495 -361.808626) (xy 63.998224 -361.77367) (xy 63.935049 -361.731762) (xy 63.876687 -361.683376)
			(xy 63.823799 -361.62906) (xy 63.776984 -361.569431) (xy 63.736772 -361.505163) (xy 63.70362 -361.436986)
			(xy 63.677902 -361.36567) (xy 63.65991 -361.292025) (xy 63.649848 -361.216885) (xy 63.647829 -361.141101)
			(xy 42.47458 -361.141101) (xy 42.498128 -361.157249) (xy 42.589363 -361.229586) (xy 42.675374 -361.308064)
			(xy 42.755746 -361.392306) (xy 42.830096 -361.481909) (xy 42.898066 -361.576443) (xy 42.959331 -361.675454)
			(xy 43.013596 -361.778468) (xy 43.060602 -361.884991) (xy 43.100123 -361.994511) (xy 43.131969 -362.106504)
			(xy 43.155987 -362.220432) (xy 43.172064 -362.33575) (xy 43.180121 -362.451903) (xy 43.180119 -362.568336)
			(xy 43.17206 -362.684489) (xy 43.155981 -362.799807) (xy 43.131959 -362.913734) (xy 43.10011 -363.025726)
			(xy 43.063884 -363.126111) (xy 86.197949 -363.126111) (xy 86.203998 -363.050541) (xy 86.218045 -362.976043)
			(xy 86.239931 -362.90346) (xy 86.269408 -362.833614) (xy 86.306143 -362.767297) (xy 86.349718 -362.705261)
			(xy 86.39964 -362.648208) (xy 86.455344 -362.596784) (xy 86.516199 -362.551573) (xy 86.581514 -362.513086)
			(xy 86.65055 -362.48176) (xy 86.722525 -362.45795) (xy 86.796623 -362.441925) (xy 86.872004 -362.433866)
			(xy 86.90991 -362.433362) (xy 86.947816 -362.433866) (xy 87.023197 -362.441925) (xy 87.097295 -362.45795)
			(xy 87.16927 -362.48176) (xy 87.238306 -362.513086) (xy 87.303621 -362.551573) (xy 87.364476 -362.596784)
			(xy 87.42018 -362.648208) (xy 87.470102 -362.705261) (xy 87.513677 -362.767297) (xy 87.550412 -362.833614)
			(xy 87.579889 -362.90346) (xy 87.601775 -362.976043) (xy 87.615822 -363.050541) (xy 87.621871 -363.126111)
			(xy 88.737949 -363.126111) (xy 88.743998 -363.050541) (xy 88.758045 -362.976043) (xy 88.779931 -362.90346)
			(xy 88.809408 -362.833614) (xy 88.846143 -362.767297) (xy 88.889718 -362.705261) (xy 88.93964 -362.648208)
			(xy 88.995344 -362.596784) (xy 89.056199 -362.551573) (xy 89.121514 -362.513086) (xy 89.19055 -362.48176)
			(xy 89.262525 -362.45795) (xy 89.336623 -362.441925) (xy 89.412004 -362.433866) (xy 89.44991 -362.433362)
			(xy 89.487816 -362.433866) (xy 89.563197 -362.441925) (xy 89.637295 -362.45795) (xy 89.70927 -362.48176)
			(xy 89.778306 -362.513086) (xy 89.843621 -362.551573) (xy 89.904476 -362.596784) (xy 89.96018 -362.648208)
			(xy 90.010102 -362.705261) (xy 90.053677 -362.767297) (xy 90.090412 -362.833614) (xy 90.119889 -362.90346)
			(xy 90.141775 -362.976043) (xy 90.155822 -363.050541) (xy 90.161871 -363.126111) (xy 91.277949 -363.126111)
			(xy 91.283998 -363.050541) (xy 91.298045 -362.976043) (xy 91.319931 -362.90346) (xy 91.349408 -362.833614)
			(xy 91.386143 -362.767297) (xy 91.429718 -362.705261) (xy 91.47964 -362.648208) (xy 91.535344 -362.596784)
			(xy 91.596199 -362.551573) (xy 91.661514 -362.513086) (xy 91.73055 -362.48176) (xy 91.802525 -362.45795)
			(xy 91.876623 -362.441925) (xy 91.952004 -362.433866) (xy 91.98991 -362.433362) (xy 92.027816 -362.433866)
			(xy 92.103197 -362.441925) (xy 92.177295 -362.45795) (xy 92.24927 -362.48176) (xy 92.318306 -362.513086)
			(xy 92.383621 -362.551573) (xy 92.444476 -362.596784) (xy 92.50018 -362.648208) (xy 92.550102 -362.705261)
			(xy 92.593677 -362.767297) (xy 92.630412 -362.833614) (xy 92.659889 -362.90346) (xy 92.681775 -362.976043)
			(xy 92.695822 -363.050541) (xy 92.701871 -363.126111) (xy 92.699852 -363.201895) (xy 92.68979 -363.277035)
			(xy 92.671798 -363.35068) (xy 92.64608 -363.421996) (xy 92.612928 -363.490173) (xy 92.572716 -363.554441)
			(xy 92.525901 -363.61407) (xy 92.473013 -363.668386) (xy 92.414651 -363.716772) (xy 92.351476 -363.75868)
			(xy 92.284205 -363.793636) (xy 92.2136 -363.821243) (xy 92.177855 -363.830991) (xy 93.154757 -363.830991)
			(xy 93.160779 -363.714808) (xy 93.174802 -363.599317) (xy 93.19676 -363.485069) (xy 93.226547 -363.372608)
			(xy 93.264022 -363.26247) (xy 93.309007 -363.15518) (xy 93.361286 -363.051249) (xy 93.420611 -362.951173)
			(xy 93.486699 -362.855427) (xy 93.559235 -362.76447) (xy 93.637874 -362.678734) (xy 93.72224 -362.598627)
			(xy 93.811932 -362.524531) (xy 93.906522 -362.456801) (xy 94.00556 -362.395757) (xy 94.108573 -362.341692)
			(xy 94.21507 -362.294862) (xy 94.324545 -362.255491) (xy 94.436475 -362.223767) (xy 94.550327 -362.199841)
			(xy 94.665559 -362.183827) (xy 94.781621 -362.1758) (xy 94.83979 -362.175298) (xy 94.897959 -362.1758)
			(xy 95.014021 -362.183827) (xy 95.129253 -362.199841) (xy 95.243105 -362.223767) (xy 95.355035 -362.255491)
			(xy 95.46451 -362.294862) (xy 95.571007 -362.341692) (xy 95.67402 -362.395757) (xy 95.773058 -362.456801)
			(xy 95.867648 -362.524531) (xy 95.95734 -362.598627) (xy 96.041706 -362.678734) (xy 96.120345 -362.76447)
			(xy 96.192881 -362.855427) (xy 96.258969 -362.951173) (xy 96.318294 -363.051249) (xy 96.370573 -363.15518)
			(xy 96.415558 -363.26247) (xy 96.453033 -363.372608) (xy 96.48282 -363.485069) (xy 96.504778 -363.599317)
			(xy 96.518801 -363.714808) (xy 96.524823 -363.830991) (xy 96.522815 -363.947313) (xy 96.512786 -364.063219)
			(xy 96.494785 -364.178156) (xy 96.468897 -364.291579) (xy 96.435246 -364.402944) (xy 96.393992 -364.511723)
			(xy 96.345331 -364.617397) (xy 96.289495 -364.719461) (xy 96.226752 -364.81743) (xy 96.157398 -364.910837)
			(xy 96.081766 -364.999237) (xy 96.000215 -365.082208) (xy 95.913134 -365.159355) (xy 95.820938 -365.23031)
			(xy 95.724066 -365.294736) (xy 95.622981 -365.352325) (xy 95.518163 -365.402802) (xy 95.410112 -365.445928)
			(xy 95.299344 -365.481497) (xy 95.186385 -365.509339) (xy 95.071775 -365.529321) (xy 94.95606 -365.541348)
			(xy 94.83979 -365.545364) (xy 94.72352 -365.541348) (xy 94.607805 -365.529321) (xy 94.493195 -365.509339)
			(xy 94.380236 -365.481497) (xy 94.269468 -365.445928) (xy 94.161417 -365.402802) (xy 94.056599 -365.352325)
			(xy 93.955514 -365.294736) (xy 93.858642 -365.23031) (xy 93.766446 -365.159355) (xy 93.679365 -365.082208)
			(xy 93.597814 -364.999237) (xy 93.522182 -364.910837) (xy 93.452828 -364.81743) (xy 93.390085 -364.719461)
			(xy 93.334249 -364.617397) (xy 93.285588 -364.511723) (xy 93.244334 -364.402944) (xy 93.210683 -364.291579)
			(xy 93.184795 -364.178156) (xy 93.166794 -364.063219) (xy 93.156765 -363.947313) (xy 93.154757 -363.830991)
			(xy 92.177855 -363.830991) (xy 92.140459 -363.841189) (xy 92.065614 -363.853248) (xy 91.98991 -363.857283)
			(xy 91.914206 -363.853248) (xy 91.839361 -363.841189) (xy 91.76622 -363.821243) (xy 91.695615 -363.793636)
			(xy 91.628344 -363.75868) (xy 91.565169 -363.716772) (xy 91.506807 -363.668386) (xy 91.453919 -363.61407)
			(xy 91.407104 -363.554441) (xy 91.366892 -363.490173) (xy 91.33374 -363.421996) (xy 91.308022 -363.35068)
			(xy 91.29003 -363.277035) (xy 91.279968 -363.201895) (xy 91.277949 -363.126111) (xy 90.161871 -363.126111)
			(xy 90.159852 -363.201895) (xy 90.14979 -363.277035) (xy 90.131798 -363.35068) (xy 90.10608 -363.421996)
			(xy 90.072928 -363.490173) (xy 90.032716 -363.554441) (xy 89.985901 -363.61407) (xy 89.933013 -363.668386)
			(xy 89.874651 -363.716772) (xy 89.811476 -363.75868) (xy 89.744205 -363.793636) (xy 89.6736 -363.821243)
			(xy 89.600459 -363.841189) (xy 89.525614 -363.853248) (xy 89.44991 -363.857283) (xy 89.374206 -363.853248)
			(xy 89.299361 -363.841189) (xy 89.22622 -363.821243) (xy 89.155615 -363.793636) (xy 89.088344 -363.75868)
			(xy 89.025169 -363.716772) (xy 88.966807 -363.668386) (xy 88.913919 -363.61407) (xy 88.867104 -363.554441)
			(xy 88.826892 -363.490173) (xy 88.79374 -363.421996) (xy 88.768022 -363.35068) (xy 88.75003 -363.277035)
			(xy 88.739968 -363.201895) (xy 88.737949 -363.126111) (xy 87.621871 -363.126111) (xy 87.619852 -363.201895)
			(xy 87.60979 -363.277035) (xy 87.591798 -363.35068) (xy 87.56608 -363.421996) (xy 87.532928 -363.490173)
			(xy 87.492716 -363.554441) (xy 87.445901 -363.61407) (xy 87.393013 -363.668386) (xy 87.334651 -363.716772)
			(xy 87.271476 -363.75868) (xy 87.204205 -363.793636) (xy 87.1336 -363.821243) (xy 87.060459 -363.841189)
			(xy 86.985614 -363.853248) (xy 86.90991 -363.857283) (xy 86.834206 -363.853248) (xy 86.759361 -363.841189)
			(xy 86.68622 -363.821243) (xy 86.615615 -363.793636) (xy 86.548344 -363.75868) (xy 86.485169 -363.716772)
			(xy 86.426807 -363.668386) (xy 86.373919 -363.61407) (xy 86.327104 -363.554441) (xy 86.286892 -363.490173)
			(xy 86.25374 -363.421996) (xy 86.228022 -363.35068) (xy 86.21003 -363.277035) (xy 86.199968 -363.201895)
			(xy 86.197949 -363.126111) (xy 43.063884 -363.126111) (xy 43.060587 -363.135246) (xy 43.013579 -363.241767)
			(xy 42.959311 -363.34478) (xy 42.898045 -363.44379) (xy 42.830072 -363.538322) (xy 42.75572 -363.627923)
			(xy 42.675346 -363.712164) (xy 42.589333 -363.79064) (xy 42.52566 -363.841121) (xy 63.647829 -363.841121)
			(xy 63.653878 -363.765551) (xy 63.667925 -363.691053) (xy 63.689811 -363.61847) (xy 63.719288 -363.548624)
			(xy 63.756023 -363.482307) (xy 63.799598 -363.420271) (xy 63.84952 -363.363218) (xy 63.905224 -363.311794)
			(xy 63.966079 -363.266583) (xy 64.031394 -363.228096) (xy 64.10043 -363.19677) (xy 64.172405 -363.17296)
			(xy 64.246503 -363.156935) (xy 64.321884 -363.148876) (xy 64.35979 -363.148372) (xy 64.397696 -363.148876)
			(xy 64.473077 -363.156935) (xy 64.547175 -363.17296) (xy 64.61915 -363.19677) (xy 64.688186 -363.228096)
			(xy 64.753501 -363.266583) (xy 64.814356 -363.311794) (xy 64.87006 -363.363218) (xy 64.919982 -363.420271)
			(xy 64.963557 -363.482307) (xy 65.000292 -363.548624) (xy 65.029769 -363.61847) (xy 65.051655 -363.691053)
			(xy 65.065702 -363.765551) (xy 65.071751 -363.841121) (xy 66.187829 -363.841121) (xy 66.193878 -363.765551)
			(xy 66.207925 -363.691053) (xy 66.229811 -363.61847) (xy 66.259288 -363.548624) (xy 66.296023 -363.482307)
			(xy 66.339598 -363.420271) (xy 66.38952 -363.363218) (xy 66.445224 -363.311794) (xy 66.506079 -363.266583)
			(xy 66.571394 -363.228096) (xy 66.64043 -363.19677) (xy 66.712405 -363.17296) (xy 66.786503 -363.156935)
			(xy 66.861884 -363.148876) (xy 66.89979 -363.148372) (xy 66.937696 -363.148876) (xy 67.013077 -363.156935)
			(xy 67.087175 -363.17296) (xy 67.15915 -363.19677) (xy 67.228186 -363.228096) (xy 67.293501 -363.266583)
			(xy 67.354356 -363.311794) (xy 67.41006 -363.363218) (xy 67.459982 -363.420271) (xy 67.503557 -363.482307)
			(xy 67.540292 -363.548624) (xy 67.569769 -363.61847) (xy 67.591655 -363.691053) (xy 67.605702 -363.765551)
			(xy 67.611751 -363.841121) (xy 68.727829 -363.841121) (xy 68.733878 -363.765551) (xy 68.747925 -363.691053)
			(xy 68.769811 -363.61847) (xy 68.799288 -363.548624) (xy 68.836023 -363.482307) (xy 68.879598 -363.420271)
			(xy 68.92952 -363.363218) (xy 68.985224 -363.311794) (xy 69.046079 -363.266583) (xy 69.111394 -363.228096)
			(xy 69.18043 -363.19677) (xy 69.252405 -363.17296) (xy 69.326503 -363.156935) (xy 69.401884 -363.148876)
			(xy 69.43979 -363.148372) (xy 69.477696 -363.148876) (xy 69.553077 -363.156935) (xy 69.627175 -363.17296)
			(xy 69.69915 -363.19677) (xy 69.768186 -363.228096) (xy 69.833501 -363.266583) (xy 69.894356 -363.311794)
			(xy 69.95006 -363.363218) (xy 69.999982 -363.420271) (xy 70.043557 -363.482307) (xy 70.080292 -363.548624)
			(xy 70.109769 -363.61847) (xy 70.131655 -363.691053) (xy 70.145702 -363.765551) (xy 70.151751 -363.841121)
			(xy 71.267829 -363.841121) (xy 71.273878 -363.765551) (xy 71.287925 -363.691053) (xy 71.309811 -363.61847)
			(xy 71.339288 -363.548624) (xy 71.376023 -363.482307) (xy 71.419598 -363.420271) (xy 71.46952 -363.363218)
			(xy 71.525224 -363.311794) (xy 71.586079 -363.266583) (xy 71.651394 -363.228096) (xy 71.72043 -363.19677)
			(xy 71.792405 -363.17296) (xy 71.866503 -363.156935) (xy 71.941884 -363.148876) (xy 71.97979 -363.148372)
			(xy 72.017696 -363.148876) (xy 72.093077 -363.156935) (xy 72.167175 -363.17296) (xy 72.23915 -363.19677)
			(xy 72.308186 -363.228096) (xy 72.373501 -363.266583) (xy 72.434356 -363.311794) (xy 72.49006 -363.363218)
			(xy 72.539982 -363.420271) (xy 72.583557 -363.482307) (xy 72.620292 -363.548624) (xy 72.649769 -363.61847)
			(xy 72.671655 -363.691053) (xy 72.685702 -363.765551) (xy 72.691751 -363.841121) (xy 73.807829 -363.841121)
			(xy 73.813878 -363.765551) (xy 73.827925 -363.691053) (xy 73.849811 -363.61847) (xy 73.879288 -363.548624)
			(xy 73.916023 -363.482307) (xy 73.959598 -363.420271) (xy 74.00952 -363.363218) (xy 74.065224 -363.311794)
			(xy 74.126079 -363.266583) (xy 74.191394 -363.228096) (xy 74.26043 -363.19677) (xy 74.332405 -363.17296)
			(xy 74.406503 -363.156935) (xy 74.481884 -363.148876) (xy 74.51979 -363.148372) (xy 74.557696 -363.148876)
			(xy 74.633077 -363.156935) (xy 74.707175 -363.17296) (xy 74.77915 -363.19677) (xy 74.848186 -363.228096)
			(xy 74.913501 -363.266583) (xy 74.974356 -363.311794) (xy 75.03006 -363.363218) (xy 75.079982 -363.420271)
			(xy 75.123557 -363.482307) (xy 75.160292 -363.548624) (xy 75.189769 -363.61847) (xy 75.211655 -363.691053)
			(xy 75.225702 -363.765551) (xy 75.231751 -363.841121) (xy 76.347829 -363.841121) (xy 76.353878 -363.765551)
			(xy 76.367925 -363.691053) (xy 76.389811 -363.61847) (xy 76.419288 -363.548624) (xy 76.456023 -363.482307)
			(xy 76.499598 -363.420271) (xy 76.54952 -363.363218) (xy 76.605224 -363.311794) (xy 76.666079 -363.266583)
			(xy 76.731394 -363.228096) (xy 76.80043 -363.19677) (xy 76.872405 -363.17296) (xy 76.946503 -363.156935)
			(xy 77.021884 -363.148876) (xy 77.05979 -363.148372) (xy 77.097696 -363.148876) (xy 77.173077 -363.156935)
			(xy 77.247175 -363.17296) (xy 77.31915 -363.19677) (xy 77.388186 -363.228096) (xy 77.453501 -363.266583)
			(xy 77.514356 -363.311794) (xy 77.57006 -363.363218) (xy 77.619982 -363.420271) (xy 77.663557 -363.482307)
			(xy 77.700292 -363.548624) (xy 77.729769 -363.61847) (xy 77.751655 -363.691053) (xy 77.765702 -363.765551)
			(xy 77.771751 -363.841121) (xy 78.887829 -363.841121) (xy 78.893878 -363.765551) (xy 78.907925 -363.691053)
			(xy 78.929811 -363.61847) (xy 78.959288 -363.548624) (xy 78.996023 -363.482307) (xy 79.039598 -363.420271)
			(xy 79.08952 -363.363218) (xy 79.145224 -363.311794) (xy 79.206079 -363.266583) (xy 79.271394 -363.228096)
			(xy 79.34043 -363.19677) (xy 79.412405 -363.17296) (xy 79.486503 -363.156935) (xy 79.561884 -363.148876)
			(xy 79.59979 -363.148372) (xy 79.637696 -363.148876) (xy 79.713077 -363.156935) (xy 79.787175 -363.17296)
			(xy 79.85915 -363.19677) (xy 79.928186 -363.228096) (xy 79.993501 -363.266583) (xy 80.054356 -363.311794)
			(xy 80.11006 -363.363218) (xy 80.159982 -363.420271) (xy 80.203557 -363.482307) (xy 80.240292 -363.548624)
			(xy 80.269769 -363.61847) (xy 80.291655 -363.691053) (xy 80.305702 -363.765551) (xy 80.311751 -363.841121)
			(xy 81.427829 -363.841121) (xy 81.433878 -363.765551) (xy 81.447925 -363.691053) (xy 81.469811 -363.61847)
			(xy 81.499288 -363.548624) (xy 81.536023 -363.482307) (xy 81.579598 -363.420271) (xy 81.62952 -363.363218)
			(xy 81.685224 -363.311794) (xy 81.746079 -363.266583) (xy 81.811394 -363.228096) (xy 81.88043 -363.19677)
			(xy 81.952405 -363.17296) (xy 82.026503 -363.156935) (xy 82.101884 -363.148876) (xy 82.13979 -363.148372)
			(xy 82.177696 -363.148876) (xy 82.253077 -363.156935) (xy 82.327175 -363.17296) (xy 82.39915 -363.19677)
			(xy 82.468186 -363.228096) (xy 82.533501 -363.266583) (xy 82.594356 -363.311794) (xy 82.65006 -363.363218)
			(xy 82.699982 -363.420271) (xy 82.743557 -363.482307) (xy 82.780292 -363.548624) (xy 82.809769 -363.61847)
			(xy 82.831655 -363.691053) (xy 82.845702 -363.765551) (xy 82.851751 -363.841121) (xy 82.849732 -363.916905)
			(xy 82.83967 -363.992045) (xy 82.821678 -364.06569) (xy 82.79596 -364.137006) (xy 82.762808 -364.205183)
			(xy 82.722596 -364.269451) (xy 82.675781 -364.32908) (xy 82.622893 -364.383396) (xy 82.607556 -364.396111)
			(xy 84.927949 -364.396111) (xy 84.933998 -364.320541) (xy 84.948045 -364.246043) (xy 84.969931 -364.17346)
			(xy 84.999408 -364.103614) (xy 85.036143 -364.037297) (xy 85.079718 -363.975261) (xy 85.12964 -363.918208)
			(xy 85.185344 -363.866784) (xy 85.246199 -363.821573) (xy 85.311514 -363.783086) (xy 85.38055 -363.75176)
			(xy 85.452525 -363.72795) (xy 85.526623 -363.711925) (xy 85.602004 -363.703866) (xy 85.63991 -363.703362)
			(xy 85.677816 -363.703866) (xy 85.753197 -363.711925) (xy 85.827295 -363.72795) (xy 85.89927 -363.75176)
			(xy 85.968306 -363.783086) (xy 86.033621 -363.821573) (xy 86.094476 -363.866784) (xy 86.15018 -363.918208)
			(xy 86.200102 -363.975261) (xy 86.243677 -364.037297) (xy 86.280412 -364.103614) (xy 86.309889 -364.17346)
			(xy 86.331775 -364.246043) (xy 86.345822 -364.320541) (xy 86.351871 -364.396111) (xy 87.467949 -364.396111)
			(xy 87.473998 -364.320541) (xy 87.488045 -364.246043) (xy 87.509931 -364.17346) (xy 87.539408 -364.103614)
			(xy 87.576143 -364.037297) (xy 87.619718 -363.975261) (xy 87.66964 -363.918208) (xy 87.725344 -363.866784)
			(xy 87.786199 -363.821573) (xy 87.851514 -363.783086) (xy 87.92055 -363.75176) (xy 87.992525 -363.72795)
			(xy 88.066623 -363.711925) (xy 88.142004 -363.703866) (xy 88.17991 -363.703362) (xy 88.217816 -363.703866)
			(xy 88.293197 -363.711925) (xy 88.367295 -363.72795) (xy 88.43927 -363.75176) (xy 88.508306 -363.783086)
			(xy 88.573621 -363.821573) (xy 88.634476 -363.866784) (xy 88.69018 -363.918208) (xy 88.740102 -363.975261)
			(xy 88.783677 -364.037297) (xy 88.820412 -364.103614) (xy 88.849889 -364.17346) (xy 88.871775 -364.246043)
			(xy 88.885822 -364.320541) (xy 88.891871 -364.396111) (xy 90.007949 -364.396111) (xy 90.013998 -364.320541)
			(xy 90.028045 -364.246043) (xy 90.049931 -364.17346) (xy 90.079408 -364.103614) (xy 90.116143 -364.037297)
			(xy 90.159718 -363.975261) (xy 90.20964 -363.918208) (xy 90.265344 -363.866784) (xy 90.326199 -363.821573)
			(xy 90.391514 -363.783086) (xy 90.46055 -363.75176) (xy 90.532525 -363.72795) (xy 90.606623 -363.711925)
			(xy 90.682004 -363.703866) (xy 90.71991 -363.703362) (xy 90.757816 -363.703866) (xy 90.833197 -363.711925)
			(xy 90.907295 -363.72795) (xy 90.97927 -363.75176) (xy 91.048306 -363.783086) (xy 91.113621 -363.821573)
			(xy 91.174476 -363.866784) (xy 91.23018 -363.918208) (xy 91.280102 -363.975261) (xy 91.323677 -364.037297)
			(xy 91.360412 -364.103614) (xy 91.389889 -364.17346) (xy 91.411775 -364.246043) (xy 91.425822 -364.320541)
			(xy 91.431871 -364.396111) (xy 91.429852 -364.471895) (xy 91.41979 -364.547035) (xy 91.401798 -364.62068)
			(xy 91.37608 -364.691996) (xy 91.342928 -364.760173) (xy 91.302716 -364.824441) (xy 91.255901 -364.88407)
			(xy 91.203013 -364.938386) (xy 91.144651 -364.986772) (xy 91.081476 -365.02868) (xy 91.014205 -365.063636)
			(xy 90.9436 -365.091243) (xy 90.870459 -365.111189) (xy 90.795614 -365.123248) (xy 90.71991 -365.127283)
			(xy 90.644206 -365.123248) (xy 90.569361 -365.111189) (xy 90.49622 -365.091243) (xy 90.425615 -365.063636)
			(xy 90.358344 -365.02868) (xy 90.295169 -364.986772) (xy 90.236807 -364.938386) (xy 90.183919 -364.88407)
			(xy 90.137104 -364.824441) (xy 90.096892 -364.760173) (xy 90.06374 -364.691996) (xy 90.038022 -364.62068)
			(xy 90.02003 -364.547035) (xy 90.009968 -364.471895) (xy 90.007949 -364.396111) (xy 88.891871 -364.396111)
			(xy 88.889852 -364.471895) (xy 88.87979 -364.547035) (xy 88.861798 -364.62068) (xy 88.83608 -364.691996)
			(xy 88.802928 -364.760173) (xy 88.762716 -364.824441) (xy 88.715901 -364.88407) (xy 88.663013 -364.938386)
			(xy 88.604651 -364.986772) (xy 88.541476 -365.02868) (xy 88.474205 -365.063636) (xy 88.4036 -365.091243)
			(xy 88.330459 -365.111189) (xy 88.255614 -365.123248) (xy 88.17991 -365.127283) (xy 88.104206 -365.123248)
			(xy 88.029361 -365.111189) (xy 87.95622 -365.091243) (xy 87.885615 -365.063636) (xy 87.818344 -365.02868)
			(xy 87.755169 -364.986772) (xy 87.696807 -364.938386) (xy 87.643919 -364.88407) (xy 87.597104 -364.824441)
			(xy 87.556892 -364.760173) (xy 87.52374 -364.691996) (xy 87.498022 -364.62068) (xy 87.48003 -364.547035)
			(xy 87.469968 -364.471895) (xy 87.467949 -364.396111) (xy 86.351871 -364.396111) (xy 86.349852 -364.471895)
			(xy 86.33979 -364.547035) (xy 86.321798 -364.62068) (xy 86.29608 -364.691996) (xy 86.262928 -364.760173)
			(xy 86.222716 -364.824441) (xy 86.175901 -364.88407) (xy 86.123013 -364.938386) (xy 86.064651 -364.986772)
			(xy 86.001476 -365.02868) (xy 85.934205 -365.063636) (xy 85.8636 -365.091243) (xy 85.790459 -365.111189)
			(xy 85.715614 -365.123248) (xy 85.63991 -365.127283) (xy 85.564206 -365.123248) (xy 85.489361 -365.111189)
			(xy 85.41622 -365.091243) (xy 85.345615 -365.063636) (xy 85.278344 -365.02868) (xy 85.215169 -364.986772)
			(xy 85.156807 -364.938386) (xy 85.103919 -364.88407) (xy 85.057104 -364.824441) (xy 85.016892 -364.760173)
			(xy 84.98374 -364.691996) (xy 84.958022 -364.62068) (xy 84.94003 -364.547035) (xy 84.929968 -364.471895)
			(xy 84.927949 -364.396111) (xy 82.607556 -364.396111) (xy 82.564531 -364.431782) (xy 82.501356 -364.47369)
			(xy 82.434085 -364.508646) (xy 82.36348 -364.536253) (xy 82.290339 -364.556199) (xy 82.215494 -364.568258)
			(xy 82.13979 -364.572293) (xy 82.064086 -364.568258) (xy 81.989241 -364.556199) (xy 81.9161 -364.536253)
			(xy 81.845495 -364.508646) (xy 81.778224 -364.47369) (xy 81.715049 -364.431782) (xy 81.656687 -364.383396)
			(xy 81.603799 -364.32908) (xy 81.556984 -364.269451) (xy 81.516772 -364.205183) (xy 81.48362 -364.137006)
			(xy 81.457902 -364.06569) (xy 81.43991 -363.992045) (xy 81.429848 -363.916905) (xy 81.427829 -363.841121)
			(xy 80.311751 -363.841121) (xy 80.309732 -363.916905) (xy 80.29967 -363.992045) (xy 80.281678 -364.06569)
			(xy 80.25596 -364.137006) (xy 80.222808 -364.205183) (xy 80.182596 -364.269451) (xy 80.135781 -364.32908)
			(xy 80.082893 -364.383396) (xy 80.024531 -364.431782) (xy 79.961356 -364.47369) (xy 79.894085 -364.508646)
			(xy 79.82348 -364.536253) (xy 79.750339 -364.556199) (xy 79.675494 -364.568258) (xy 79.59979 -364.572293)
			(xy 79.524086 -364.568258) (xy 79.449241 -364.556199) (xy 79.3761 -364.536253) (xy 79.305495 -364.508646)
			(xy 79.238224 -364.47369) (xy 79.175049 -364.431782) (xy 79.116687 -364.383396) (xy 79.063799 -364.32908)
			(xy 79.016984 -364.269451) (xy 78.976772 -364.205183) (xy 78.94362 -364.137006) (xy 78.917902 -364.06569)
			(xy 78.89991 -363.992045) (xy 78.889848 -363.916905) (xy 78.887829 -363.841121) (xy 77.771751 -363.841121)
			(xy 77.769732 -363.916905) (xy 77.75967 -363.992045) (xy 77.741678 -364.06569) (xy 77.71596 -364.137006)
			(xy 77.682808 -364.205183) (xy 77.642596 -364.269451) (xy 77.595781 -364.32908) (xy 77.542893 -364.383396)
			(xy 77.484531 -364.431782) (xy 77.421356 -364.47369) (xy 77.354085 -364.508646) (xy 77.28348 -364.536253)
			(xy 77.210339 -364.556199) (xy 77.135494 -364.568258) (xy 77.05979 -364.572293) (xy 76.984086 -364.568258)
			(xy 76.909241 -364.556199) (xy 76.8361 -364.536253) (xy 76.765495 -364.508646) (xy 76.698224 -364.47369)
			(xy 76.635049 -364.431782) (xy 76.576687 -364.383396) (xy 76.523799 -364.32908) (xy 76.476984 -364.269451)
			(xy 76.436772 -364.205183) (xy 76.40362 -364.137006) (xy 76.377902 -364.06569) (xy 76.35991 -363.992045)
			(xy 76.349848 -363.916905) (xy 76.347829 -363.841121) (xy 75.231751 -363.841121) (xy 75.229732 -363.916905)
			(xy 75.21967 -363.992045) (xy 75.201678 -364.06569) (xy 75.17596 -364.137006) (xy 75.142808 -364.205183)
			(xy 75.102596 -364.269451) (xy 75.055781 -364.32908) (xy 75.002893 -364.383396) (xy 74.944531 -364.431782)
			(xy 74.881356 -364.47369) (xy 74.814085 -364.508646) (xy 74.74348 -364.536253) (xy 74.670339 -364.556199)
			(xy 74.595494 -364.568258) (xy 74.51979 -364.572293) (xy 74.444086 -364.568258) (xy 74.369241 -364.556199)
			(xy 74.2961 -364.536253) (xy 74.225495 -364.508646) (xy 74.158224 -364.47369) (xy 74.095049 -364.431782)
			(xy 74.036687 -364.383396) (xy 73.983799 -364.32908) (xy 73.936984 -364.269451) (xy 73.896772 -364.205183)
			(xy 73.86362 -364.137006) (xy 73.837902 -364.06569) (xy 73.81991 -363.992045) (xy 73.809848 -363.916905)
			(xy 73.807829 -363.841121) (xy 72.691751 -363.841121) (xy 72.689732 -363.916905) (xy 72.67967 -363.992045)
			(xy 72.661678 -364.06569) (xy 72.63596 -364.137006) (xy 72.602808 -364.205183) (xy 72.562596 -364.269451)
			(xy 72.515781 -364.32908) (xy 72.462893 -364.383396) (xy 72.404531 -364.431782) (xy 72.341356 -364.47369)
			(xy 72.274085 -364.508646) (xy 72.20348 -364.536253) (xy 72.130339 -364.556199) (xy 72.055494 -364.568258)
			(xy 71.97979 -364.572293) (xy 71.904086 -364.568258) (xy 71.829241 -364.556199) (xy 71.7561 -364.536253)
			(xy 71.685495 -364.508646) (xy 71.618224 -364.47369) (xy 71.555049 -364.431782) (xy 71.496687 -364.383396)
			(xy 71.443799 -364.32908) (xy 71.396984 -364.269451) (xy 71.356772 -364.205183) (xy 71.32362 -364.137006)
			(xy 71.297902 -364.06569) (xy 71.27991 -363.992045) (xy 71.269848 -363.916905) (xy 71.267829 -363.841121)
			(xy 70.151751 -363.841121) (xy 70.149732 -363.916905) (xy 70.13967 -363.992045) (xy 70.121678 -364.06569)
			(xy 70.09596 -364.137006) (xy 70.062808 -364.205183) (xy 70.022596 -364.269451) (xy 69.975781 -364.32908)
			(xy 69.922893 -364.383396) (xy 69.864531 -364.431782) (xy 69.801356 -364.47369) (xy 69.734085 -364.508646)
			(xy 69.66348 -364.536253) (xy 69.590339 -364.556199) (xy 69.515494 -364.568258) (xy 69.43979 -364.572293)
			(xy 69.364086 -364.568258) (xy 69.289241 -364.556199) (xy 69.2161 -364.536253) (xy 69.145495 -364.508646)
			(xy 69.078224 -364.47369) (xy 69.015049 -364.431782) (xy 68.956687 -364.383396) (xy 68.903799 -364.32908)
			(xy 68.856984 -364.269451) (xy 68.816772 -364.205183) (xy 68.78362 -364.137006) (xy 68.757902 -364.06569)
			(xy 68.73991 -363.992045) (xy 68.729848 -363.916905) (xy 68.727829 -363.841121) (xy 67.611751 -363.841121)
			(xy 67.609732 -363.916905) (xy 67.59967 -363.992045) (xy 67.581678 -364.06569) (xy 67.55596 -364.137006)
			(xy 67.522808 -364.205183) (xy 67.482596 -364.269451) (xy 67.435781 -364.32908) (xy 67.382893 -364.383396)
			(xy 67.324531 -364.431782) (xy 67.261356 -364.47369) (xy 67.194085 -364.508646) (xy 67.12348 -364.536253)
			(xy 67.050339 -364.556199) (xy 66.975494 -364.568258) (xy 66.89979 -364.572293) (xy 66.824086 -364.568258)
			(xy 66.749241 -364.556199) (xy 66.6761 -364.536253) (xy 66.605495 -364.508646) (xy 66.538224 -364.47369)
			(xy 66.475049 -364.431782) (xy 66.416687 -364.383396) (xy 66.363799 -364.32908) (xy 66.316984 -364.269451)
			(xy 66.276772 -364.205183) (xy 66.24362 -364.137006) (xy 66.217902 -364.06569) (xy 66.19991 -363.992045)
			(xy 66.189848 -363.916905) (xy 66.187829 -363.841121) (xy 65.071751 -363.841121) (xy 65.069732 -363.916905)
			(xy 65.05967 -363.992045) (xy 65.041678 -364.06569) (xy 65.01596 -364.137006) (xy 64.982808 -364.205183)
			(xy 64.942596 -364.269451) (xy 64.895781 -364.32908) (xy 64.842893 -364.383396) (xy 64.784531 -364.431782)
			(xy 64.721356 -364.47369) (xy 64.654085 -364.508646) (xy 64.58348 -364.536253) (xy 64.510339 -364.556199)
			(xy 64.435494 -364.568258) (xy 64.35979 -364.572293) (xy 64.284086 -364.568258) (xy 64.209241 -364.556199)
			(xy 64.1361 -364.536253) (xy 64.065495 -364.508646) (xy 63.998224 -364.47369) (xy 63.935049 -364.431782)
			(xy 63.876687 -364.383396) (xy 63.823799 -364.32908) (xy 63.776984 -364.269451) (xy 63.736772 -364.205183)
			(xy 63.70362 -364.137006) (xy 63.677902 -364.06569) (xy 63.65991 -363.992045) (xy 63.649848 -363.916905)
			(xy 63.647829 -363.841121) (xy 42.52566 -363.841121) (xy 42.498096 -363.862974) (xy 42.402071 -363.928821)
			(xy 42.30172 -363.987865) (xy 42.197522 -364.039821) (xy 42.089979 -364.084442) (xy 41.979605 -364.121513)
			(xy 41.866931 -364.150856) (xy 41.752495 -364.17233) (xy 41.636848 -364.185833) (xy 41.520544 -364.1913)
			(xy 41.40414 -364.188705) (xy 41.288195 -364.178059) (xy 41.173265 -364.159415) (xy 41.059901 -364.132861)
			(xy 40.948646 -364.098525) (xy 40.840034 -364.056571) (xy 40.734587 -364.007202) (xy 40.632809 -363.950652)
			(xy 40.535189 -363.887194) (xy 40.442194 -363.817133) (xy 40.397938 -363.779308) (xy 40.38075 -363.76503)
			(xy 40.342391 -363.742121) (xy 40.300617 -363.726275) (xy 40.256715 -363.717979) (xy 40.212038 -363.717489)
			(xy 40.167965 -363.724822) (xy 40.125853 -363.739749) (xy 40.087002 -363.761813) (xy 40.052608 -363.790331)
			(xy 40.023733 -363.824425) (xy 40.001265 -363.863044) (xy 39.985899 -363.904998) (xy 39.978107 -363.948992)
			(xy 39.977568 -363.971332) (xy 39.977568 -367.89868) (xy 39.97808 -367.922321) (xy 39.986808 -367.968791)
			(xy 40.003983 -368.012843) (xy 40.029014 -368.052957) (xy 40.061036 -368.087745) (xy 40.098942 -368.116007)
			(xy 40.141423 -368.136767) (xy 40.187012 -368.149307) (xy 40.234134 -368.153195) (xy 40.281162 -368.148295)
			(xy 40.303958 -368.142012) (xy 40.333264 -368.133792) (xy 40.393381 -368.124278) (xy 40.454229 -368.122815)
			(xy 40.514733 -368.129427) (xy 40.573829 -368.143999) (xy 40.630472 -368.166274) (xy 40.683663 -368.195858)
			(xy 40.732466 -368.23223) (xy 40.776018 -368.274748) (xy 40.813552 -368.322662) (xy 40.844405 -368.375128)
			(xy 40.868034 -368.431219) (xy 40.884022 -368.489947) (xy 40.892086 -368.550276) (xy 40.892085 -368.611141)
			(xy 40.884018 -368.67147) (xy 40.868029 -368.730197) (xy 40.844397 -368.786287) (xy 40.813542 -368.838752)
			(xy 40.776006 -368.886665) (xy 40.732453 -368.929181) (xy 40.683649 -368.965551) (xy 40.630456 -368.995133)
			(xy 40.573812 -369.017406) (xy 40.514717 -369.031976) (xy 40.454211 -369.038586) (xy 40.393364 -369.03712)
			(xy 40.333247 -369.027604) (xy 40.303958 -369.019328) (xy 40.281158 -369.013096) (xy 40.234148 -369.008239)
			(xy 40.18705 -369.012154) (xy 40.141488 -369.024708) (xy 40.099031 -369.045467) (xy 40.061143 -369.073717)
			(xy 40.02913 -369.108483) (xy 40.004094 -369.148568) (xy 39.986899 -369.192589) (xy 39.978138 -369.23903)
			(xy 39.977568 -369.26266) (xy 39.977568 -370.642743) (xy 73.760322 -370.642743) (xy 73.760322 -370.571421)
			(xy 73.768308 -370.500547) (xy 73.784178 -370.431012) (xy 73.807735 -370.363692) (xy 73.83868 -370.299433)
			(xy 73.876626 -370.239042) (xy 73.921095 -370.18328) (xy 73.971528 -370.132847) (xy 74.02729 -370.088378)
			(xy 74.087681 -370.050432) (xy 74.15194 -370.019487) (xy 74.21926 -369.99593) (xy 74.288795 -369.98006)
			(xy 74.359669 -369.972074) (xy 74.39533 -369.971574) (xy 74.430991 -369.972074) (xy 74.501865 -369.98006)
			(xy 74.5714 -369.99593) (xy 74.63872 -370.019487) (xy 74.702979 -370.050432) (xy 74.76337 -370.088378)
			(xy 74.819132 -370.132847) (xy 74.869565 -370.18328) (xy 74.914034 -370.239042) (xy 74.95198 -370.299433)
			(xy 74.982925 -370.363692) (xy 75.006482 -370.431012) (xy 75.022352 -370.500547) (xy 75.030338 -370.571421)
			(xy 75.030338 -370.642743) (xy 75.835756 -370.642743) (xy 75.835756 -370.571421) (xy 75.843742 -370.500547)
			(xy 75.859612 -370.431012) (xy 75.883169 -370.363692) (xy 75.914114 -370.299433) (xy 75.95206 -370.239042)
			(xy 75.996529 -370.18328) (xy 76.046962 -370.132847) (xy 76.102724 -370.088378) (xy 76.163115 -370.050432)
			(xy 76.227374 -370.019487) (xy 76.294694 -369.99593) (xy 76.364229 -369.98006) (xy 76.435103 -369.972074)
			(xy 76.470764 -369.971574) (xy 76.506425 -369.972074) (xy 76.577299 -369.98006) (xy 76.646834 -369.99593)
			(xy 76.714154 -370.019487) (xy 76.778413 -370.050432) (xy 76.838804 -370.088378) (xy 76.894566 -370.132847)
			(xy 76.944999 -370.18328) (xy 76.989468 -370.239042) (xy 77.027414 -370.299433) (xy 77.058359 -370.363692)
			(xy 77.081916 -370.431012) (xy 77.097786 -370.500547) (xy 77.105772 -370.571421) (xy 77.105772 -370.642743)
			(xy 77.105686 -370.643505) (xy 78.060034 -370.643505) (xy 78.060034 -370.572183) (xy 78.06802 -370.501309)
			(xy 78.08389 -370.431774) (xy 78.107447 -370.364454) (xy 78.138392 -370.300195) (xy 78.176338 -370.239804)
			(xy 78.220807 -370.184042) (xy 78.27124 -370.133609) (xy 78.327002 -370.08914) (xy 78.387393 -370.051194)
			(xy 78.451652 -370.020249) (xy 78.518972 -369.996692) (xy 78.588507 -369.980822) (xy 78.659381 -369.972836)
			(xy 78.695042 -369.972336) (xy 78.730703 -369.972836) (xy 78.801577 -369.980822) (xy 78.871112 -369.996692)
			(xy 78.938432 -370.020249) (xy 79.002691 -370.051194) (xy 79.063082 -370.08914) (xy 79.118844 -370.133609)
			(xy 79.169277 -370.184042) (xy 79.213746 -370.239804) (xy 79.251692 -370.300195) (xy 79.282637 -370.364454)
			(xy 79.306194 -370.431774) (xy 79.322064 -370.501309) (xy 79.33005 -370.572183) (xy 79.33005 -370.643505)
			(xy 79.322064 -370.714379) (xy 79.306194 -370.783914) (xy 79.282637 -370.851234) (xy 79.251692 -370.915493)
			(xy 79.213746 -370.975884) (xy 79.169277 -371.031646) (xy 79.118844 -371.082079) (xy 79.063082 -371.126548)
			(xy 79.002691 -371.164494) (xy 78.938432 -371.195439) (xy 78.871112 -371.218996) (xy 78.801577 -371.234866)
			(xy 78.730703 -371.242852) (xy 78.659381 -371.242852) (xy 78.588507 -371.234866) (xy 78.518972 -371.218996)
			(xy 78.451652 -371.195439) (xy 78.387393 -371.164494) (xy 78.327002 -371.126548) (xy 78.27124 -371.082079)
			(xy 78.220807 -371.031646) (xy 78.176338 -370.975884) (xy 78.138392 -370.915493) (xy 78.107447 -370.851234)
			(xy 78.08389 -370.783914) (xy 78.06802 -370.714379) (xy 78.060034 -370.643505) (xy 77.105686 -370.643505)
			(xy 77.097786 -370.713617) (xy 77.081916 -370.783152) (xy 77.058359 -370.850472) (xy 77.027414 -370.914731)
			(xy 76.989468 -370.975122) (xy 76.944999 -371.030884) (xy 76.894566 -371.081317) (xy 76.838804 -371.125786)
			(xy 76.778413 -371.163732) (xy 76.714154 -371.194677) (xy 76.646834 -371.218234) (xy 76.577299 -371.234104)
			(xy 76.506425 -371.24209) (xy 76.435103 -371.24209) (xy 76.364229 -371.234104) (xy 76.294694 -371.218234)
			(xy 76.227374 -371.194677) (xy 76.163115 -371.163732) (xy 76.102724 -371.125786) (xy 76.046962 -371.081317)
			(xy 75.996529 -371.030884) (xy 75.95206 -370.975122) (xy 75.914114 -370.914731) (xy 75.883169 -370.850472)
			(xy 75.859612 -370.783152) (xy 75.843742 -370.713617) (xy 75.835756 -370.642743) (xy 75.030338 -370.642743)
			(xy 75.022352 -370.713617) (xy 75.006482 -370.783152) (xy 74.982925 -370.850472) (xy 74.95198 -370.914731)
			(xy 74.914034 -370.975122) (xy 74.869565 -371.030884) (xy 74.819132 -371.081317) (xy 74.76337 -371.125786)
			(xy 74.702979 -371.163732) (xy 74.63872 -371.194677) (xy 74.5714 -371.218234) (xy 74.501865 -371.234104)
			(xy 74.430991 -371.24209) (xy 74.359669 -371.24209) (xy 74.288795 -371.234104) (xy 74.21926 -371.218234)
			(xy 74.15194 -371.194677) (xy 74.087681 -371.163732) (xy 74.02729 -371.125786) (xy 73.971528 -371.081317)
			(xy 73.921095 -371.030884) (xy 73.876626 -370.975122) (xy 73.83868 -370.914731) (xy 73.807735 -370.850472)
			(xy 73.784178 -370.783152) (xy 73.768308 -370.713617) (xy 73.760322 -370.642743) (xy 39.977568 -370.642743)
			(xy 39.977568 -372.399407) (xy 73.760322 -372.399407) (xy 73.760322 -372.328085) (xy 73.768308 -372.257211)
			(xy 73.784178 -372.187676) (xy 73.807735 -372.120356) (xy 73.83868 -372.056097) (xy 73.876626 -371.995706)
			(xy 73.921095 -371.939944) (xy 73.971528 -371.889511) (xy 74.02729 -371.845042) (xy 74.087681 -371.807096)
			(xy 74.15194 -371.776151) (xy 74.21926 -371.752594) (xy 74.288795 -371.736724) (xy 74.359669 -371.728738)
			(xy 74.39533 -371.728238) (xy 74.430991 -371.728738) (xy 74.501865 -371.736724) (xy 74.5714 -371.752594)
			(xy 74.63872 -371.776151) (xy 74.702979 -371.807096) (xy 74.76337 -371.845042) (xy 74.819132 -371.889511)
			(xy 74.869565 -371.939944) (xy 74.914034 -371.995706) (xy 74.95198 -372.056097) (xy 74.982925 -372.120356)
			(xy 75.006482 -372.187676) (xy 75.022352 -372.257211) (xy 75.030338 -372.328085) (xy 75.030338 -372.399407)
			(xy 75.835756 -372.399407) (xy 75.835756 -372.328085) (xy 75.843742 -372.257211) (xy 75.859612 -372.187676)
			(xy 75.883169 -372.120356) (xy 75.914114 -372.056097) (xy 75.95206 -371.995706) (xy 75.996529 -371.939944)
			(xy 76.046962 -371.889511) (xy 76.102724 -371.845042) (xy 76.163115 -371.807096) (xy 76.227374 -371.776151)
			(xy 76.294694 -371.752594) (xy 76.364229 -371.736724) (xy 76.435103 -371.728738) (xy 76.470764 -371.728238)
			(xy 76.506425 -371.728738) (xy 76.577299 -371.736724) (xy 76.646834 -371.752594) (xy 76.714154 -371.776151)
			(xy 76.778413 -371.807096) (xy 76.838804 -371.845042) (xy 76.894566 -371.889511) (xy 76.944999 -371.939944)
			(xy 76.989468 -371.995706) (xy 77.027414 -372.056097) (xy 77.058359 -372.120356) (xy 77.081916 -372.187676)
			(xy 77.097786 -372.257211) (xy 77.105772 -372.328085) (xy 77.105772 -372.399407) (xy 77.105686 -372.400169)
			(xy 78.060034 -372.400169) (xy 78.060034 -372.328847) (xy 78.06802 -372.257973) (xy 78.08389 -372.188438)
			(xy 78.107447 -372.121118) (xy 78.138392 -372.056859) (xy 78.176338 -371.996468) (xy 78.220807 -371.940706)
			(xy 78.27124 -371.890273) (xy 78.327002 -371.845804) (xy 78.387393 -371.807858) (xy 78.451652 -371.776913)
			(xy 78.518972 -371.753356) (xy 78.588507 -371.737486) (xy 78.659381 -371.7295) (xy 78.695042 -371.729)
			(xy 78.730703 -371.7295) (xy 78.801577 -371.737486) (xy 78.871112 -371.753356) (xy 78.938432 -371.776913)
			(xy 79.002691 -371.807858) (xy 79.063082 -371.845804) (xy 79.118844 -371.890273) (xy 79.169277 -371.940706)
			(xy 79.213746 -371.996468) (xy 79.251692 -372.056859) (xy 79.282637 -372.121118) (xy 79.306194 -372.188438)
			(xy 79.322064 -372.257973) (xy 79.33005 -372.328847) (xy 79.33005 -372.400169) (xy 79.322064 -372.471043)
			(xy 79.306194 -372.540578) (xy 79.282637 -372.607898) (xy 79.251692 -372.672157) (xy 79.213746 -372.732548)
			(xy 79.169277 -372.78831) (xy 79.118844 -372.838743) (xy 79.063082 -372.883212) (xy 79.002691 -372.921158)
			(xy 78.938432 -372.952103) (xy 78.871112 -372.97566) (xy 78.801577 -372.99153) (xy 78.730703 -372.999516)
			(xy 78.659381 -372.999516) (xy 78.588507 -372.99153) (xy 78.518972 -372.97566) (xy 78.451652 -372.952103)
			(xy 78.387393 -372.921158) (xy 78.327002 -372.883212) (xy 78.27124 -372.838743) (xy 78.220807 -372.78831)
			(xy 78.176338 -372.732548) (xy 78.138392 -372.672157) (xy 78.107447 -372.607898) (xy 78.08389 -372.540578)
			(xy 78.06802 -372.471043) (xy 78.060034 -372.400169) (xy 77.105686 -372.400169) (xy 77.097786 -372.470281)
			(xy 77.081916 -372.539816) (xy 77.058359 -372.607136) (xy 77.027414 -372.671395) (xy 76.989468 -372.731786)
			(xy 76.944999 -372.787548) (xy 76.894566 -372.837981) (xy 76.838804 -372.88245) (xy 76.778413 -372.920396)
			(xy 76.714154 -372.951341) (xy 76.646834 -372.974898) (xy 76.577299 -372.990768) (xy 76.506425 -372.998754)
			(xy 76.435103 -372.998754) (xy 76.364229 -372.990768) (xy 76.294694 -372.974898) (xy 76.227374 -372.951341)
			(xy 76.163115 -372.920396) (xy 76.102724 -372.88245) (xy 76.046962 -372.837981) (xy 75.996529 -372.787548)
			(xy 75.95206 -372.731786) (xy 75.914114 -372.671395) (xy 75.883169 -372.607136) (xy 75.859612 -372.539816)
			(xy 75.843742 -372.470281) (xy 75.835756 -372.399407) (xy 75.030338 -372.399407) (xy 75.022352 -372.470281)
			(xy 75.006482 -372.539816) (xy 74.982925 -372.607136) (xy 74.95198 -372.671395) (xy 74.914034 -372.731786)
			(xy 74.869565 -372.787548) (xy 74.819132 -372.837981) (xy 74.76337 -372.88245) (xy 74.702979 -372.920396)
			(xy 74.63872 -372.951341) (xy 74.5714 -372.974898) (xy 74.501865 -372.990768) (xy 74.430991 -372.998754)
			(xy 74.359669 -372.998754) (xy 74.288795 -372.990768) (xy 74.21926 -372.974898) (xy 74.15194 -372.951341)
			(xy 74.087681 -372.920396) (xy 74.02729 -372.88245) (xy 73.971528 -372.837981) (xy 73.921095 -372.787548)
			(xy 73.876626 -372.731786) (xy 73.83868 -372.671395) (xy 73.807735 -372.607136) (xy 73.784178 -372.539816)
			(xy 73.768308 -372.470281) (xy 73.760322 -372.399407) (xy 39.977568 -372.399407) (xy 39.977568 -373.61114)
			(xy 50.797968 -373.61114) (xy 52.449476 -373.61114) (xy 52.449476 -374.165977) (xy 73.760322 -374.165977)
			(xy 73.760322 -374.094655) (xy 73.768308 -374.023781) (xy 73.784178 -373.954246) (xy 73.807735 -373.886926)
			(xy 73.83868 -373.822667) (xy 73.876626 -373.762276) (xy 73.921095 -373.706514) (xy 73.971528 -373.656081)
			(xy 74.02729 -373.611612) (xy 74.087681 -373.573666) (xy 74.15194 -373.542721) (xy 74.21926 -373.519164)
			(xy 74.288795 -373.503294) (xy 74.359669 -373.495308) (xy 74.39533 -373.494808) (xy 74.430991 -373.495308)
			(xy 74.501865 -373.503294) (xy 74.5714 -373.519164) (xy 74.63872 -373.542721) (xy 74.702979 -373.573666)
			(xy 74.76337 -373.611612) (xy 74.819132 -373.656081) (xy 74.869565 -373.706514) (xy 74.914034 -373.762276)
			(xy 74.95198 -373.822667) (xy 74.982925 -373.886926) (xy 75.006482 -373.954246) (xy 75.022352 -374.023781)
			(xy 75.030338 -374.094655) (xy 75.030338 -374.165977) (xy 75.835756 -374.165977) (xy 75.835756 -374.094655)
			(xy 75.843742 -374.023781) (xy 75.859612 -373.954246) (xy 75.883169 -373.886926) (xy 75.914114 -373.822667)
			(xy 75.95206 -373.762276) (xy 75.996529 -373.706514) (xy 76.046962 -373.656081) (xy 76.102724 -373.611612)
			(xy 76.163115 -373.573666) (xy 76.227374 -373.542721) (xy 76.294694 -373.519164) (xy 76.364229 -373.503294)
			(xy 76.435103 -373.495308) (xy 76.470764 -373.494808) (xy 76.506425 -373.495308) (xy 76.577299 -373.503294)
			(xy 76.646834 -373.519164) (xy 76.714154 -373.542721) (xy 76.778413 -373.573666) (xy 76.838804 -373.611612)
			(xy 76.894566 -373.656081) (xy 76.944999 -373.706514) (xy 76.989468 -373.762276) (xy 77.027414 -373.822667)
			(xy 77.058359 -373.886926) (xy 77.081916 -373.954246) (xy 77.097786 -374.023781) (xy 77.105772 -374.094655)
			(xy 77.105772 -374.165977) (xy 77.105686 -374.166739) (xy 78.060034 -374.166739) (xy 78.060034 -374.095417)
			(xy 78.06802 -374.024543) (xy 78.08389 -373.955008) (xy 78.107447 -373.887688) (xy 78.138392 -373.823429)
			(xy 78.176338 -373.763038) (xy 78.220807 -373.707276) (xy 78.27124 -373.656843) (xy 78.327002 -373.612374)
			(xy 78.387393 -373.574428) (xy 78.451652 -373.543483) (xy 78.518972 -373.519926) (xy 78.588507 -373.504056)
			(xy 78.659381 -373.49607) (xy 78.695042 -373.49557) (xy 78.730703 -373.49607) (xy 78.801577 -373.504056)
			(xy 78.871112 -373.519926) (xy 78.938432 -373.543483) (xy 79.002691 -373.574428) (xy 79.063082 -373.612374)
			(xy 79.118844 -373.656843) (xy 79.169277 -373.707276) (xy 79.213746 -373.763038) (xy 79.251692 -373.823429)
			(xy 79.282637 -373.887688) (xy 79.306194 -373.955008) (xy 79.322064 -374.024543) (xy 79.33005 -374.095417)
			(xy 79.33005 -374.166739) (xy 79.322064 -374.237613) (xy 79.306194 -374.307148) (xy 79.282637 -374.374468)
			(xy 79.251692 -374.438727) (xy 79.213746 -374.499118) (xy 79.169277 -374.55488) (xy 79.118844 -374.605313)
			(xy 79.063082 -374.649782) (xy 79.002691 -374.687728) (xy 78.938432 -374.718673) (xy 78.871112 -374.74223)
			(xy 78.801577 -374.7581) (xy 78.730703 -374.766086) (xy 78.659381 -374.766086) (xy 78.588507 -374.7581)
			(xy 78.518972 -374.74223) (xy 78.451652 -374.718673) (xy 78.387393 -374.687728) (xy 78.327002 -374.649782)
			(xy 78.27124 -374.605313) (xy 78.220807 -374.55488) (xy 78.176338 -374.499118) (xy 78.138392 -374.438727)
			(xy 78.107447 -374.374468) (xy 78.08389 -374.307148) (xy 78.06802 -374.237613) (xy 78.060034 -374.166739)
			(xy 77.105686 -374.166739) (xy 77.097786 -374.236851) (xy 77.081916 -374.306386) (xy 77.058359 -374.373706)
			(xy 77.027414 -374.437965) (xy 76.989468 -374.498356) (xy 76.944999 -374.554118) (xy 76.894566 -374.604551)
			(xy 76.838804 -374.64902) (xy 76.778413 -374.686966) (xy 76.714154 -374.717911) (xy 76.646834 -374.741468)
			(xy 76.577299 -374.757338) (xy 76.506425 -374.765324) (xy 76.435103 -374.765324) (xy 76.364229 -374.757338)
			(xy 76.294694 -374.741468) (xy 76.227374 -374.717911) (xy 76.163115 -374.686966) (xy 76.102724 -374.64902)
			(xy 76.046962 -374.604551) (xy 75.996529 -374.554118) (xy 75.95206 -374.498356) (xy 75.914114 -374.437965)
			(xy 75.883169 -374.373706) (xy 75.859612 -374.306386) (xy 75.843742 -374.236851) (xy 75.835756 -374.165977)
			(xy 75.030338 -374.165977) (xy 75.022352 -374.236851) (xy 75.006482 -374.306386) (xy 74.982925 -374.373706)
			(xy 74.95198 -374.437965) (xy 74.914034 -374.498356) (xy 74.869565 -374.554118) (xy 74.819132 -374.604551)
			(xy 74.76337 -374.64902) (xy 74.702979 -374.686966) (xy 74.63872 -374.717911) (xy 74.5714 -374.741468)
			(xy 74.501865 -374.757338) (xy 74.430991 -374.765324) (xy 74.359669 -374.765324) (xy 74.288795 -374.757338)
			(xy 74.21926 -374.741468) (xy 74.15194 -374.717911) (xy 74.087681 -374.686966) (xy 74.02729 -374.64902)
			(xy 73.971528 -374.604551) (xy 73.921095 -374.554118) (xy 73.876626 -374.498356) (xy 73.83868 -374.437965)
			(xy 73.807735 -374.373706) (xy 73.784178 -374.306386) (xy 73.768308 -374.236851) (xy 73.760322 -374.165977)
			(xy 52.449476 -374.165977) (xy 52.449476 -375.263156) (xy 50.797968 -375.263156) (xy 50.797968 -373.61114)
			(xy 39.977568 -373.61114) (xy 39.977568 -374.589548) (xy 39.978033 -374.61157) (xy 39.985621 -374.654956)
			(xy 40.000577 -374.696382) (xy 40.022454 -374.734609) (xy 40.050595 -374.76849) (xy 40.084159 -374.797009)
			(xy 40.122138 -374.819313) (xy 40.163395 -374.834732) (xy 40.206693 -374.842805) (xy 40.250734 -374.843289)
			(xy 40.294199 -374.83617) (xy 40.315134 -374.829324) (xy 40.341986 -374.82049) (xy 40.397519 -374.809934)
			(xy 40.454002 -374.807688) (xy 40.510198 -374.8138) (xy 40.564877 -374.828139) (xy 40.616841 -374.850388)
			(xy 40.664954 -374.880061) (xy 40.708161 -374.91651) (xy 40.745517 -374.958934) (xy 40.776205 -375.006407)
			(xy 40.799551 -375.057888) (xy 40.815045 -375.11225) (xy 40.822349 -375.168304) (xy 40.821301 -375.224821)
			(xy 40.811925 -375.280566) (xy 40.794426 -375.334316) (xy 40.769187 -375.384896) (xy 40.736762 -375.431199)
			(xy 40.697858 -375.47221) (xy 40.65333 -375.507031) (xy 40.60415 -375.534901) (xy 40.551397 -375.555209)
			(xy 40.523922 -375.56186) (xy 40.501951 -375.567276) (xy 40.46024 -375.584807) (xy 40.422292 -375.609448)
			(xy 40.389309 -375.640421) (xy 40.362332 -375.676745) (xy 40.342215 -375.717273) (xy 40.329593 -375.760723)
			(xy 40.324867 -375.805721) (xy 40.328184 -375.850845) (xy 40.339441 -375.894669) (xy 40.358281 -375.935806)
			(xy 40.384108 -375.972956) (xy 40.391586 -375.980807) (xy 73.714602 -375.980807) (xy 73.714602 -375.909485)
			(xy 73.722588 -375.838611) (xy 73.738458 -375.769076) (xy 73.762015 -375.701756) (xy 73.79296 -375.637497)
			(xy 73.830906 -375.577106) (xy 73.875375 -375.521344) (xy 73.925808 -375.470911) (xy 73.98157 -375.426442)
			(xy 74.041961 -375.388496) (xy 74.10622 -375.357551) (xy 74.17354 -375.333994) (xy 74.243075 -375.318124)
			(xy 74.313949 -375.310138) (xy 74.34961 -375.309638) (xy 74.385271 -375.310138) (xy 74.456145 -375.318124)
			(xy 74.52568 -375.333994) (xy 74.593 -375.357551) (xy 74.657259 -375.388496) (xy 74.71765 -375.426442)
			(xy 74.773412 -375.470911) (xy 74.823845 -375.521344) (xy 74.868314 -375.577106) (xy 74.90626 -375.637497)
			(xy 74.937205 -375.701756) (xy 74.960762 -375.769076) (xy 74.976632 -375.838611) (xy 74.984618 -375.909485)
			(xy 74.984618 -375.980807) (xy 75.790036 -375.980807) (xy 75.790036 -375.909485) (xy 75.798022 -375.838611)
			(xy 75.813892 -375.769076) (xy 75.837449 -375.701756) (xy 75.868394 -375.637497) (xy 75.90634 -375.577106)
			(xy 75.950809 -375.521344) (xy 76.001242 -375.470911) (xy 76.057004 -375.426442) (xy 76.117395 -375.388496)
			(xy 76.181654 -375.357551) (xy 76.248974 -375.333994) (xy 76.318509 -375.318124) (xy 76.389383 -375.310138)
			(xy 76.425044 -375.309638) (xy 76.460705 -375.310138) (xy 76.531579 -375.318124) (xy 76.601114 -375.333994)
			(xy 76.668434 -375.357551) (xy 76.732693 -375.388496) (xy 76.793084 -375.426442) (xy 76.848846 -375.470911)
			(xy 76.899279 -375.521344) (xy 76.943748 -375.577106) (xy 76.981694 -375.637497) (xy 77.012639 -375.701756)
			(xy 77.036196 -375.769076) (xy 77.052066 -375.838611) (xy 77.060052 -375.909485) (xy 77.060052 -375.980807)
			(xy 77.059966 -375.981569) (xy 77.968848 -375.981569) (xy 77.968848 -375.910247) (xy 77.976834 -375.839373)
			(xy 77.992704 -375.769838) (xy 78.016261 -375.702518) (xy 78.047206 -375.638259) (xy 78.085152 -375.577868)
			(xy 78.129621 -375.522106) (xy 78.180054 -375.471673) (xy 78.235816 -375.427204) (xy 78.296207 -375.389258)
			(xy 78.360466 -375.358313) (xy 78.427786 -375.334756) (xy 78.497321 -375.318886) (xy 78.568195 -375.3109)
			(xy 78.603856 -375.3104) (xy 78.639517 -375.3109) (xy 78.710391 -375.318886) (xy 78.779926 -375.334756)
			(xy 78.847246 -375.358313) (xy 78.911505 -375.389258) (xy 78.971896 -375.427204) (xy 79.027658 -375.471673)
			(xy 79.078091 -375.522106) (xy 79.12256 -375.577868) (xy 79.160506 -375.638259) (xy 79.171174 -375.660411)
			(xy 86.399122 -375.660411) (xy 86.401115 -375.460283) (xy 86.411112 -375.260394) (xy 86.429099 -375.061066)
			(xy 86.455047 -374.862617) (xy 86.488914 -374.665365) (xy 86.530646 -374.469626) (xy 86.580175 -374.275713)
			(xy 86.637424 -374.083938) (xy 86.702299 -373.894606) (xy 86.774698 -373.708022) (xy 86.854504 -373.524483)
			(xy 86.941589 -373.344285) (xy 87.035814 -373.167715) (xy 87.137028 -372.995056) (xy 87.245069 -372.826586)
			(xy 87.359764 -372.662572) (xy 87.48093 -372.503279) (xy 87.608371 -372.348962) (xy 87.741885 -372.199866)
			(xy 87.881257 -372.056232) (xy 88.026264 -371.91829) (xy 88.176675 -371.786259) (xy 88.332247 -371.660352)
			(xy 88.492732 -371.54077) (xy 88.657873 -371.427705) (xy 88.827405 -371.321337) (xy 89.001058 -371.221838)
			(xy 89.178552 -371.129366) (xy 89.359604 -371.04407) (xy 89.543924 -370.966086) (xy 89.731216 -370.895538)
			(xy 89.921181 -370.832541) (xy 90.113514 -370.777195) (xy 90.307908 -370.729588) (xy 90.504051 -370.689797)
			(xy 90.701628 -370.657885) (xy 90.900325 -370.633904) (xy 91.099821 -370.617891) (xy 91.299799 -370.609874)
			(xy 91.399868 -370.609368) (xy 91.499937 -370.609864) (xy 91.699915 -370.617861) (xy 91.899414 -370.633853)
			(xy 92.098112 -370.657814) (xy 92.295693 -370.689706) (xy 92.49184 -370.729477) (xy 92.686239 -370.777064)
			(xy 92.878578 -370.832391) (xy 93.068549 -370.895369) (xy 93.255848 -370.965897) (xy 93.440176 -371.043863)
			(xy 93.621237 -371.129141) (xy 93.79874 -371.221594) (xy 93.972403 -371.321076) (xy 94.141946 -371.427426)
			(xy 94.307099 -371.540475) (xy 94.467596 -371.66004) (xy 94.623181 -371.785932) (xy 94.773605 -371.917947)
			(xy 94.918626 -372.055875) (xy 95.058012 -372.199495) (xy 95.191541 -372.348576) (xy 95.318999 -372.502881)
			(xy 95.44018 -372.662162) (xy 95.554892 -372.826163) (xy 95.66295 -372.994623) (xy 95.764182 -373.167272)
			(xy 95.858425 -373.343832) (xy 95.945528 -373.524022) (xy 96.025353 -373.707552) (xy 96.09777 -373.894129)
			(xy 96.162665 -374.083454) (xy 96.219933 -374.275224) (xy 96.269483 -374.469131) (xy 96.311234 -374.664866)
			(xy 96.345121 -374.862115) (xy 96.371089 -375.060561) (xy 96.389096 -375.259888) (xy 96.399114 -375.459775)
			(xy 96.401127 -375.659903) (xy 96.395131 -375.859951) (xy 96.381135 -376.0596) (xy 96.359164 -376.258528)
			(xy 96.32925 -376.456418) (xy 96.291443 -376.652953) (xy 96.245804 -376.847818) (xy 96.192404 -377.040701)
			(xy 96.13133 -377.231293) (xy 96.062679 -377.419288) (xy 95.986561 -377.604387) (xy 95.903099 -377.786292)
			(xy 95.812426 -377.964711) (xy 95.714687 -378.139361) (xy 95.610038 -378.30996) (xy 95.498648 -378.476235)
			(xy 95.380694 -378.63792) (xy 95.256365 -378.794757) (xy 95.125862 -378.946494) (xy 94.989391 -379.092888)
			(xy 94.847173 -379.233704) (xy 94.699435 -379.368718) (xy 94.546413 -379.497713) (xy 94.388353 -379.620482)
			(xy 94.225507 -379.736829) (xy 94.058137 -379.846567) (xy 93.88651 -379.949521) (xy 93.710902 -380.045526)
			(xy 93.531592 -380.134428) (xy 93.34887 -380.216084) (xy 93.163027 -380.290365) (xy 92.97436 -380.357151)
			(xy 92.783173 -380.416334) (xy 92.589771 -380.467821) (xy 92.394464 -380.511529) (xy 92.197564 -380.547388)
			(xy 91.999387 -380.57534) (xy 91.800251 -380.59534) (xy 91.600474 -380.607358) (xy 91.400376 -380.611372)
			(xy 91.200278 -380.607378) (xy 91.000499 -380.595381) (xy 90.801361 -380.575401) (xy 90.603182 -380.547469)
			(xy 90.406278 -380.51163) (xy 90.210967 -380.467942) (xy 90.017559 -380.416475) (xy 89.826366 -380.357311)
			(xy 89.637693 -380.290544) (xy 89.451842 -380.216282) (xy 89.269111 -380.134644) (xy 89.089793 -380.045761)
			(xy 88.914175 -379.949774) (xy 88.742537 -379.846837) (xy 88.575156 -379.737116) (xy 88.412298 -379.620785)
			(xy 88.254226 -379.498032) (xy 88.101191 -379.369053) (xy 87.953439 -379.234055) (xy 87.811206 -379.093252)
			(xy 87.674721 -378.946872) (xy 87.544202 -378.795149) (xy 87.419858 -378.638325) (xy 87.301888 -378.476651)
			(xy 87.19048 -378.310387) (xy 87.085814 -378.139799) (xy 86.988057 -377.96516) (xy 86.897366 -377.786749)
			(xy 86.813885 -377.604853) (xy 86.737749 -377.419762) (xy 86.669079 -377.231773) (xy 86.607986 -377.041188)
			(xy 86.554566 -376.84831) (xy 86.508906 -376.65345) (xy 86.47108 -376.456919) (xy 86.441146 -376.259032)
			(xy 86.419154 -376.060106) (xy 86.405139 -375.860459) (xy 86.399122 -375.660411) (xy 79.171174 -375.660411)
			(xy 79.191451 -375.702518) (xy 79.215008 -375.769838) (xy 79.230878 -375.839373) (xy 79.238864 -375.910247)
			(xy 79.238864 -375.981569) (xy 79.230878 -376.052443) (xy 79.215008 -376.121978) (xy 79.191451 -376.189298)
			(xy 79.160506 -376.253557) (xy 79.12256 -376.313948) (xy 79.078091 -376.36971) (xy 79.027658 -376.420143)
			(xy 78.971896 -376.464612) (xy 78.911505 -376.502558) (xy 78.847246 -376.533503) (xy 78.779926 -376.55706)
			(xy 78.710391 -376.57293) (xy 78.639517 -376.580916) (xy 78.568195 -376.580916) (xy 78.497321 -376.57293)
			(xy 78.427786 -376.55706) (xy 78.360466 -376.533503) (xy 78.296207 -376.502558) (xy 78.235816 -376.464612)
			(xy 78.180054 -376.420143) (xy 78.129621 -376.36971) (xy 78.085152 -376.313948) (xy 78.047206 -376.253557)
			(xy 78.016261 -376.189298) (xy 77.992704 -376.121978) (xy 77.976834 -376.052443) (xy 77.968848 -375.981569)
			(xy 77.059966 -375.981569) (xy 77.052066 -376.051681) (xy 77.036196 -376.121216) (xy 77.012639 -376.188536)
			(xy 76.981694 -376.252795) (xy 76.943748 -376.313186) (xy 76.899279 -376.368948) (xy 76.848846 -376.419381)
			(xy 76.793084 -376.46385) (xy 76.732693 -376.501796) (xy 76.668434 -376.532741) (xy 76.601114 -376.556298)
			(xy 76.531579 -376.572168) (xy 76.460705 -376.580154) (xy 76.389383 -376.580154) (xy 76.318509 -376.572168)
			(xy 76.248974 -376.556298) (xy 76.181654 -376.532741) (xy 76.117395 -376.501796) (xy 76.057004 -376.46385)
			(xy 76.001242 -376.419381) (xy 75.950809 -376.368948) (xy 75.90634 -376.313186) (xy 75.868394 -376.252795)
			(xy 75.837449 -376.188536) (xy 75.813892 -376.121216) (xy 75.798022 -376.051681) (xy 75.790036 -375.980807)
			(xy 74.984618 -375.980807) (xy 74.976632 -376.051681) (xy 74.960762 -376.121216) (xy 74.937205 -376.188536)
			(xy 74.90626 -376.252795) (xy 74.868314 -376.313186) (xy 74.823845 -376.368948) (xy 74.773412 -376.419381)
			(xy 74.71765 -376.46385) (xy 74.657259 -376.501796) (xy 74.593 -376.532741) (xy 74.52568 -376.556298)
			(xy 74.456145 -376.572168) (xy 74.385271 -376.580154) (xy 74.313949 -376.580154) (xy 74.243075 -376.572168)
			(xy 74.17354 -376.556298) (xy 74.10622 -376.532741) (xy 74.041961 -376.501796) (xy 73.98157 -376.46385)
			(xy 73.925808 -376.419381) (xy 73.875375 -376.368948) (xy 73.830906 -376.313186) (xy 73.79296 -376.252795)
			(xy 73.762015 -376.188536) (xy 73.738458 -376.121216) (xy 73.722588 -376.051681) (xy 73.714602 -375.980807)
			(xy 40.391586 -375.980807) (xy 40.399716 -375.989342) (xy 40.861234 -376.450606) (xy 40.883236 -376.473339)
			(xy 40.921749 -376.523531) (xy 40.953382 -376.57832) (xy 40.977593 -376.63677) (xy 40.993967 -376.697879)
			(xy 41.002225 -376.760603) (xy 41.002225 -376.823869) (xy 40.993967 -376.886593) (xy 40.977593 -376.947702)
			(xy 40.953382 -377.006152) (xy 40.921749 -377.060941) (xy 40.883236 -377.111133) (xy 40.838501 -377.155868)
			(xy 40.788309 -377.194381) (xy 40.73352 -377.226014) (xy 40.67507 -377.250225) (xy 40.613961 -377.266599)
			(xy 40.551237 -377.274857) (xy 40.487971 -377.274857) (xy 40.425247 -377.266599) (xy 40.364138 -377.250225)
			(xy 40.305688 -377.226014) (xy 40.250899 -377.194381) (xy 40.200707 -377.155868) (xy 40.177974 -377.133866)
			(xy 39.011352 -375.967244) (xy 39.011352 -375.67489) (xy 39.010851 -375.651858) (xy 39.002545 -375.606548)
			(xy 38.986209 -375.563478) (xy 38.962375 -375.524058) (xy 38.931827 -375.48958) (xy 38.895564 -375.461174)
			(xy 38.854774 -375.439769) (xy 38.810795 -375.426068) (xy 38.765065 -375.420519) (xy 38.719085 -375.423305)
			(xy 38.67436 -375.434333) (xy 38.632356 -375.453242) (xy 38.594448 -375.479414) (xy 38.577774 -375.495312)
			(xy 36.403534 -377.669552) (xy 30.19806 -377.669552) (xy 30.130158 -377.737471) (xy 73.714602 -377.737471)
			(xy 73.714602 -377.666149) (xy 73.722588 -377.595275) (xy 73.738458 -377.52574) (xy 73.762015 -377.45842)
			(xy 73.79296 -377.394161) (xy 73.830906 -377.33377) (xy 73.875375 -377.278008) (xy 73.925808 -377.227575)
			(xy 73.98157 -377.183106) (xy 74.041961 -377.14516) (xy 74.10622 -377.114215) (xy 74.17354 -377.090658)
			(xy 74.243075 -377.074788) (xy 74.313949 -377.066802) (xy 74.34961 -377.066302) (xy 74.385271 -377.066802)
			(xy 74.456145 -377.074788) (xy 74.52568 -377.090658) (xy 74.593 -377.114215) (xy 74.657259 -377.14516)
			(xy 74.71765 -377.183106) (xy 74.773412 -377.227575) (xy 74.823845 -377.278008) (xy 74.868314 -377.33377)
			(xy 74.90626 -377.394161) (xy 74.937205 -377.45842) (xy 74.960762 -377.52574) (xy 74.976632 -377.595275)
			(xy 74.984618 -377.666149) (xy 74.984618 -377.737471) (xy 75.790036 -377.737471) (xy 75.790036 -377.666149)
			(xy 75.798022 -377.595275) (xy 75.813892 -377.52574) (xy 75.837449 -377.45842) (xy 75.868394 -377.394161)
			(xy 75.90634 -377.33377) (xy 75.950809 -377.278008) (xy 76.001242 -377.227575) (xy 76.057004 -377.183106)
			(xy 76.117395 -377.14516) (xy 76.181654 -377.114215) (xy 76.248974 -377.090658) (xy 76.318509 -377.074788)
			(xy 76.389383 -377.066802) (xy 76.425044 -377.066302) (xy 76.460705 -377.066802) (xy 76.531579 -377.074788)
			(xy 76.601114 -377.090658) (xy 76.668434 -377.114215) (xy 76.732693 -377.14516) (xy 76.793084 -377.183106)
			(xy 76.848846 -377.227575) (xy 76.899279 -377.278008) (xy 76.943748 -377.33377) (xy 76.981694 -377.394161)
			(xy 77.012639 -377.45842) (xy 77.036196 -377.52574) (xy 77.052066 -377.595275) (xy 77.060052 -377.666149)
			(xy 77.060052 -377.737471) (xy 77.059966 -377.738233) (xy 77.968848 -377.738233) (xy 77.968848 -377.666911)
			(xy 77.976834 -377.596037) (xy 77.992704 -377.526502) (xy 78.016261 -377.459182) (xy 78.047206 -377.394923)
			(xy 78.085152 -377.334532) (xy 78.129621 -377.27877) (xy 78.180054 -377.228337) (xy 78.235816 -377.183868)
			(xy 78.296207 -377.145922) (xy 78.360466 -377.114977) (xy 78.427786 -377.09142) (xy 78.497321 -377.07555)
			(xy 78.568195 -377.067564) (xy 78.603856 -377.067064) (xy 78.639517 -377.067564) (xy 78.710391 -377.07555)
			(xy 78.779926 -377.09142) (xy 78.847246 -377.114977) (xy 78.911505 -377.145922) (xy 78.971896 -377.183868)
			(xy 79.027658 -377.228337) (xy 79.078091 -377.27877) (xy 79.12256 -377.334532) (xy 79.160506 -377.394923)
			(xy 79.191451 -377.459182) (xy 79.215008 -377.526502) (xy 79.230878 -377.596037) (xy 79.238864 -377.666911)
			(xy 79.238864 -377.738233) (xy 79.230878 -377.809107) (xy 79.215008 -377.878642) (xy 79.191451 -377.945962)
			(xy 79.160506 -378.010221) (xy 79.12256 -378.070612) (xy 79.078091 -378.126374) (xy 79.027658 -378.176807)
			(xy 78.971896 -378.221276) (xy 78.911505 -378.259222) (xy 78.847246 -378.290167) (xy 78.779926 -378.313724)
			(xy 78.710391 -378.329594) (xy 78.639517 -378.33758) (xy 78.568195 -378.33758) (xy 78.497321 -378.329594)
			(xy 78.427786 -378.313724) (xy 78.360466 -378.290167) (xy 78.296207 -378.259222) (xy 78.235816 -378.221276)
			(xy 78.180054 -378.176807) (xy 78.129621 -378.126374) (xy 78.085152 -378.070612) (xy 78.047206 -378.010221)
			(xy 78.016261 -377.945962) (xy 77.992704 -377.878642) (xy 77.976834 -377.809107) (xy 77.968848 -377.738233)
			(xy 77.059966 -377.738233) (xy 77.052066 -377.808345) (xy 77.036196 -377.87788) (xy 77.012639 -377.9452)
			(xy 76.981694 -378.009459) (xy 76.943748 -378.06985) (xy 76.899279 -378.125612) (xy 76.848846 -378.176045)
			(xy 76.793084 -378.220514) (xy 76.732693 -378.25846) (xy 76.668434 -378.289405) (xy 76.601114 -378.312962)
			(xy 76.531579 -378.328832) (xy 76.460705 -378.336818) (xy 76.389383 -378.336818) (xy 76.318509 -378.328832)
			(xy 76.248974 -378.312962) (xy 76.181654 -378.289405) (xy 76.117395 -378.25846) (xy 76.057004 -378.220514)
			(xy 76.001242 -378.176045) (xy 75.950809 -378.125612) (xy 75.90634 -378.06985) (xy 75.868394 -378.009459)
			(xy 75.837449 -377.9452) (xy 75.813892 -377.87788) (xy 75.798022 -377.808345) (xy 75.790036 -377.737471)
			(xy 74.984618 -377.737471) (xy 74.976632 -377.808345) (xy 74.960762 -377.87788) (xy 74.937205 -377.9452)
			(xy 74.90626 -378.009459) (xy 74.868314 -378.06985) (xy 74.823845 -378.125612) (xy 74.773412 -378.176045)
			(xy 74.71765 -378.220514) (xy 74.657259 -378.25846) (xy 74.593 -378.289405) (xy 74.52568 -378.312962)
			(xy 74.456145 -378.328832) (xy 74.385271 -378.336818) (xy 74.313949 -378.336818) (xy 74.243075 -378.328832)
			(xy 74.17354 -378.312962) (xy 74.10622 -378.289405) (xy 74.041961 -378.25846) (xy 73.98157 -378.220514)
			(xy 73.925808 -378.176045) (xy 73.875375 -378.125612) (xy 73.830906 -378.06985) (xy 73.79296 -378.009459)
			(xy 73.762015 -377.9452) (xy 73.738458 -377.87788) (xy 73.722588 -377.808345) (xy 73.714602 -377.737471)
			(xy 30.130158 -377.737471) (xy 29.175202 -378.692664) (xy 29.153735 -378.713477) (xy 29.106544 -378.750194)
			(xy 29.055185 -378.780809) (xy 29.000441 -378.804856) (xy 28.943149 -378.821967) (xy 28.884184 -378.831881)
			(xy 28.824447 -378.834446) (xy 28.764849 -378.829623) (xy 28.706302 -378.817486) (xy 28.67787 -378.808234)
			(xy 28.656942 -378.801579) (xy 28.613565 -378.794745) (xy 28.569659 -378.79547) (xy 28.526532 -378.803733)
			(xy 28.485467 -378.819287) (xy 28.447687 -378.841669) (xy 28.414318 -378.870212) (xy 28.386352 -378.904067)
			(xy 28.364624 -378.942226) (xy 28.349778 -378.983553) (xy 28.342258 -379.026816) (xy 28.341828 -379.048772)
			(xy 28.341828 -379.504041) (xy 73.714602 -379.504041) (xy 73.714602 -379.432719) (xy 73.722588 -379.361845)
			(xy 73.738458 -379.29231) (xy 73.762015 -379.22499) (xy 73.79296 -379.160731) (xy 73.830906 -379.10034)
			(xy 73.875375 -379.044578) (xy 73.925808 -378.994145) (xy 73.98157 -378.949676) (xy 74.041961 -378.91173)
			(xy 74.10622 -378.880785) (xy 74.17354 -378.857228) (xy 74.243075 -378.841358) (xy 74.313949 -378.833372)
			(xy 74.34961 -378.832872) (xy 74.385271 -378.833372) (xy 74.456145 -378.841358) (xy 74.52568 -378.857228)
			(xy 74.593 -378.880785) (xy 74.657259 -378.91173) (xy 74.71765 -378.949676) (xy 74.773412 -378.994145)
			(xy 74.823845 -379.044578) (xy 74.868314 -379.10034) (xy 74.90626 -379.160731) (xy 74.937205 -379.22499)
			(xy 74.960762 -379.29231) (xy 74.976632 -379.361845) (xy 74.984618 -379.432719) (xy 74.984618 -379.504041)
			(xy 75.790036 -379.504041) (xy 75.790036 -379.432719) (xy 75.798022 -379.361845) (xy 75.813892 -379.29231)
			(xy 75.837449 -379.22499) (xy 75.868394 -379.160731) (xy 75.90634 -379.10034) (xy 75.950809 -379.044578)
			(xy 76.001242 -378.994145) (xy 76.057004 -378.949676) (xy 76.117395 -378.91173) (xy 76.181654 -378.880785)
			(xy 76.248974 -378.857228) (xy 76.318509 -378.841358) (xy 76.389383 -378.833372) (xy 76.425044 -378.832872)
			(xy 76.460705 -378.833372) (xy 76.531579 -378.841358) (xy 76.601114 -378.857228) (xy 76.668434 -378.880785)
			(xy 76.732693 -378.91173) (xy 76.793084 -378.949676) (xy 76.848846 -378.994145) (xy 76.899279 -379.044578)
			(xy 76.943748 -379.10034) (xy 76.981694 -379.160731) (xy 77.012639 -379.22499) (xy 77.036196 -379.29231)
			(xy 77.052066 -379.361845) (xy 77.060052 -379.432719) (xy 77.060052 -379.504041) (xy 77.059966 -379.504803)
			(xy 77.968848 -379.504803) (xy 77.968848 -379.433481) (xy 77.976834 -379.362607) (xy 77.992704 -379.293072)
			(xy 78.016261 -379.225752) (xy 78.047206 -379.161493) (xy 78.085152 -379.101102) (xy 78.129621 -379.04534)
			(xy 78.180054 -378.994907) (xy 78.235816 -378.950438) (xy 78.296207 -378.912492) (xy 78.360466 -378.881547)
			(xy 78.427786 -378.85799) (xy 78.497321 -378.84212) (xy 78.568195 -378.834134) (xy 78.603856 -378.833634)
			(xy 78.639517 -378.834134) (xy 78.710391 -378.84212) (xy 78.779926 -378.85799) (xy 78.847246 -378.881547)
			(xy 78.911505 -378.912492) (xy 78.971896 -378.950438) (xy 79.027658 -378.994907) (xy 79.078091 -379.04534)
			(xy 79.12256 -379.101102) (xy 79.160506 -379.161493) (xy 79.191451 -379.225752) (xy 79.215008 -379.293072)
			(xy 79.230878 -379.362607) (xy 79.238864 -379.433481) (xy 79.238864 -379.504803) (xy 79.230878 -379.575677)
			(xy 79.215008 -379.645212) (xy 79.191451 -379.712532) (xy 79.160506 -379.776791) (xy 79.12256 -379.837182)
			(xy 79.078091 -379.892944) (xy 79.027658 -379.943377) (xy 78.971896 -379.987846) (xy 78.911505 -380.025792)
			(xy 78.847246 -380.056737) (xy 78.779926 -380.080294) (xy 78.710391 -380.096164) (xy 78.639517 -380.10415)
			(xy 78.568195 -380.10415) (xy 78.497321 -380.096164) (xy 78.427786 -380.080294) (xy 78.360466 -380.056737)
			(xy 78.296207 -380.025792) (xy 78.235816 -379.987846) (xy 78.180054 -379.943377) (xy 78.129621 -379.892944)
			(xy 78.085152 -379.837182) (xy 78.047206 -379.776791) (xy 78.016261 -379.712532) (xy 77.992704 -379.645212)
			(xy 77.976834 -379.575677) (xy 77.968848 -379.504803) (xy 77.059966 -379.504803) (xy 77.052066 -379.574915)
			(xy 77.036196 -379.64445) (xy 77.012639 -379.71177) (xy 76.981694 -379.776029) (xy 76.943748 -379.83642)
			(xy 76.899279 -379.892182) (xy 76.848846 -379.942615) (xy 76.793084 -379.987084) (xy 76.732693 -380.02503)
			(xy 76.668434 -380.055975) (xy 76.601114 -380.079532) (xy 76.531579 -380.095402) (xy 76.460705 -380.103388)
			(xy 76.389383 -380.103388) (xy 76.318509 -380.095402) (xy 76.248974 -380.079532) (xy 76.181654 -380.055975)
			(xy 76.117395 -380.02503) (xy 76.057004 -379.987084) (xy 76.001242 -379.942615) (xy 75.950809 -379.892182)
			(xy 75.90634 -379.83642) (xy 75.868394 -379.776029) (xy 75.837449 -379.71177) (xy 75.813892 -379.64445)
			(xy 75.798022 -379.574915) (xy 75.790036 -379.504041) (xy 74.984618 -379.504041) (xy 74.976632 -379.574915)
			(xy 74.960762 -379.64445) (xy 74.937205 -379.71177) (xy 74.90626 -379.776029) (xy 74.868314 -379.83642)
			(xy 74.823845 -379.892182) (xy 74.773412 -379.942615) (xy 74.71765 -379.987084) (xy 74.657259 -380.02503)
			(xy 74.593 -380.055975) (xy 74.52568 -380.079532) (xy 74.456145 -380.095402) (xy 74.385271 -380.103388)
			(xy 74.313949 -380.103388) (xy 74.243075 -380.095402) (xy 74.17354 -380.079532) (xy 74.10622 -380.055975)
			(xy 74.041961 -380.02503) (xy 73.98157 -379.987084) (xy 73.925808 -379.942615) (xy 73.875375 -379.892182)
			(xy 73.830906 -379.83642) (xy 73.79296 -379.776029) (xy 73.762015 -379.71177) (xy 73.738458 -379.64445)
			(xy 73.722588 -379.574915) (xy 73.714602 -379.504041) (xy 28.341828 -379.504041) (xy 28.341828 -384.55625)
			(xy 76.183218 -384.55625) (xy 76.183218 -384.496314) (xy 76.191041 -384.436892) (xy 76.206554 -384.378999)
			(xy 76.22949 -384.323626) (xy 76.259457 -384.27172) (xy 76.295944 -384.22417) (xy 76.338324 -384.18179)
			(xy 76.385874 -384.145303) (xy 76.43778 -384.115336) (xy 76.493153 -384.0924) (xy 76.551046 -384.076887)
			(xy 76.610468 -384.069064) (xy 76.640436 -384.068574) (xy 76.670404 -384.069064) (xy 76.729826 -384.076887)
			(xy 76.787719 -384.0924) (xy 76.843092 -384.115336) (xy 76.894998 -384.145303) (xy 76.942548 -384.18179)
			(xy 76.984928 -384.22417) (xy 77.021415 -384.27172) (xy 77.051382 -384.323626) (xy 77.074318 -384.378999)
			(xy 77.089831 -384.436892) (xy 77.097654 -384.496314) (xy 77.097654 -384.55625) (xy 77.089831 -384.615672)
			(xy 77.074318 -384.673565) (xy 77.051382 -384.728938) (xy 77.021415 -384.780844) (xy 76.984928 -384.828394)
			(xy 76.942548 -384.870774) (xy 76.894998 -384.907261) (xy 76.843092 -384.937228) (xy 76.787719 -384.960164)
			(xy 76.729826 -384.975677) (xy 76.670404 -384.9835) (xy 76.610468 -384.9835) (xy 76.551046 -384.975677)
			(xy 76.493153 -384.960164) (xy 76.43778 -384.937228) (xy 76.385874 -384.907261) (xy 76.338324 -384.870774)
			(xy 76.295944 -384.828394) (xy 76.259457 -384.780844) (xy 76.22949 -384.728938) (xy 76.206554 -384.673565)
			(xy 76.191041 -384.615672) (xy 76.183218 -384.55625) (xy 28.341828 -384.55625) (xy 28.341828 -387.227822)
			(xy 76.3186 -387.227822) (xy 76.3186 -387.167886) (xy 76.326423 -387.108464) (xy 76.341936 -387.050571)
			(xy 76.364872 -386.995198) (xy 76.394839 -386.943292) (xy 76.431326 -386.895742) (xy 76.473706 -386.853362)
			(xy 76.521256 -386.816875) (xy 76.573162 -386.786908) (xy 76.628535 -386.763972) (xy 76.686428 -386.748459)
			(xy 76.74585 -386.740636) (xy 76.775818 -386.740146) (xy 76.805786 -386.740636) (xy 76.865208 -386.748459)
			(xy 76.923101 -386.763972) (xy 76.978474 -386.786908) (xy 77.03038 -386.816875) (xy 77.07793 -386.853362)
			(xy 77.12031 -386.895742) (xy 77.156797 -386.943292) (xy 77.186764 -386.995198) (xy 77.2097 -387.050571)
			(xy 77.225213 -387.108464) (xy 77.233036 -387.167886) (xy 77.233036 -387.227822) (xy 77.225213 -387.287244)
			(xy 77.2097 -387.345137) (xy 77.186764 -387.40051) (xy 77.156797 -387.452416) (xy 77.12031 -387.499966)
			(xy 77.07793 -387.542346) (xy 77.03038 -387.578833) (xy 76.978474 -387.6088) (xy 76.923101 -387.631736)
			(xy 76.865208 -387.647249) (xy 76.805786 -387.655072) (xy 76.74585 -387.655072) (xy 76.686428 -387.647249)
			(xy 76.628535 -387.631736) (xy 76.573162 -387.6088) (xy 76.521256 -387.578833) (xy 76.473706 -387.542346)
			(xy 76.431326 -387.499966) (xy 76.394839 -387.452416) (xy 76.364872 -387.40051) (xy 76.341936 -387.345137)
			(xy 76.326423 -387.287244) (xy 76.3186 -387.227822) (xy 28.341828 -387.227822) (xy 28.341828 -389.706967)
			(xy 66.405498 -389.706967) (xy 66.405498 -389.635645) (xy 66.413484 -389.564771) (xy 66.429354 -389.495236)
			(xy 66.452911 -389.427916) (xy 66.483856 -389.363657) (xy 66.521802 -389.303266) (xy 66.566271 -389.247504)
			(xy 66.616704 -389.197071) (xy 66.672466 -389.152602) (xy 66.732857 -389.114656) (xy 66.797116 -389.083711)
			(xy 66.864436 -389.060154) (xy 66.933971 -389.044284) (xy 67.004845 -389.036298) (xy 67.040506 -389.035798)
			(xy 67.076167 -389.036298) (xy 67.147041 -389.044284) (xy 67.216576 -389.060154) (xy 67.283896 -389.083711)
			(xy 67.348155 -389.114656) (xy 67.408546 -389.152602) (xy 67.464308 -389.197071) (xy 67.514741 -389.247504)
			(xy 67.55921 -389.303266) (xy 67.597156 -389.363657) (xy 67.628101 -389.427916) (xy 67.651658 -389.495236)
			(xy 67.667528 -389.564771) (xy 67.675514 -389.635645) (xy 67.675514 -389.706967) (xy 68.334628 -389.706967)
			(xy 68.334628 -389.635645) (xy 68.342614 -389.564771) (xy 68.358484 -389.495236) (xy 68.382041 -389.427916)
			(xy 68.412986 -389.363657) (xy 68.450932 -389.303266) (xy 68.495401 -389.247504) (xy 68.545834 -389.197071)
			(xy 68.601596 -389.152602) (xy 68.661987 -389.114656) (xy 68.726246 -389.083711) (xy 68.793566 -389.060154)
			(xy 68.863101 -389.044284) (xy 68.933975 -389.036298) (xy 68.969636 -389.035798) (xy 69.005297 -389.036298)
			(xy 69.076171 -389.044284) (xy 69.145706 -389.060154) (xy 69.213026 -389.083711) (xy 69.277285 -389.114656)
			(xy 69.337676 -389.152602) (xy 69.393438 -389.197071) (xy 69.443871 -389.247504) (xy 69.48834 -389.303266)
			(xy 69.526286 -389.363657) (xy 69.557231 -389.427916) (xy 69.580788 -389.495236) (xy 69.596658 -389.564771)
			(xy 69.604644 -389.635645) (xy 69.604644 -389.706967) (xy 69.599492 -389.752687) (xy 70.078592 -389.752687)
			(xy 70.078592 -389.681365) (xy 70.086578 -389.610491) (xy 70.102448 -389.540956) (xy 70.126005 -389.473636)
			(xy 70.15695 -389.409377) (xy 70.194896 -389.348986) (xy 70.239365 -389.293224) (xy 70.289798 -389.242791)
			(xy 70.34556 -389.198322) (xy 70.405951 -389.160376) (xy 70.47021 -389.129431) (xy 70.53753 -389.105874)
			(xy 70.607065 -389.090004) (xy 70.677939 -389.082018) (xy 70.7136 -389.081518) (xy 70.749261 -389.082018)
			(xy 70.820135 -389.090004) (xy 70.88967 -389.105874) (xy 70.95699 -389.129431) (xy 71.021249 -389.160376)
			(xy 71.08164 -389.198322) (xy 71.137402 -389.242791) (xy 71.187835 -389.293224) (xy 71.232304 -389.348986)
			(xy 71.27025 -389.409377) (xy 71.301195 -389.473636) (xy 71.324752 -389.540956) (xy 71.340622 -389.610491)
			(xy 71.348608 -389.681365) (xy 71.348608 -389.752687) (xy 72.007722 -389.752687) (xy 72.007722 -389.681365)
			(xy 72.015708 -389.610491) (xy 72.031578 -389.540956) (xy 72.055135 -389.473636) (xy 72.08608 -389.409377)
			(xy 72.124026 -389.348986) (xy 72.168495 -389.293224) (xy 72.218928 -389.242791) (xy 72.27469 -389.198322)
			(xy 72.335081 -389.160376) (xy 72.39934 -389.129431) (xy 72.46666 -389.105874) (xy 72.536195 -389.090004)
			(xy 72.607069 -389.082018) (xy 72.64273 -389.081518) (xy 72.678391 -389.082018) (xy 72.749265 -389.090004)
			(xy 72.8188 -389.105874) (xy 72.88612 -389.129431) (xy 72.950379 -389.160376) (xy 73.01077 -389.198322)
			(xy 73.066532 -389.242791) (xy 73.116965 -389.293224) (xy 73.161434 -389.348986) (xy 73.19938 -389.409377)
			(xy 73.230325 -389.473636) (xy 73.253882 -389.540956) (xy 73.269752 -389.610491) (xy 73.277738 -389.681365)
			(xy 73.277738 -389.752687) (xy 73.269752 -389.823561) (xy 73.253882 -389.893096) (xy 73.230325 -389.960416)
			(xy 73.19938 -390.024675) (xy 73.161434 -390.085066) (xy 73.116965 -390.140828) (xy 73.066532 -390.191261)
			(xy 73.01077 -390.23573) (xy 72.950379 -390.273676) (xy 72.88612 -390.304621) (xy 72.8188 -390.328178)
			(xy 72.749265 -390.344048) (xy 72.678391 -390.352034) (xy 72.607069 -390.352034) (xy 72.536195 -390.344048)
			(xy 72.46666 -390.328178) (xy 72.39934 -390.304621) (xy 72.335081 -390.273676) (xy 72.27469 -390.23573)
			(xy 72.218928 -390.191261) (xy 72.168495 -390.140828) (xy 72.124026 -390.085066) (xy 72.08608 -390.024675)
			(xy 72.055135 -389.960416) (xy 72.031578 -389.893096) (xy 72.015708 -389.823561) (xy 72.007722 -389.752687)
			(xy 71.348608 -389.752687) (xy 71.340622 -389.823561) (xy 71.324752 -389.893096) (xy 71.301195 -389.960416)
			(xy 71.27025 -390.024675) (xy 71.232304 -390.085066) (xy 71.187835 -390.140828) (xy 71.137402 -390.191261)
			(xy 71.08164 -390.23573) (xy 71.021249 -390.273676) (xy 70.95699 -390.304621) (xy 70.88967 -390.328178)
			(xy 70.820135 -390.344048) (xy 70.749261 -390.352034) (xy 70.677939 -390.352034) (xy 70.607065 -390.344048)
			(xy 70.53753 -390.328178) (xy 70.47021 -390.304621) (xy 70.405951 -390.273676) (xy 70.34556 -390.23573)
			(xy 70.289798 -390.191261) (xy 70.239365 -390.140828) (xy 70.194896 -390.085066) (xy 70.15695 -390.024675)
			(xy 70.126005 -389.960416) (xy 70.102448 -389.893096) (xy 70.086578 -389.823561) (xy 70.078592 -389.752687)
			(xy 69.599492 -389.752687) (xy 69.596658 -389.777841) (xy 69.580788 -389.847376) (xy 69.557231 -389.914696)
			(xy 69.526286 -389.978955) (xy 69.48834 -390.039346) (xy 69.443871 -390.095108) (xy 69.393438 -390.145541)
			(xy 69.337676 -390.19001) (xy 69.277285 -390.227956) (xy 69.213026 -390.258901) (xy 69.145706 -390.282458)
			(xy 69.076171 -390.298328) (xy 69.005297 -390.306314) (xy 68.933975 -390.306314) (xy 68.863101 -390.298328)
			(xy 68.793566 -390.282458) (xy 68.726246 -390.258901) (xy 68.661987 -390.227956) (xy 68.601596 -390.19001)
			(xy 68.545834 -390.145541) (xy 68.495401 -390.095108) (xy 68.450932 -390.039346) (xy 68.412986 -389.978955)
			(xy 68.382041 -389.914696) (xy 68.358484 -389.847376) (xy 68.342614 -389.777841) (xy 68.334628 -389.706967)
			(xy 67.675514 -389.706967) (xy 67.667528 -389.777841) (xy 67.651658 -389.847376) (xy 67.628101 -389.914696)
			(xy 67.597156 -389.978955) (xy 67.55921 -390.039346) (xy 67.514741 -390.095108) (xy 67.464308 -390.145541)
			(xy 67.408546 -390.19001) (xy 67.348155 -390.227956) (xy 67.283896 -390.258901) (xy 67.216576 -390.282458)
			(xy 67.147041 -390.298328) (xy 67.076167 -390.306314) (xy 67.004845 -390.306314) (xy 66.933971 -390.298328)
			(xy 66.864436 -390.282458) (xy 66.797116 -390.258901) (xy 66.732857 -390.227956) (xy 66.672466 -390.19001)
			(xy 66.616704 -390.145541) (xy 66.566271 -390.095108) (xy 66.521802 -390.039346) (xy 66.483856 -389.978955)
			(xy 66.452911 -389.914696) (xy 66.429354 -389.847376) (xy 66.413484 -389.777841) (xy 66.405498 -389.706967)
			(xy 28.341828 -389.706967) (xy 28.341828 -391.463631) (xy 66.405498 -391.463631) (xy 66.405498 -391.392309)
			(xy 66.413484 -391.321435) (xy 66.429354 -391.2519) (xy 66.452911 -391.18458) (xy 66.483856 -391.120321)
			(xy 66.521802 -391.05993) (xy 66.566271 -391.004168) (xy 66.616704 -390.953735) (xy 66.672466 -390.909266)
			(xy 66.732857 -390.87132) (xy 66.797116 -390.840375) (xy 66.864436 -390.816818) (xy 66.933971 -390.800948)
			(xy 67.004845 -390.792962) (xy 67.040506 -390.792462) (xy 67.076167 -390.792962) (xy 67.147041 -390.800948)
			(xy 67.216576 -390.816818) (xy 67.283896 -390.840375) (xy 67.348155 -390.87132) (xy 67.408546 -390.909266)
			(xy 67.464308 -390.953735) (xy 67.514741 -391.004168) (xy 67.55921 -391.05993) (xy 67.597156 -391.120321)
			(xy 67.628101 -391.18458) (xy 67.651658 -391.2519) (xy 67.667528 -391.321435) (xy 67.675514 -391.392309)
			(xy 67.675514 -391.463631) (xy 68.334628 -391.463631) (xy 68.334628 -391.392309) (xy 68.342614 -391.321435)
			(xy 68.358484 -391.2519) (xy 68.382041 -391.18458) (xy 68.412986 -391.120321) (xy 68.450932 -391.05993)
			(xy 68.495401 -391.004168) (xy 68.545834 -390.953735) (xy 68.601596 -390.909266) (xy 68.661987 -390.87132)
			(xy 68.726246 -390.840375) (xy 68.793566 -390.816818) (xy 68.863101 -390.800948) (xy 68.933975 -390.792962)
			(xy 68.969636 -390.792462) (xy 69.005297 -390.792962) (xy 69.076171 -390.800948) (xy 69.145706 -390.816818)
			(xy 69.213026 -390.840375) (xy 69.277285 -390.87132) (xy 69.337676 -390.909266) (xy 69.393438 -390.953735)
			(xy 69.443871 -391.004168) (xy 69.48834 -391.05993) (xy 69.526286 -391.120321) (xy 69.557231 -391.18458)
			(xy 69.580788 -391.2519) (xy 69.596658 -391.321435) (xy 69.604644 -391.392309) (xy 69.604644 -391.463631)
			(xy 69.599492 -391.509351) (xy 70.078592 -391.509351) (xy 70.078592 -391.438029) (xy 70.086578 -391.367155)
			(xy 70.102448 -391.29762) (xy 70.126005 -391.2303) (xy 70.15695 -391.166041) (xy 70.194896 -391.10565)
			(xy 70.239365 -391.049888) (xy 70.289798 -390.999455) (xy 70.34556 -390.954986) (xy 70.405951 -390.91704)
			(xy 70.47021 -390.886095) (xy 70.53753 -390.862538) (xy 70.607065 -390.846668) (xy 70.677939 -390.838682)
			(xy 70.7136 -390.838182) (xy 70.749261 -390.838682) (xy 70.820135 -390.846668) (xy 70.88967 -390.862538)
			(xy 70.95699 -390.886095) (xy 71.021249 -390.91704) (xy 71.08164 -390.954986) (xy 71.137402 -390.999455)
			(xy 71.187835 -391.049888) (xy 71.232304 -391.10565) (xy 71.27025 -391.166041) (xy 71.301195 -391.2303)
			(xy 71.324752 -391.29762) (xy 71.340622 -391.367155) (xy 71.348608 -391.438029) (xy 71.348608 -391.509351)
			(xy 72.007722 -391.509351) (xy 72.007722 -391.438029) (xy 72.015708 -391.367155) (xy 72.031578 -391.29762)
			(xy 72.055135 -391.2303) (xy 72.08608 -391.166041) (xy 72.124026 -391.10565) (xy 72.168495 -391.049888)
			(xy 72.218928 -390.999455) (xy 72.27469 -390.954986) (xy 72.335081 -390.91704) (xy 72.39934 -390.886095)
			(xy 72.46666 -390.862538) (xy 72.536195 -390.846668) (xy 72.607069 -390.838682) (xy 72.64273 -390.838182)
			(xy 72.678391 -390.838682) (xy 72.749265 -390.846668) (xy 72.8188 -390.862538) (xy 72.88612 -390.886095)
			(xy 72.950379 -390.91704) (xy 73.01077 -390.954986) (xy 73.066532 -390.999455) (xy 73.116965 -391.049888)
			(xy 73.161434 -391.10565) (xy 73.19938 -391.166041) (xy 73.230325 -391.2303) (xy 73.253882 -391.29762)
			(xy 73.269752 -391.367155) (xy 73.277738 -391.438029) (xy 73.277738 -391.509351) (xy 73.269752 -391.580225)
			(xy 73.253882 -391.64976) (xy 73.230325 -391.71708) (xy 73.19938 -391.781339) (xy 73.161434 -391.84173)
			(xy 73.116965 -391.897492) (xy 73.066532 -391.947925) (xy 73.01077 -391.992394) (xy 72.950379 -392.03034)
			(xy 72.88612 -392.061285) (xy 72.8188 -392.084842) (xy 72.749265 -392.100712) (xy 72.678391 -392.108698)
			(xy 72.607069 -392.108698) (xy 72.536195 -392.100712) (xy 72.46666 -392.084842) (xy 72.39934 -392.061285)
			(xy 72.335081 -392.03034) (xy 72.27469 -391.992394) (xy 72.218928 -391.947925) (xy 72.168495 -391.897492)
			(xy 72.124026 -391.84173) (xy 72.08608 -391.781339) (xy 72.055135 -391.71708) (xy 72.031578 -391.64976)
			(xy 72.015708 -391.580225) (xy 72.007722 -391.509351) (xy 71.348608 -391.509351) (xy 71.340622 -391.580225)
			(xy 71.324752 -391.64976) (xy 71.301195 -391.71708) (xy 71.27025 -391.781339) (xy 71.232304 -391.84173)
			(xy 71.187835 -391.897492) (xy 71.137402 -391.947925) (xy 71.08164 -391.992394) (xy 71.021249 -392.03034)
			(xy 70.95699 -392.061285) (xy 70.88967 -392.084842) (xy 70.820135 -392.100712) (xy 70.749261 -392.108698)
			(xy 70.677939 -392.108698) (xy 70.607065 -392.100712) (xy 70.53753 -392.084842) (xy 70.47021 -392.061285)
			(xy 70.405951 -392.03034) (xy 70.34556 -391.992394) (xy 70.289798 -391.947925) (xy 70.239365 -391.897492)
			(xy 70.194896 -391.84173) (xy 70.15695 -391.781339) (xy 70.126005 -391.71708) (xy 70.102448 -391.64976)
			(xy 70.086578 -391.580225) (xy 70.078592 -391.509351) (xy 69.599492 -391.509351) (xy 69.596658 -391.534505)
			(xy 69.580788 -391.60404) (xy 69.557231 -391.67136) (xy 69.526286 -391.735619) (xy 69.48834 -391.79601)
			(xy 69.443871 -391.851772) (xy 69.393438 -391.902205) (xy 69.337676 -391.946674) (xy 69.277285 -391.98462)
			(xy 69.213026 -392.015565) (xy 69.145706 -392.039122) (xy 69.076171 -392.054992) (xy 69.005297 -392.062978)
			(xy 68.933975 -392.062978) (xy 68.863101 -392.054992) (xy 68.793566 -392.039122) (xy 68.726246 -392.015565)
			(xy 68.661987 -391.98462) (xy 68.601596 -391.946674) (xy 68.545834 -391.902205) (xy 68.495401 -391.851772)
			(xy 68.450932 -391.79601) (xy 68.412986 -391.735619) (xy 68.382041 -391.67136) (xy 68.358484 -391.60404)
			(xy 68.342614 -391.534505) (xy 68.334628 -391.463631) (xy 67.675514 -391.463631) (xy 67.667528 -391.534505)
			(xy 67.651658 -391.60404) (xy 67.628101 -391.67136) (xy 67.597156 -391.735619) (xy 67.55921 -391.79601)
			(xy 67.514741 -391.851772) (xy 67.464308 -391.902205) (xy 67.408546 -391.946674) (xy 67.348155 -391.98462)
			(xy 67.283896 -392.015565) (xy 67.216576 -392.039122) (xy 67.147041 -392.054992) (xy 67.076167 -392.062978)
			(xy 67.004845 -392.062978) (xy 66.933971 -392.054992) (xy 66.864436 -392.039122) (xy 66.797116 -392.015565)
			(xy 66.732857 -391.98462) (xy 66.672466 -391.946674) (xy 66.616704 -391.902205) (xy 66.566271 -391.851772)
			(xy 66.521802 -391.79601) (xy 66.483856 -391.735619) (xy 66.452911 -391.67136) (xy 66.429354 -391.60404)
			(xy 66.413484 -391.534505) (xy 66.405498 -391.463631) (xy 28.341828 -391.463631) (xy 28.341828 -393.230201)
			(xy 66.405498 -393.230201) (xy 66.405498 -393.158879) (xy 66.413484 -393.088005) (xy 66.429354 -393.01847)
			(xy 66.452911 -392.95115) (xy 66.483856 -392.886891) (xy 66.521802 -392.8265) (xy 66.566271 -392.770738)
			(xy 66.616704 -392.720305) (xy 66.672466 -392.675836) (xy 66.732857 -392.63789) (xy 66.797116 -392.606945)
			(xy 66.864436 -392.583388) (xy 66.933971 -392.567518) (xy 67.004845 -392.559532) (xy 67.040506 -392.559032)
			(xy 67.076167 -392.559532) (xy 67.147041 -392.567518) (xy 67.216576 -392.583388) (xy 67.283896 -392.606945)
			(xy 67.348155 -392.63789) (xy 67.408546 -392.675836) (xy 67.464308 -392.720305) (xy 67.514741 -392.770738)
			(xy 67.55921 -392.8265) (xy 67.597156 -392.886891) (xy 67.628101 -392.95115) (xy 67.651658 -393.01847)
			(xy 67.667528 -393.088005) (xy 67.675514 -393.158879) (xy 67.675514 -393.230201) (xy 68.334628 -393.230201)
			(xy 68.334628 -393.158879) (xy 68.342614 -393.088005) (xy 68.358484 -393.01847) (xy 68.382041 -392.95115)
			(xy 68.412986 -392.886891) (xy 68.450932 -392.8265) (xy 68.495401 -392.770738) (xy 68.545834 -392.720305)
			(xy 68.601596 -392.675836) (xy 68.661987 -392.63789) (xy 68.726246 -392.606945) (xy 68.793566 -392.583388)
			(xy 68.863101 -392.567518) (xy 68.933975 -392.559532) (xy 68.969636 -392.559032) (xy 69.005297 -392.559532)
			(xy 69.076171 -392.567518) (xy 69.145706 -392.583388) (xy 69.213026 -392.606945) (xy 69.277285 -392.63789)
			(xy 69.337676 -392.675836) (xy 69.393438 -392.720305) (xy 69.443871 -392.770738) (xy 69.48834 -392.8265)
			(xy 69.526286 -392.886891) (xy 69.557231 -392.95115) (xy 69.580788 -393.01847) (xy 69.596658 -393.088005)
			(xy 69.604644 -393.158879) (xy 69.604644 -393.230201) (xy 69.599492 -393.275921) (xy 70.078592 -393.275921)
			(xy 70.078592 -393.204599) (xy 70.086578 -393.133725) (xy 70.102448 -393.06419) (xy 70.126005 -392.99687)
			(xy 70.15695 -392.932611) (xy 70.194896 -392.87222) (xy 70.239365 -392.816458) (xy 70.289798 -392.766025)
			(xy 70.34556 -392.721556) (xy 70.405951 -392.68361) (xy 70.47021 -392.652665) (xy 70.53753 -392.629108)
			(xy 70.607065 -392.613238) (xy 70.677939 -392.605252) (xy 70.7136 -392.604752) (xy 70.749261 -392.605252)
			(xy 70.820135 -392.613238) (xy 70.88967 -392.629108) (xy 70.95699 -392.652665) (xy 71.021249 -392.68361)
			(xy 71.08164 -392.721556) (xy 71.137402 -392.766025) (xy 71.187835 -392.816458) (xy 71.232304 -392.87222)
			(xy 71.27025 -392.932611) (xy 71.301195 -392.99687) (xy 71.324752 -393.06419) (xy 71.340622 -393.133725)
			(xy 71.348608 -393.204599) (xy 71.348608 -393.275921) (xy 72.007722 -393.275921) (xy 72.007722 -393.204599)
			(xy 72.015708 -393.133725) (xy 72.031578 -393.06419) (xy 72.055135 -392.99687) (xy 72.08608 -392.932611)
			(xy 72.124026 -392.87222) (xy 72.168495 -392.816458) (xy 72.218928 -392.766025) (xy 72.27469 -392.721556)
			(xy 72.335081 -392.68361) (xy 72.39934 -392.652665) (xy 72.46666 -392.629108) (xy 72.536195 -392.613238)
			(xy 72.607069 -392.605252) (xy 72.64273 -392.604752) (xy 72.678391 -392.605252) (xy 72.749265 -392.613238)
			(xy 72.8188 -392.629108) (xy 72.88612 -392.652665) (xy 72.950379 -392.68361) (xy 73.01077 -392.721556)
			(xy 73.066532 -392.766025) (xy 73.116965 -392.816458) (xy 73.161434 -392.87222) (xy 73.19938 -392.932611)
			(xy 73.230325 -392.99687) (xy 73.253882 -393.06419) (xy 73.269752 -393.133725) (xy 73.277738 -393.204599)
			(xy 73.277738 -393.275921) (xy 73.269752 -393.346795) (xy 73.253882 -393.41633) (xy 73.230325 -393.48365)
			(xy 73.19938 -393.547909) (xy 73.161434 -393.6083) (xy 73.116965 -393.664062) (xy 73.066532 -393.714495)
			(xy 73.01077 -393.758964) (xy 72.950379 -393.79691) (xy 72.88612 -393.827855) (xy 72.8188 -393.851412)
			(xy 72.749265 -393.867282) (xy 72.678391 -393.875268) (xy 72.607069 -393.875268) (xy 72.536195 -393.867282)
			(xy 72.46666 -393.851412) (xy 72.39934 -393.827855) (xy 72.335081 -393.79691) (xy 72.27469 -393.758964)
			(xy 72.218928 -393.714495) (xy 72.168495 -393.664062) (xy 72.124026 -393.6083) (xy 72.08608 -393.547909)
			(xy 72.055135 -393.48365) (xy 72.031578 -393.41633) (xy 72.015708 -393.346795) (xy 72.007722 -393.275921)
			(xy 71.348608 -393.275921) (xy 71.340622 -393.346795) (xy 71.324752 -393.41633) (xy 71.301195 -393.48365)
			(xy 71.27025 -393.547909) (xy 71.232304 -393.6083) (xy 71.187835 -393.664062) (xy 71.137402 -393.714495)
			(xy 71.08164 -393.758964) (xy 71.021249 -393.79691) (xy 70.95699 -393.827855) (xy 70.88967 -393.851412)
			(xy 70.820135 -393.867282) (xy 70.749261 -393.875268) (xy 70.677939 -393.875268) (xy 70.607065 -393.867282)
			(xy 70.53753 -393.851412) (xy 70.47021 -393.827855) (xy 70.405951 -393.79691) (xy 70.34556 -393.758964)
			(xy 70.289798 -393.714495) (xy 70.239365 -393.664062) (xy 70.194896 -393.6083) (xy 70.15695 -393.547909)
			(xy 70.126005 -393.48365) (xy 70.102448 -393.41633) (xy 70.086578 -393.346795) (xy 70.078592 -393.275921)
			(xy 69.599492 -393.275921) (xy 69.596658 -393.301075) (xy 69.580788 -393.37061) (xy 69.557231 -393.43793)
			(xy 69.526286 -393.502189) (xy 69.48834 -393.56258) (xy 69.443871 -393.618342) (xy 69.393438 -393.668775)
			(xy 69.337676 -393.713244) (xy 69.277285 -393.75119) (xy 69.213026 -393.782135) (xy 69.145706 -393.805692)
			(xy 69.076171 -393.821562) (xy 69.005297 -393.829548) (xy 68.933975 -393.829548) (xy 68.863101 -393.821562)
			(xy 68.793566 -393.805692) (xy 68.726246 -393.782135) (xy 68.661987 -393.75119) (xy 68.601596 -393.713244)
			(xy 68.545834 -393.668775) (xy 68.495401 -393.618342) (xy 68.450932 -393.56258) (xy 68.412986 -393.502189)
			(xy 68.382041 -393.43793) (xy 68.358484 -393.37061) (xy 68.342614 -393.301075) (xy 68.334628 -393.230201)
			(xy 67.675514 -393.230201) (xy 67.667528 -393.301075) (xy 67.651658 -393.37061) (xy 67.628101 -393.43793)
			(xy 67.597156 -393.502189) (xy 67.55921 -393.56258) (xy 67.514741 -393.618342) (xy 67.464308 -393.668775)
			(xy 67.408546 -393.713244) (xy 67.348155 -393.75119) (xy 67.283896 -393.782135) (xy 67.216576 -393.805692)
			(xy 67.147041 -393.821562) (xy 67.076167 -393.829548) (xy 67.004845 -393.829548) (xy 66.933971 -393.821562)
			(xy 66.864436 -393.805692) (xy 66.797116 -393.782135) (xy 66.732857 -393.75119) (xy 66.672466 -393.713244)
			(xy 66.616704 -393.668775) (xy 66.566271 -393.618342) (xy 66.521802 -393.56258) (xy 66.483856 -393.502189)
			(xy 66.452911 -393.43793) (xy 66.429354 -393.37061) (xy 66.413484 -393.301075) (xy 66.405498 -393.230201)
			(xy 28.341828 -393.230201) (xy 28.341828 -394.722604) (xy 51.208432 -394.722604) (xy 52.85994 -394.722604)
			(xy 52.85994 -396.374112) (xy 51.208432 -396.374112) (xy 51.208432 -394.722604) (xy 28.341828 -394.722604)
			(xy 28.341828 -397.968212) (xy 84.245178 -397.968212) (xy 84.245178 -397.908276) (xy 84.253001 -397.848854)
			(xy 84.268514 -397.790961) (xy 84.29145 -397.735588) (xy 84.321417 -397.683682) (xy 84.357904 -397.636132)
			(xy 84.400284 -397.593752) (xy 84.447834 -397.557265) (xy 84.49974 -397.527298) (xy 84.555113 -397.504362)
			(xy 84.613006 -397.488849) (xy 84.672428 -397.481026) (xy 84.702396 -397.480536) (xy 84.732364 -397.481026)
			(xy 84.791786 -397.488849) (xy 84.849679 -397.504362) (xy 84.905052 -397.527298) (xy 84.956958 -397.557265)
			(xy 85.004508 -397.593752) (xy 85.046888 -397.636132) (xy 85.083375 -397.683682) (xy 85.113342 -397.735588)
			(xy 85.136278 -397.790961) (xy 85.144434 -397.8214) (xy 92.971348 -397.8214) (xy 92.971348 -397.761464)
			(xy 92.979171 -397.702042) (xy 92.994684 -397.644149) (xy 93.01762 -397.588776) (xy 93.047587 -397.53687)
			(xy 93.084074 -397.48932) (xy 93.126454 -397.44694) (xy 93.174004 -397.410453) (xy 93.22591 -397.380486)
			(xy 93.281283 -397.35755) (xy 93.339176 -397.342037) (xy 93.398598 -397.334214) (xy 93.428566 -397.333724)
			(xy 93.458534 -397.334214) (xy 93.517956 -397.342037) (xy 93.575849 -397.35755) (xy 93.631222 -397.380486)
			(xy 93.683128 -397.410453) (xy 93.730678 -397.44694) (xy 93.773058 -397.48932) (xy 93.809545 -397.53687)
			(xy 93.839512 -397.588776) (xy 93.862448 -397.644149) (xy 93.877961 -397.702042) (xy 93.885784 -397.761464)
			(xy 93.885784 -397.8214) (xy 93.877961 -397.880822) (xy 93.862448 -397.938715) (xy 93.839512 -397.994088)
			(xy 93.809545 -398.045994) (xy 93.773058 -398.093544) (xy 93.730678 -398.135924) (xy 93.683128 -398.172411)
			(xy 93.631222 -398.202378) (xy 93.575849 -398.225314) (xy 93.517956 -398.240827) (xy 93.458534 -398.24865)
			(xy 93.398598 -398.24865) (xy 93.339176 -398.240827) (xy 93.281283 -398.225314) (xy 93.22591 -398.202378)
			(xy 93.174004 -398.172411) (xy 93.126454 -398.135924) (xy 93.084074 -398.093544) (xy 93.047587 -398.045994)
			(xy 93.01762 -397.994088) (xy 92.994684 -397.938715) (xy 92.979171 -397.880822) (xy 92.971348 -397.8214)
			(xy 85.144434 -397.8214) (xy 85.151791 -397.848854) (xy 85.159614 -397.908276) (xy 85.159614 -397.968212)
			(xy 85.151791 -398.027634) (xy 85.136278 -398.085527) (xy 85.113342 -398.1409) (xy 85.083375 -398.192806)
			(xy 85.046888 -398.240356) (xy 85.004508 -398.282736) (xy 84.956958 -398.319223) (xy 84.905052 -398.34919)
			(xy 84.849679 -398.372126) (xy 84.791786 -398.387639) (xy 84.732364 -398.395462) (xy 84.672428 -398.395462)
			(xy 84.613006 -398.387639) (xy 84.555113 -398.372126) (xy 84.49974 -398.34919) (xy 84.447834 -398.319223)
			(xy 84.400284 -398.282736) (xy 84.357904 -398.240356) (xy 84.321417 -398.192806) (xy 84.29145 -398.1409)
			(xy 84.268514 -398.085527) (xy 84.253001 -398.027634) (xy 84.245178 -397.968212) (xy 28.341828 -397.968212)
			(xy 28.341828 -399.044664) (xy 81.767662 -399.044664) (xy 81.767662 -398.984728) (xy 81.775485 -398.925306)
			(xy 81.790998 -398.867413) (xy 81.813934 -398.81204) (xy 81.843901 -398.760134) (xy 81.880388 -398.712584)
			(xy 81.922768 -398.670204) (xy 81.970318 -398.633717) (xy 82.022224 -398.60375) (xy 82.077597 -398.580814)
			(xy 82.13549 -398.565301) (xy 82.194912 -398.557478) (xy 82.22488 -398.556988) (xy 82.254848 -398.557478)
			(xy 82.31427 -398.565301) (xy 82.372163 -398.580814) (xy 82.427536 -398.60375) (xy 82.479442 -398.633717)
			(xy 82.526992 -398.670204) (xy 82.569372 -398.712584) (xy 82.605859 -398.760134) (xy 82.635826 -398.81204)
			(xy 82.658762 -398.867413) (xy 82.674275 -398.925306) (xy 82.682098 -398.984728) (xy 82.682098 -399.044664)
			(xy 82.674275 -399.104086) (xy 82.658762 -399.161979) (xy 82.635826 -399.217352) (xy 82.605859 -399.269258)
			(xy 82.580371 -399.302474) (xy 83.210128 -399.302474) (xy 83.210128 -399.242538) (xy 83.217951 -399.183116)
			(xy 83.233464 -399.125223) (xy 83.2564 -399.06985) (xy 83.286367 -399.017944) (xy 83.322854 -398.970394)
			(xy 83.365234 -398.928014) (xy 83.412784 -398.891527) (xy 83.46469 -398.86156) (xy 83.520063 -398.838624)
			(xy 83.577956 -398.823111) (xy 83.637378 -398.815288) (xy 83.667346 -398.814798) (xy 83.697314 -398.815288)
			(xy 83.756736 -398.823111) (xy 83.814629 -398.838624) (xy 83.870002 -398.86156) (xy 83.921908 -398.891527)
			(xy 83.969458 -398.928014) (xy 84.011838 -398.970394) (xy 84.048325 -399.017944) (xy 84.078292 -399.06985)
			(xy 84.101228 -399.125223) (xy 84.116741 -399.183116) (xy 84.124564 -399.242538) (xy 84.124564 -399.302474)
			(xy 84.116741 -399.361896) (xy 84.101228 -399.419789) (xy 84.078292 -399.475162) (xy 84.048325 -399.527068)
			(xy 84.011838 -399.574618) (xy 83.969458 -399.616998) (xy 83.921908 -399.653485) (xy 83.870002 -399.683452)
			(xy 83.814629 -399.706388) (xy 83.756736 -399.721901) (xy 83.697314 -399.729724) (xy 83.637378 -399.729724)
			(xy 83.577956 -399.721901) (xy 83.520063 -399.706388) (xy 83.46469 -399.683452) (xy 83.412784 -399.653485)
			(xy 83.365234 -399.616998) (xy 83.322854 -399.574618) (xy 83.286367 -399.527068) (xy 83.2564 -399.475162)
			(xy 83.233464 -399.419789) (xy 83.217951 -399.361896) (xy 83.210128 -399.302474) (xy 82.580371 -399.302474)
			(xy 82.569372 -399.316808) (xy 82.526992 -399.359188) (xy 82.479442 -399.395675) (xy 82.427536 -399.425642)
			(xy 82.372163 -399.448578) (xy 82.31427 -399.464091) (xy 82.254848 -399.471914) (xy 82.194912 -399.471914)
			(xy 82.13549 -399.464091) (xy 82.077597 -399.448578) (xy 82.022224 -399.425642) (xy 81.970318 -399.395675)
			(xy 81.922768 -399.359188) (xy 81.880388 -399.316808) (xy 81.843901 -399.269258) (xy 81.813934 -399.217352)
			(xy 81.790998 -399.161979) (xy 81.775485 -399.104086) (xy 81.767662 -399.044664) (xy 28.341828 -399.044664)
			(xy 28.341828 -400.301202) (xy 78.81034 -400.301202) (xy 78.81034 -400.241266) (xy 78.818163 -400.181844)
			(xy 78.833676 -400.123951) (xy 78.856612 -400.068578) (xy 78.886579 -400.016672) (xy 78.923066 -399.969122)
			(xy 78.965446 -399.926742) (xy 79.012996 -399.890255) (xy 79.064902 -399.860288) (xy 79.120275 -399.837352)
			(xy 79.178168 -399.821839) (xy 79.23759 -399.814016) (xy 79.267558 -399.813526) (xy 79.297526 -399.814016)
			(xy 79.356948 -399.821839) (xy 79.414841 -399.837352) (xy 79.470214 -399.860288) (xy 79.52212 -399.890255)
			(xy 79.56967 -399.926742) (xy 79.61205 -399.969122) (xy 79.648537 -400.016672) (xy 79.660444 -400.037296)
			(xy 80.122504 -400.037296) (xy 80.122504 -399.97736) (xy 80.130327 -399.917938) (xy 80.14584 -399.860045)
			(xy 80.168776 -399.804672) (xy 80.198743 -399.752766) (xy 80.23523 -399.705216) (xy 80.27761 -399.662836)
			(xy 80.32516 -399.626349) (xy 80.377066 -399.596382) (xy 80.432439 -399.573446) (xy 80.490332 -399.557933)
			(xy 80.549754 -399.55011) (xy 80.579722 -399.54962) (xy 80.60969 -399.55011) (xy 80.669112 -399.557933)
			(xy 80.727005 -399.573446) (xy 80.782378 -399.596382) (xy 80.834284 -399.626349) (xy 80.881834 -399.662836)
			(xy 80.924214 -399.705216) (xy 80.960701 -399.752766) (xy 80.973194 -399.774406) (xy 84.877384 -399.774406)
			(xy 84.877384 -399.71447) (xy 84.885207 -399.655048) (xy 84.90072 -399.597155) (xy 84.923656 -399.541782)
			(xy 84.953623 -399.489876) (xy 84.99011 -399.442326) (xy 85.03249 -399.399946) (xy 85.08004 -399.363459)
			(xy 85.131946 -399.333492) (xy 85.187319 -399.310556) (xy 85.245212 -399.295043) (xy 85.304634 -399.28722)
			(xy 85.334602 -399.28673) (xy 85.36457 -399.28722) (xy 85.423992 -399.295043) (xy 85.481885 -399.310556)
			(xy 85.537258 -399.333492) (xy 85.545565 -399.338288) (xy 86.76689 -399.338288) (xy 86.76689 -399.278352)
			(xy 86.774713 -399.21893) (xy 86.790226 -399.161037) (xy 86.813162 -399.105664) (xy 86.843129 -399.053758)
			(xy 86.879616 -399.006208) (xy 86.921996 -398.963828) (xy 86.969546 -398.927341) (xy 87.021452 -398.897374)
			(xy 87.076825 -398.874438) (xy 87.134718 -398.858925) (xy 87.19414 -398.851102) (xy 87.224108 -398.850612)
			(xy 87.254076 -398.851102) (xy 87.302416 -398.857466) (xy 88.115122 -398.857466) (xy 88.115122 -398.79753)
			(xy 88.122945 -398.738108) (xy 88.138458 -398.680215) (xy 88.161394 -398.624842) (xy 88.191361 -398.572936)
			(xy 88.227848 -398.525386) (xy 88.270228 -398.483006) (xy 88.317778 -398.446519) (xy 88.369684 -398.416552)
			(xy 88.425057 -398.393616) (xy 88.48295 -398.378103) (xy 88.542372 -398.37028) (xy 88.57234 -398.36979)
			(xy 88.602308 -398.37028) (xy 88.66173 -398.378103) (xy 88.719623 -398.393616) (xy 88.774996 -398.416552)
			(xy 88.826902 -398.446519) (xy 88.874452 -398.483006) (xy 88.916832 -398.525386) (xy 88.918859 -398.528028)
			(xy 91.239576 -398.528028) (xy 91.239576 -398.468092) (xy 91.247399 -398.40867) (xy 91.262912 -398.350777)
			(xy 91.285848 -398.295404) (xy 91.315815 -398.243498) (xy 91.352302 -398.195948) (xy 91.394682 -398.153568)
			(xy 91.442232 -398.117081) (xy 91.494138 -398.087114) (xy 91.549511 -398.064178) (xy 91.607404 -398.048665)
			(xy 91.666826 -398.040842) (xy 91.696794 -398.040352) (xy 91.726762 -398.040842) (xy 91.786184 -398.048665)
			(xy 91.844077 -398.064178) (xy 91.89945 -398.087114) (xy 91.951356 -398.117081) (xy 91.998906 -398.153568)
			(xy 92.041286 -398.195948) (xy 92.077773 -398.243498) (xy 92.10774 -398.295404) (xy 92.130676 -398.350777)
			(xy 92.146189 -398.40867) (xy 92.154012 -398.468092) (xy 92.154012 -398.528028) (xy 92.146189 -398.58745)
			(xy 92.130676 -398.645343) (xy 92.10774 -398.700716) (xy 92.077773 -398.752622) (xy 92.041286 -398.800172)
			(xy 91.998906 -398.842552) (xy 91.951356 -398.879039) (xy 91.89945 -398.909006) (xy 91.844077 -398.931942)
			(xy 91.786184 -398.947455) (xy 91.726762 -398.955278) (xy 91.666826 -398.955278) (xy 91.607404 -398.947455)
			(xy 91.549511 -398.931942) (xy 91.494138 -398.909006) (xy 91.442232 -398.879039) (xy 91.394682 -398.842552)
			(xy 91.352302 -398.800172) (xy 91.315815 -398.752622) (xy 91.285848 -398.700716) (xy 91.262912 -398.645343)
			(xy 91.247399 -398.58745) (xy 91.239576 -398.528028) (xy 88.918859 -398.528028) (xy 88.953319 -398.572936)
			(xy 88.983286 -398.624842) (xy 89.006222 -398.680215) (xy 89.021735 -398.738108) (xy 89.029558 -398.79753)
			(xy 89.029558 -398.857466) (xy 89.021735 -398.916888) (xy 89.006222 -398.974781) (xy 88.983286 -399.030154)
			(xy 88.965231 -399.061428) (xy 89.805238 -399.061428) (xy 89.805238 -399.001492) (xy 89.813061 -398.94207)
			(xy 89.828574 -398.884177) (xy 89.85151 -398.828804) (xy 89.881477 -398.776898) (xy 89.917964 -398.729348)
			(xy 89.960344 -398.686968) (xy 90.007894 -398.650481) (xy 90.0598 -398.620514) (xy 90.115173 -398.597578)
			(xy 90.173066 -398.582065) (xy 90.232488 -398.574242) (xy 90.262456 -398.573752) (xy 90.292424 -398.574242)
			(xy 90.351846 -398.582065) (xy 90.409739 -398.597578) (xy 90.465112 -398.620514) (xy 90.517018 -398.650481)
			(xy 90.564568 -398.686968) (xy 90.606948 -398.729348) (xy 90.643435 -398.776898) (xy 90.673402 -398.828804)
			(xy 90.696338 -398.884177) (xy 90.711851 -398.94207) (xy 90.719674 -399.001492) (xy 90.719674 -399.061428)
			(xy 90.711851 -399.12085) (xy 90.696338 -399.178743) (xy 90.673402 -399.234116) (xy 90.643435 -399.286022)
			(xy 90.606948 -399.333572) (xy 90.564568 -399.375952) (xy 90.517018 -399.412439) (xy 90.465112 -399.442406)
			(xy 90.409739 -399.465342) (xy 90.351846 -399.480855) (xy 90.292424 -399.488678) (xy 90.232488 -399.488678)
			(xy 90.173066 -399.480855) (xy 90.115173 -399.465342) (xy 90.0598 -399.442406) (xy 90.007894 -399.412439)
			(xy 89.960344 -399.375952) (xy 89.917964 -399.333572) (xy 89.881477 -399.286022) (xy 89.85151 -399.234116)
			(xy 89.828574 -399.178743) (xy 89.813061 -399.12085) (xy 89.805238 -399.061428) (xy 88.965231 -399.061428)
			(xy 88.953319 -399.08206) (xy 88.916832 -399.12961) (xy 88.874452 -399.17199) (xy 88.826902 -399.208477)
			(xy 88.774996 -399.238444) (xy 88.719623 -399.26138) (xy 88.66173 -399.276893) (xy 88.602308 -399.284716)
			(xy 88.542372 -399.284716) (xy 88.48295 -399.276893) (xy 88.425057 -399.26138) (xy 88.369684 -399.238444)
			(xy 88.317778 -399.208477) (xy 88.270228 -399.17199) (xy 88.227848 -399.12961) (xy 88.191361 -399.08206)
			(xy 88.161394 -399.030154) (xy 88.138458 -398.974781) (xy 88.122945 -398.916888) (xy 88.115122 -398.857466)
			(xy 87.302416 -398.857466) (xy 87.313498 -398.858925) (xy 87.371391 -398.874438) (xy 87.426764 -398.897374)
			(xy 87.47867 -398.927341) (xy 87.52622 -398.963828) (xy 87.5686 -399.006208) (xy 87.605087 -399.053758)
			(xy 87.635054 -399.105664) (xy 87.65799 -399.161037) (xy 87.673503 -399.21893) (xy 87.681326 -399.278352)
			(xy 87.681326 -399.338288) (xy 87.673503 -399.39771) (xy 87.65799 -399.455603) (xy 87.635054 -399.510976)
			(xy 87.605087 -399.562882) (xy 87.5686 -399.610432) (xy 87.52622 -399.652812) (xy 87.47867 -399.689299)
			(xy 87.426764 -399.719266) (xy 87.371391 -399.742202) (xy 87.313498 -399.757715) (xy 87.254076 -399.765538)
			(xy 87.19414 -399.765538) (xy 87.134718 -399.757715) (xy 87.076825 -399.742202) (xy 87.021452 -399.719266)
			(xy 86.969546 -399.689299) (xy 86.921996 -399.652812) (xy 86.879616 -399.610432) (xy 86.843129 -399.562882)
			(xy 86.813162 -399.510976) (xy 86.790226 -399.455603) (xy 86.774713 -399.39771) (xy 86.76689 -399.338288)
			(xy 85.545565 -399.338288) (xy 85.589164 -399.363459) (xy 85.636714 -399.399946) (xy 85.679094 -399.442326)
			(xy 85.715581 -399.489876) (xy 85.745548 -399.541782) (xy 85.768484 -399.597155) (xy 85.783997 -399.655048)
			(xy 85.79182 -399.71447) (xy 85.79182 -399.774406) (xy 85.783997 -399.833828) (xy 85.768484 -399.891721)
			(xy 85.745548 -399.947094) (xy 85.715581 -399.999) (xy 85.679094 -400.04655) (xy 85.636714 -400.08893)
			(xy 85.589164 -400.125417) (xy 85.561857 -400.141182) (xy 87.997012 -400.141182) (xy 87.997012 -400.081246)
			(xy 88.004835 -400.021824) (xy 88.020348 -399.963931) (xy 88.043284 -399.908558) (xy 88.073251 -399.856652)
			(xy 88.109738 -399.809102) (xy 88.152118 -399.766722) (xy 88.199668 -399.730235) (xy 88.251574 -399.700268)
			(xy 88.306947 -399.677332) (xy 88.36484 -399.661819) (xy 88.424262 -399.653996) (xy 88.45423 -399.653506)
			(xy 88.484198 -399.653996) (xy 88.54362 -399.661819) (xy 88.601513 -399.677332) (xy 88.656886 -399.700268)
			(xy 88.708792 -399.730235) (xy 88.756342 -399.766722) (xy 88.798722 -399.809102) (xy 88.835209 -399.856652)
			(xy 88.865176 -399.908558) (xy 88.888112 -399.963931) (xy 88.903625 -400.021824) (xy 88.911448 -400.081246)
			(xy 88.911448 -400.141182) (xy 88.903625 -400.200604) (xy 88.888112 -400.258497) (xy 88.865176 -400.31387)
			(xy 88.835209 -400.365776) (xy 88.798722 -400.413326) (xy 88.756342 -400.455706) (xy 88.708792 -400.492193)
			(xy 88.656886 -400.52216) (xy 88.601513 -400.545096) (xy 88.54362 -400.560609) (xy 88.484198 -400.568432)
			(xy 88.424262 -400.568432) (xy 88.36484 -400.560609) (xy 88.306947 -400.545096) (xy 88.251574 -400.52216)
			(xy 88.199668 -400.492193) (xy 88.152118 -400.455706) (xy 88.109738 -400.413326) (xy 88.073251 -400.365776)
			(xy 88.043284 -400.31387) (xy 88.020348 -400.258497) (xy 88.004835 -400.200604) (xy 87.997012 -400.141182)
			(xy 85.561857 -400.141182) (xy 85.537258 -400.155384) (xy 85.481885 -400.17832) (xy 85.423992 -400.193833)
			(xy 85.36457 -400.201656) (xy 85.304634 -400.201656) (xy 85.245212 -400.193833) (xy 85.187319 -400.17832)
			(xy 85.131946 -400.155384) (xy 85.08004 -400.125417) (xy 85.03249 -400.08893) (xy 84.99011 -400.04655)
			(xy 84.953623 -399.999) (xy 84.923656 -399.947094) (xy 84.90072 -399.891721) (xy 84.885207 -399.833828)
			(xy 84.877384 -399.774406) (xy 80.973194 -399.774406) (xy 80.990668 -399.804672) (xy 81.013604 -399.860045)
			(xy 81.029117 -399.917938) (xy 81.03694 -399.97736) (xy 81.03694 -400.037296) (xy 81.029117 -400.096718)
			(xy 81.013604 -400.154611) (xy 80.990668 -400.209984) (xy 80.960701 -400.26189) (xy 80.924214 -400.30944)
			(xy 80.881834 -400.35182) (xy 80.834284 -400.388307) (xy 80.782378 -400.418274) (xy 80.727005 -400.44121)
			(xy 80.669112 -400.456723) (xy 80.60969 -400.464546) (xy 80.549754 -400.464546) (xy 80.490332 -400.456723)
			(xy 80.432439 -400.44121) (xy 80.377066 -400.418274) (xy 80.32516 -400.388307) (xy 80.27761 -400.35182)
			(xy 80.23523 -400.30944) (xy 80.198743 -400.26189) (xy 80.168776 -400.209984) (xy 80.14584 -400.154611)
			(xy 80.130327 -400.096718) (xy 80.122504 -400.037296) (xy 79.660444 -400.037296) (xy 79.678504 -400.068578)
			(xy 79.70144 -400.123951) (xy 79.716953 -400.181844) (xy 79.724776 -400.241266) (xy 79.724776 -400.301202)
			(xy 79.716953 -400.360624) (xy 79.70144 -400.418517) (xy 79.678504 -400.47389) (xy 79.648537 -400.525796)
			(xy 79.61205 -400.573346) (xy 79.56967 -400.615726) (xy 79.52212 -400.652213) (xy 79.470214 -400.68218)
			(xy 79.414841 -400.705116) (xy 79.356948 -400.720629) (xy 79.297526 -400.728452) (xy 79.23759 -400.728452)
			(xy 79.178168 -400.720629) (xy 79.120275 -400.705116) (xy 79.064902 -400.68218) (xy 79.012996 -400.652213)
			(xy 78.965446 -400.615726) (xy 78.923066 -400.573346) (xy 78.886579 -400.525796) (xy 78.856612 -400.47389)
			(xy 78.833676 -400.418517) (xy 78.818163 -400.360624) (xy 78.81034 -400.301202) (xy 28.341828 -400.301202)
			(xy 28.341828 -406.931047) (xy 39.818567 -406.931047) (xy 39.824576 -406.815126) (xy 39.838567 -406.699897)
			(xy 39.860475 -406.585907) (xy 39.890195 -406.4737) (xy 39.927585 -406.363811) (xy 39.972468 -406.256764)
			(xy 40.024629 -406.153068) (xy 40.08382 -406.053218) (xy 40.149759 -405.957689) (xy 40.222131 -405.866938)
			(xy 40.300592 -405.781395) (xy 40.384767 -405.701469) (xy 40.474256 -405.627542) (xy 40.568632 -405.559964)
			(xy 40.667446 -405.499058) (xy 40.770226 -405.445115) (xy 40.876483 -405.398391) (xy 40.98571 -405.35911)
			(xy 41.097387 -405.327458) (xy 41.210982 -405.303585) (xy 41.325953 -405.287607) (xy 41.441752 -405.279599)
			(xy 41.49979 -405.279098) (xy 41.557828 -405.279599) (xy 41.673627 -405.287607) (xy 41.788598 -405.303585)
			(xy 41.902193 -405.327458) (xy 42.01387 -405.35911) (xy 42.123097 -405.398391) (xy 42.229354 -405.445115)
			(xy 42.332134 -405.499058) (xy 42.430948 -405.559964) (xy 42.474432 -405.591101) (xy 63.647829 -405.591101)
			(xy 63.653878 -405.515531) (xy 63.667925 -405.441033) (xy 63.689811 -405.36845) (xy 63.719288 -405.298604)
			(xy 63.756023 -405.232287) (xy 63.799598 -405.170251) (xy 63.84952 -405.113198) (xy 63.905224 -405.061774)
			(xy 63.966079 -405.016563) (xy 64.031394 -404.978076) (xy 64.10043 -404.94675) (xy 64.172405 -404.92294)
			(xy 64.246503 -404.906915) (xy 64.321884 -404.898856) (xy 64.35979 -404.898352) (xy 64.397696 -404.898856)
			(xy 64.473077 -404.906915) (xy 64.547175 -404.92294) (xy 64.61915 -404.94675) (xy 64.688186 -404.978076)
			(xy 64.753501 -405.016563) (xy 64.814356 -405.061774) (xy 64.87006 -405.113198) (xy 64.919982 -405.170251)
			(xy 64.963557 -405.232287) (xy 65.000292 -405.298604) (xy 65.029769 -405.36845) (xy 65.051655 -405.441033)
			(xy 65.065702 -405.515531) (xy 65.071751 -405.591101) (xy 66.187829 -405.591101) (xy 66.193878 -405.515531)
			(xy 66.207925 -405.441033) (xy 66.229811 -405.36845) (xy 66.259288 -405.298604) (xy 66.296023 -405.232287)
			(xy 66.339598 -405.170251) (xy 66.38952 -405.113198) (xy 66.445224 -405.061774) (xy 66.506079 -405.016563)
			(xy 66.571394 -404.978076) (xy 66.64043 -404.94675) (xy 66.712405 -404.92294) (xy 66.786503 -404.906915)
			(xy 66.861884 -404.898856) (xy 66.89979 -404.898352) (xy 66.937696 -404.898856) (xy 67.013077 -404.906915)
			(xy 67.087175 -404.92294) (xy 67.15915 -404.94675) (xy 67.228186 -404.978076) (xy 67.293501 -405.016563)
			(xy 67.354356 -405.061774) (xy 67.41006 -405.113198) (xy 67.459982 -405.170251) (xy 67.503557 -405.232287)
			(xy 67.540292 -405.298604) (xy 67.569769 -405.36845) (xy 67.591655 -405.441033) (xy 67.605702 -405.515531)
			(xy 67.611751 -405.591101) (xy 68.727829 -405.591101) (xy 68.733878 -405.515531) (xy 68.747925 -405.441033)
			(xy 68.769811 -405.36845) (xy 68.799288 -405.298604) (xy 68.836023 -405.232287) (xy 68.879598 -405.170251)
			(xy 68.92952 -405.113198) (xy 68.985224 -405.061774) (xy 69.046079 -405.016563) (xy 69.111394 -404.978076)
			(xy 69.18043 -404.94675) (xy 69.252405 -404.92294) (xy 69.326503 -404.906915) (xy 69.401884 -404.898856)
			(xy 69.43979 -404.898352) (xy 69.477696 -404.898856) (xy 69.553077 -404.906915) (xy 69.627175 -404.92294)
			(xy 69.69915 -404.94675) (xy 69.768186 -404.978076) (xy 69.833501 -405.016563) (xy 69.894356 -405.061774)
			(xy 69.95006 -405.113198) (xy 69.999982 -405.170251) (xy 70.043557 -405.232287) (xy 70.080292 -405.298604)
			(xy 70.109769 -405.36845) (xy 70.131655 -405.441033) (xy 70.145702 -405.515531) (xy 70.151751 -405.591101)
			(xy 71.267829 -405.591101) (xy 71.273878 -405.515531) (xy 71.287925 -405.441033) (xy 71.309811 -405.36845)
			(xy 71.339288 -405.298604) (xy 71.376023 -405.232287) (xy 71.419598 -405.170251) (xy 71.46952 -405.113198)
			(xy 71.525224 -405.061774) (xy 71.586079 -405.016563) (xy 71.651394 -404.978076) (xy 71.72043 -404.94675)
			(xy 71.792405 -404.92294) (xy 71.866503 -404.906915) (xy 71.941884 -404.898856) (xy 71.97979 -404.898352)
			(xy 72.017696 -404.898856) (xy 72.093077 -404.906915) (xy 72.167175 -404.92294) (xy 72.23915 -404.94675)
			(xy 72.308186 -404.978076) (xy 72.373501 -405.016563) (xy 72.434356 -405.061774) (xy 72.49006 -405.113198)
			(xy 72.539982 -405.170251) (xy 72.583557 -405.232287) (xy 72.620292 -405.298604) (xy 72.649769 -405.36845)
			(xy 72.671655 -405.441033) (xy 72.685702 -405.515531) (xy 72.691751 -405.591101) (xy 73.807829 -405.591101)
			(xy 73.813878 -405.515531) (xy 73.827925 -405.441033) (xy 73.849811 -405.36845) (xy 73.879288 -405.298604)
			(xy 73.916023 -405.232287) (xy 73.959598 -405.170251) (xy 74.00952 -405.113198) (xy 74.065224 -405.061774)
			(xy 74.126079 -405.016563) (xy 74.191394 -404.978076) (xy 74.26043 -404.94675) (xy 74.332405 -404.92294)
			(xy 74.406503 -404.906915) (xy 74.481884 -404.898856) (xy 74.51979 -404.898352) (xy 74.557696 -404.898856)
			(xy 74.633077 -404.906915) (xy 74.707175 -404.92294) (xy 74.77915 -404.94675) (xy 74.848186 -404.978076)
			(xy 74.913501 -405.016563) (xy 74.974356 -405.061774) (xy 75.03006 -405.113198) (xy 75.079982 -405.170251)
			(xy 75.123557 -405.232287) (xy 75.160292 -405.298604) (xy 75.189769 -405.36845) (xy 75.211655 -405.441033)
			(xy 75.225702 -405.515531) (xy 75.231751 -405.591101) (xy 76.347829 -405.591101) (xy 76.353878 -405.515531)
			(xy 76.367925 -405.441033) (xy 76.389811 -405.36845) (xy 76.419288 -405.298604) (xy 76.456023 -405.232287)
			(xy 76.499598 -405.170251) (xy 76.54952 -405.113198) (xy 76.605224 -405.061774) (xy 76.666079 -405.016563)
			(xy 76.731394 -404.978076) (xy 76.80043 -404.94675) (xy 76.872405 -404.92294) (xy 76.946503 -404.906915)
			(xy 77.021884 -404.898856) (xy 77.05979 -404.898352) (xy 77.097696 -404.898856) (xy 77.173077 -404.906915)
			(xy 77.247175 -404.92294) (xy 77.31915 -404.94675) (xy 77.388186 -404.978076) (xy 77.453501 -405.016563)
			(xy 77.514356 -405.061774) (xy 77.57006 -405.113198) (xy 77.619982 -405.170251) (xy 77.663557 -405.232287)
			(xy 77.700292 -405.298604) (xy 77.729769 -405.36845) (xy 77.751655 -405.441033) (xy 77.765702 -405.515531)
			(xy 77.771751 -405.591101) (xy 78.887829 -405.591101) (xy 78.893878 -405.515531) (xy 78.907925 -405.441033)
			(xy 78.929811 -405.36845) (xy 78.959288 -405.298604) (xy 78.996023 -405.232287) (xy 79.039598 -405.170251)
			(xy 79.08952 -405.113198) (xy 79.145224 -405.061774) (xy 79.206079 -405.016563) (xy 79.271394 -404.978076)
			(xy 79.34043 -404.94675) (xy 79.412405 -404.92294) (xy 79.486503 -404.906915) (xy 79.561884 -404.898856)
			(xy 79.59979 -404.898352) (xy 79.637696 -404.898856) (xy 79.713077 -404.906915) (xy 79.787175 -404.92294)
			(xy 79.85915 -404.94675) (xy 79.928186 -404.978076) (xy 79.993501 -405.016563) (xy 80.054356 -405.061774)
			(xy 80.11006 -405.113198) (xy 80.159982 -405.170251) (xy 80.203557 -405.232287) (xy 80.240292 -405.298604)
			(xy 80.269769 -405.36845) (xy 80.291655 -405.441033) (xy 80.305702 -405.515531) (xy 80.311751 -405.591101)
			(xy 81.427829 -405.591101) (xy 81.433878 -405.515531) (xy 81.447925 -405.441033) (xy 81.469811 -405.36845)
			(xy 81.499288 -405.298604) (xy 81.536023 -405.232287) (xy 81.579598 -405.170251) (xy 81.62952 -405.113198)
			(xy 81.685224 -405.061774) (xy 81.746079 -405.016563) (xy 81.811394 -404.978076) (xy 81.88043 -404.94675)
			(xy 81.952405 -404.92294) (xy 82.026503 -404.906915) (xy 82.101884 -404.898856) (xy 82.13979 -404.898352)
			(xy 82.177696 -404.898856) (xy 82.253077 -404.906915) (xy 82.327175 -404.92294) (xy 82.39915 -404.94675)
			(xy 82.468186 -404.978076) (xy 82.533501 -405.016563) (xy 82.559813 -405.036111) (xy 86.197949 -405.036111)
			(xy 86.203998 -404.960541) (xy 86.218045 -404.886043) (xy 86.239931 -404.81346) (xy 86.269408 -404.743614)
			(xy 86.306143 -404.677297) (xy 86.349718 -404.615261) (xy 86.39964 -404.558208) (xy 86.455344 -404.506784)
			(xy 86.516199 -404.461573) (xy 86.581514 -404.423086) (xy 86.65055 -404.39176) (xy 86.722525 -404.36795)
			(xy 86.796623 -404.351925) (xy 86.872004 -404.343866) (xy 86.90991 -404.343362) (xy 86.947816 -404.343866)
			(xy 87.023197 -404.351925) (xy 87.097295 -404.36795) (xy 87.16927 -404.39176) (xy 87.238306 -404.423086)
			(xy 87.303621 -404.461573) (xy 87.364476 -404.506784) (xy 87.42018 -404.558208) (xy 87.470102 -404.615261)
			(xy 87.513677 -404.677297) (xy 87.550412 -404.743614) (xy 87.579889 -404.81346) (xy 87.601775 -404.886043)
			(xy 87.615822 -404.960541) (xy 87.621871 -405.036111) (xy 88.737949 -405.036111) (xy 88.743998 -404.960541)
			(xy 88.758045 -404.886043) (xy 88.779931 -404.81346) (xy 88.809408 -404.743614) (xy 88.846143 -404.677297)
			(xy 88.889718 -404.615261) (xy 88.93964 -404.558208) (xy 88.995344 -404.506784) (xy 89.056199 -404.461573)
			(xy 89.121514 -404.423086) (xy 89.19055 -404.39176) (xy 89.262525 -404.36795) (xy 89.336623 -404.351925)
			(xy 89.412004 -404.343866) (xy 89.44991 -404.343362) (xy 89.487816 -404.343866) (xy 89.563197 -404.351925)
			(xy 89.637295 -404.36795) (xy 89.70927 -404.39176) (xy 89.778306 -404.423086) (xy 89.843621 -404.461573)
			(xy 89.904476 -404.506784) (xy 89.96018 -404.558208) (xy 90.010102 -404.615261) (xy 90.053677 -404.677297)
			(xy 90.090412 -404.743614) (xy 90.119889 -404.81346) (xy 90.141775 -404.886043) (xy 90.155822 -404.960541)
			(xy 90.161871 -405.036111) (xy 91.277949 -405.036111) (xy 91.283998 -404.960541) (xy 91.298045 -404.886043)
			(xy 91.319931 -404.81346) (xy 91.349408 -404.743614) (xy 91.386143 -404.677297) (xy 91.429718 -404.615261)
			(xy 91.47964 -404.558208) (xy 91.535344 -404.506784) (xy 91.596199 -404.461573) (xy 91.661514 -404.423086)
			(xy 91.73055 -404.39176) (xy 91.802525 -404.36795) (xy 91.876623 -404.351925) (xy 91.952004 -404.343866)
			(xy 91.98991 -404.343362) (xy 92.027816 -404.343866) (xy 92.103197 -404.351925) (xy 92.177295 -404.36795)
			(xy 92.24927 -404.39176) (xy 92.318306 -404.423086) (xy 92.383621 -404.461573) (xy 92.444476 -404.506784)
			(xy 92.50018 -404.558208) (xy 92.550102 -404.615261) (xy 92.593677 -404.677297) (xy 92.630412 -404.743614)
			(xy 92.659889 -404.81346) (xy 92.681775 -404.886043) (xy 92.695822 -404.960541) (xy 92.701871 -405.036111)
			(xy 92.699852 -405.111895) (xy 92.68979 -405.187035) (xy 92.671798 -405.26068) (xy 92.64608 -405.331996)
			(xy 92.612928 -405.400173) (xy 92.572716 -405.464441) (xy 92.525901 -405.52407) (xy 92.473013 -405.578386)
			(xy 92.414651 -405.626772) (xy 92.351476 -405.66868) (xy 92.284205 -405.703636) (xy 92.2136 -405.731243)
			(xy 92.140459 -405.751189) (xy 92.065614 -405.763248) (xy 91.98991 -405.767283) (xy 91.914206 -405.763248)
			(xy 91.839361 -405.751189) (xy 91.76622 -405.731243) (xy 91.695615 -405.703636) (xy 91.628344 -405.66868)
			(xy 91.565169 -405.626772) (xy 91.506807 -405.578386) (xy 91.453919 -405.52407) (xy 91.407104 -405.464441)
			(xy 91.366892 -405.400173) (xy 91.33374 -405.331996) (xy 91.308022 -405.26068) (xy 91.29003 -405.187035)
			(xy 91.279968 -405.111895) (xy 91.277949 -405.036111) (xy 90.161871 -405.036111) (xy 90.159852 -405.111895)
			(xy 90.14979 -405.187035) (xy 90.131798 -405.26068) (xy 90.10608 -405.331996) (xy 90.072928 -405.400173)
			(xy 90.032716 -405.464441) (xy 89.985901 -405.52407) (xy 89.933013 -405.578386) (xy 89.874651 -405.626772)
			(xy 89.811476 -405.66868) (xy 89.744205 -405.703636) (xy 89.6736 -405.731243) (xy 89.600459 -405.751189)
			(xy 89.525614 -405.763248) (xy 89.44991 -405.767283) (xy 89.374206 -405.763248) (xy 89.299361 -405.751189)
			(xy 89.22622 -405.731243) (xy 89.155615 -405.703636) (xy 89.088344 -405.66868) (xy 89.025169 -405.626772)
			(xy 88.966807 -405.578386) (xy 88.913919 -405.52407) (xy 88.867104 -405.464441) (xy 88.826892 -405.400173)
			(xy 88.79374 -405.331996) (xy 88.768022 -405.26068) (xy 88.75003 -405.187035) (xy 88.739968 -405.111895)
			(xy 88.737949 -405.036111) (xy 87.621871 -405.036111) (xy 87.619852 -405.111895) (xy 87.60979 -405.187035)
			(xy 87.591798 -405.26068) (xy 87.56608 -405.331996) (xy 87.532928 -405.400173) (xy 87.492716 -405.464441)
			(xy 87.445901 -405.52407) (xy 87.393013 -405.578386) (xy 87.334651 -405.626772) (xy 87.271476 -405.66868)
			(xy 87.204205 -405.703636) (xy 87.1336 -405.731243) (xy 87.060459 -405.751189) (xy 86.985614 -405.763248)
			(xy 86.90991 -405.767283) (xy 86.834206 -405.763248) (xy 86.759361 -405.751189) (xy 86.68622 -405.731243)
			(xy 86.615615 -405.703636) (xy 86.548344 -405.66868) (xy 86.485169 -405.626772) (xy 86.426807 -405.578386)
			(xy 86.373919 -405.52407) (xy 86.327104 -405.464441) (xy 86.286892 -405.400173) (xy 86.25374 -405.331996)
			(xy 86.228022 -405.26068) (xy 86.21003 -405.187035) (xy 86.199968 -405.111895) (xy 86.197949 -405.036111)
			(xy 82.559813 -405.036111) (xy 82.594356 -405.061774) (xy 82.65006 -405.113198) (xy 82.699982 -405.170251)
			(xy 82.743557 -405.232287) (xy 82.780292 -405.298604) (xy 82.809769 -405.36845) (xy 82.831655 -405.441033)
			(xy 82.845702 -405.515531) (xy 82.851751 -405.591101) (xy 82.849732 -405.666885) (xy 82.83967 -405.742025)
			(xy 82.821678 -405.81567) (xy 82.79596 -405.886986) (xy 82.762808 -405.955163) (xy 82.722596 -406.019431)
			(xy 82.675781 -406.07906) (xy 82.622893 -406.133376) (xy 82.564531 -406.181762) (xy 82.501356 -406.22367)
			(xy 82.434085 -406.258626) (xy 82.36348 -406.286233) (xy 82.290588 -406.306111) (xy 84.927949 -406.306111)
			(xy 84.933998 -406.230541) (xy 84.948045 -406.156043) (xy 84.969931 -406.08346) (xy 84.999408 -406.013614)
			(xy 85.036143 -405.947297) (xy 85.079718 -405.885261) (xy 85.12964 -405.828208) (xy 85.185344 -405.776784)
			(xy 85.246199 -405.731573) (xy 85.311514 -405.693086) (xy 85.38055 -405.66176) (xy 85.452525 -405.63795)
			(xy 85.526623 -405.621925) (xy 85.602004 -405.613866) (xy 85.63991 -405.613362) (xy 85.677816 -405.613866)
			(xy 85.753197 -405.621925) (xy 85.827295 -405.63795) (xy 85.89927 -405.66176) (xy 85.968306 -405.693086)
			(xy 86.033621 -405.731573) (xy 86.094476 -405.776784) (xy 86.15018 -405.828208) (xy 86.200102 -405.885261)
			(xy 86.243677 -405.947297) (xy 86.280412 -406.013614) (xy 86.309889 -406.08346) (xy 86.331775 -406.156043)
			(xy 86.345822 -406.230541) (xy 86.351871 -406.306111) (xy 87.467949 -406.306111) (xy 87.473998 -406.230541)
			(xy 87.488045 -406.156043) (xy 87.509931 -406.08346) (xy 87.539408 -406.013614) (xy 87.576143 -405.947297)
			(xy 87.619718 -405.885261) (xy 87.66964 -405.828208) (xy 87.725344 -405.776784) (xy 87.786199 -405.731573)
			(xy 87.851514 -405.693086) (xy 87.92055 -405.66176) (xy 87.992525 -405.63795) (xy 88.066623 -405.621925)
			(xy 88.142004 -405.613866) (xy 88.17991 -405.613362) (xy 88.217816 -405.613866) (xy 88.293197 -405.621925)
			(xy 88.367295 -405.63795) (xy 88.43927 -405.66176) (xy 88.508306 -405.693086) (xy 88.573621 -405.731573)
			(xy 88.634476 -405.776784) (xy 88.69018 -405.828208) (xy 88.740102 -405.885261) (xy 88.783677 -405.947297)
			(xy 88.820412 -406.013614) (xy 88.849889 -406.08346) (xy 88.871775 -406.156043) (xy 88.885822 -406.230541)
			(xy 88.891871 -406.306111) (xy 90.007949 -406.306111) (xy 90.013998 -406.230541) (xy 90.028045 -406.156043)
			(xy 90.049931 -406.08346) (xy 90.079408 -406.013614) (xy 90.116143 -405.947297) (xy 90.159718 -405.885261)
			(xy 90.20964 -405.828208) (xy 90.265344 -405.776784) (xy 90.326199 -405.731573) (xy 90.391514 -405.693086)
			(xy 90.46055 -405.66176) (xy 90.532525 -405.63795) (xy 90.606623 -405.621925) (xy 90.682004 -405.613866)
			(xy 90.71991 -405.613362) (xy 90.757816 -405.613866) (xy 90.833197 -405.621925) (xy 90.907295 -405.63795)
			(xy 90.97927 -405.66176) (xy 91.048306 -405.693086) (xy 91.113621 -405.731573) (xy 91.174476 -405.776784)
			(xy 91.23018 -405.828208) (xy 91.280102 -405.885261) (xy 91.323677 -405.947297) (xy 91.360412 -406.013614)
			(xy 91.389889 -406.08346) (xy 91.411775 -406.156043) (xy 91.425822 -406.230541) (xy 91.431871 -406.306111)
			(xy 91.429852 -406.381895) (xy 91.41979 -406.457035) (xy 91.401798 -406.53068) (xy 91.37608 -406.601996)
			(xy 91.342928 -406.670173) (xy 91.302716 -406.734441) (xy 91.255901 -406.79407) (xy 91.203013 -406.848386)
			(xy 91.144651 -406.896772) (xy 91.081476 -406.93868) (xy 91.014205 -406.973636) (xy 90.9436 -407.001243)
			(xy 90.870459 -407.021189) (xy 90.795614 -407.033248) (xy 90.71991 -407.037283) (xy 90.644206 -407.033248)
			(xy 90.569361 -407.021189) (xy 90.49622 -407.001243) (xy 90.425615 -406.973636) (xy 90.358344 -406.93868)
			(xy 90.295169 -406.896772) (xy 90.236807 -406.848386) (xy 90.183919 -406.79407) (xy 90.137104 -406.734441)
			(xy 90.096892 -406.670173) (xy 90.06374 -406.601996) (xy 90.038022 -406.53068) (xy 90.02003 -406.457035)
			(xy 90.009968 -406.381895) (xy 90.007949 -406.306111) (xy 88.891871 -406.306111) (xy 88.889852 -406.381895)
			(xy 88.87979 -406.457035) (xy 88.861798 -406.53068) (xy 88.83608 -406.601996) (xy 88.802928 -406.670173)
			(xy 88.762716 -406.734441) (xy 88.715901 -406.79407) (xy 88.663013 -406.848386) (xy 88.604651 -406.896772)
			(xy 88.541476 -406.93868) (xy 88.474205 -406.973636) (xy 88.4036 -407.001243) (xy 88.330459 -407.021189)
			(xy 88.255614 -407.033248) (xy 88.17991 -407.037283) (xy 88.104206 -407.033248) (xy 88.029361 -407.021189)
			(xy 87.95622 -407.001243) (xy 87.885615 -406.973636) (xy 87.818344 -406.93868) (xy 87.755169 -406.896772)
			(xy 87.696807 -406.848386) (xy 87.643919 -406.79407) (xy 87.597104 -406.734441) (xy 87.556892 -406.670173)
			(xy 87.52374 -406.601996) (xy 87.498022 -406.53068) (xy 87.48003 -406.457035) (xy 87.469968 -406.381895)
			(xy 87.467949 -406.306111) (xy 86.351871 -406.306111) (xy 86.349852 -406.381895) (xy 86.33979 -406.457035)
			(xy 86.321798 -406.53068) (xy 86.29608 -406.601996) (xy 86.262928 -406.670173) (xy 86.222716 -406.734441)
			(xy 86.175901 -406.79407) (xy 86.123013 -406.848386) (xy 86.064651 -406.896772) (xy 86.001476 -406.93868)
			(xy 85.934205 -406.973636) (xy 85.8636 -407.001243) (xy 85.790459 -407.021189) (xy 85.715614 -407.033248)
			(xy 85.63991 -407.037283) (xy 85.564206 -407.033248) (xy 85.489361 -407.021189) (xy 85.41622 -407.001243)
			(xy 85.345615 -406.973636) (xy 85.278344 -406.93868) (xy 85.215169 -406.896772) (xy 85.156807 -406.848386)
			(xy 85.103919 -406.79407) (xy 85.057104 -406.734441) (xy 85.016892 -406.670173) (xy 84.98374 -406.601996)
			(xy 84.958022 -406.53068) (xy 84.94003 -406.457035) (xy 84.929968 -406.381895) (xy 84.927949 -406.306111)
			(xy 82.290588 -406.306111) (xy 82.290339 -406.306179) (xy 82.215494 -406.318238) (xy 82.13979 -406.322273)
			(xy 82.064086 -406.318238) (xy 81.989241 -406.306179) (xy 81.9161 -406.286233) (xy 81.845495 -406.258626)
			(xy 81.778224 -406.22367) (xy 81.715049 -406.181762) (xy 81.656687 -406.133376) (xy 81.603799 -406.07906)
			(xy 81.556984 -406.019431) (xy 81.516772 -405.955163) (xy 81.48362 -405.886986) (xy 81.457902 -405.81567)
			(xy 81.43991 -405.742025) (xy 81.429848 -405.666885) (xy 81.427829 -405.591101) (xy 80.311751 -405.591101)
			(xy 80.309732 -405.666885) (xy 80.29967 -405.742025) (xy 80.281678 -405.81567) (xy 80.25596 -405.886986)
			(xy 80.222808 -405.955163) (xy 80.182596 -406.019431) (xy 80.135781 -406.07906) (xy 80.082893 -406.133376)
			(xy 80.024531 -406.181762) (xy 79.961356 -406.22367) (xy 79.894085 -406.258626) (xy 79.82348 -406.286233)
			(xy 79.750339 -406.306179) (xy 79.675494 -406.318238) (xy 79.59979 -406.322273) (xy 79.524086 -406.318238)
			(xy 79.449241 -406.306179) (xy 79.3761 -406.286233) (xy 79.305495 -406.258626) (xy 79.238224 -406.22367)
			(xy 79.175049 -406.181762) (xy 79.116687 -406.133376) (xy 79.063799 -406.07906) (xy 79.016984 -406.019431)
			(xy 78.976772 -405.955163) (xy 78.94362 -405.886986) (xy 78.917902 -405.81567) (xy 78.89991 -405.742025)
			(xy 78.889848 -405.666885) (xy 78.887829 -405.591101) (xy 77.771751 -405.591101) (xy 77.769732 -405.666885)
			(xy 77.75967 -405.742025) (xy 77.741678 -405.81567) (xy 77.71596 -405.886986) (xy 77.682808 -405.955163)
			(xy 77.642596 -406.019431) (xy 77.595781 -406.07906) (xy 77.542893 -406.133376) (xy 77.484531 -406.181762)
			(xy 77.421356 -406.22367) (xy 77.354085 -406.258626) (xy 77.28348 -406.286233) (xy 77.210339 -406.306179)
			(xy 77.135494 -406.318238) (xy 77.05979 -406.322273) (xy 76.984086 -406.318238) (xy 76.909241 -406.306179)
			(xy 76.8361 -406.286233) (xy 76.765495 -406.258626) (xy 76.698224 -406.22367) (xy 76.635049 -406.181762)
			(xy 76.576687 -406.133376) (xy 76.523799 -406.07906) (xy 76.476984 -406.019431) (xy 76.436772 -405.955163)
			(xy 76.40362 -405.886986) (xy 76.377902 -405.81567) (xy 76.35991 -405.742025) (xy 76.349848 -405.666885)
			(xy 76.347829 -405.591101) (xy 75.231751 -405.591101) (xy 75.229732 -405.666885) (xy 75.21967 -405.742025)
			(xy 75.201678 -405.81567) (xy 75.17596 -405.886986) (xy 75.142808 -405.955163) (xy 75.102596 -406.019431)
			(xy 75.055781 -406.07906) (xy 75.002893 -406.133376) (xy 74.944531 -406.181762) (xy 74.881356 -406.22367)
			(xy 74.814085 -406.258626) (xy 74.74348 -406.286233) (xy 74.670339 -406.306179) (xy 74.595494 -406.318238)
			(xy 74.51979 -406.322273) (xy 74.444086 -406.318238) (xy 74.369241 -406.306179) (xy 74.2961 -406.286233)
			(xy 74.225495 -406.258626) (xy 74.158224 -406.22367) (xy 74.095049 -406.181762) (xy 74.036687 -406.133376)
			(xy 73.983799 -406.07906) (xy 73.936984 -406.019431) (xy 73.896772 -405.955163) (xy 73.86362 -405.886986)
			(xy 73.837902 -405.81567) (xy 73.81991 -405.742025) (xy 73.809848 -405.666885) (xy 73.807829 -405.591101)
			(xy 72.691751 -405.591101) (xy 72.689732 -405.666885) (xy 72.67967 -405.742025) (xy 72.661678 -405.81567)
			(xy 72.63596 -405.886986) (xy 72.602808 -405.955163) (xy 72.562596 -406.019431) (xy 72.515781 -406.07906)
			(xy 72.462893 -406.133376) (xy 72.404531 -406.181762) (xy 72.341356 -406.22367) (xy 72.274085 -406.258626)
			(xy 72.20348 -406.286233) (xy 72.130339 -406.306179) (xy 72.055494 -406.318238) (xy 71.97979 -406.322273)
			(xy 71.904086 -406.318238) (xy 71.829241 -406.306179) (xy 71.7561 -406.286233) (xy 71.685495 -406.258626)
			(xy 71.618224 -406.22367) (xy 71.555049 -406.181762) (xy 71.496687 -406.133376) (xy 71.443799 -406.07906)
			(xy 71.396984 -406.019431) (xy 71.356772 -405.955163) (xy 71.32362 -405.886986) (xy 71.297902 -405.81567)
			(xy 71.27991 -405.742025) (xy 71.269848 -405.666885) (xy 71.267829 -405.591101) (xy 70.151751 -405.591101)
			(xy 70.149732 -405.666885) (xy 70.13967 -405.742025) (xy 70.121678 -405.81567) (xy 70.09596 -405.886986)
			(xy 70.062808 -405.955163) (xy 70.022596 -406.019431) (xy 69.975781 -406.07906) (xy 69.922893 -406.133376)
			(xy 69.864531 -406.181762) (xy 69.801356 -406.22367) (xy 69.734085 -406.258626) (xy 69.66348 -406.286233)
			(xy 69.590339 -406.306179) (xy 69.515494 -406.318238) (xy 69.43979 -406.322273) (xy 69.364086 -406.318238)
			(xy 69.289241 -406.306179) (xy 69.2161 -406.286233) (xy 69.145495 -406.258626) (xy 69.078224 -406.22367)
			(xy 69.015049 -406.181762) (xy 68.956687 -406.133376) (xy 68.903799 -406.07906) (xy 68.856984 -406.019431)
			(xy 68.816772 -405.955163) (xy 68.78362 -405.886986) (xy 68.757902 -405.81567) (xy 68.73991 -405.742025)
			(xy 68.729848 -405.666885) (xy 68.727829 -405.591101) (xy 67.611751 -405.591101) (xy 67.609732 -405.666885)
			(xy 67.59967 -405.742025) (xy 67.581678 -405.81567) (xy 67.55596 -405.886986) (xy 67.522808 -405.955163)
			(xy 67.482596 -406.019431) (xy 67.435781 -406.07906) (xy 67.382893 -406.133376) (xy 67.324531 -406.181762)
			(xy 67.261356 -406.22367) (xy 67.194085 -406.258626) (xy 67.12348 -406.286233) (xy 67.050339 -406.306179)
			(xy 66.975494 -406.318238) (xy 66.89979 -406.322273) (xy 66.824086 -406.318238) (xy 66.749241 -406.306179)
			(xy 66.6761 -406.286233) (xy 66.605495 -406.258626) (xy 66.538224 -406.22367) (xy 66.475049 -406.181762)
			(xy 66.416687 -406.133376) (xy 66.363799 -406.07906) (xy 66.316984 -406.019431) (xy 66.276772 -405.955163)
			(xy 66.24362 -405.886986) (xy 66.217902 -405.81567) (xy 66.19991 -405.742025) (xy 66.189848 -405.666885)
			(xy 66.187829 -405.591101) (xy 65.071751 -405.591101) (xy 65.069732 -405.666885) (xy 65.05967 -405.742025)
			(xy 65.041678 -405.81567) (xy 65.01596 -405.886986) (xy 64.982808 -405.955163) (xy 64.942596 -406.019431)
			(xy 64.895781 -406.07906) (xy 64.842893 -406.133376) (xy 64.784531 -406.181762) (xy 64.721356 -406.22367)
			(xy 64.654085 -406.258626) (xy 64.58348 -406.286233) (xy 64.510339 -406.306179) (xy 64.435494 -406.318238)
			(xy 64.35979 -406.322273) (xy 64.284086 -406.318238) (xy 64.209241 -406.306179) (xy 64.1361 -406.286233)
			(xy 64.065495 -406.258626) (xy 63.998224 -406.22367) (xy 63.935049 -406.181762) (xy 63.876687 -406.133376)
			(xy 63.823799 -406.07906) (xy 63.776984 -406.019431) (xy 63.736772 -405.955163) (xy 63.70362 -405.886986)
			(xy 63.677902 -405.81567) (xy 63.65991 -405.742025) (xy 63.649848 -405.666885) (xy 63.647829 -405.591101)
			(xy 42.474432 -405.591101) (xy 42.525324 -405.627542) (xy 42.614813 -405.701469) (xy 42.698988 -405.781395)
			(xy 42.777449 -405.866938) (xy 42.849821 -405.957689) (xy 42.91576 -406.053218) (xy 42.974951 -406.153068)
			(xy 43.027112 -406.256764) (xy 43.071995 -406.363811) (xy 43.109385 -406.4737) (xy 43.139105 -406.585907)
			(xy 43.161013 -406.699897) (xy 43.175004 -406.815126) (xy 43.181013 -406.931047) (xy 43.179009 -407.047105)
			(xy 43.169003 -407.162749) (xy 43.151043 -407.277427) (xy 43.125213 -407.390593) (xy 43.091638 -407.501707)
			(xy 43.06342 -407.576111) (xy 86.197949 -407.576111) (xy 86.203998 -407.500541) (xy 86.218045 -407.426043)
			(xy 86.239931 -407.35346) (xy 86.269408 -407.283614) (xy 86.306143 -407.217297) (xy 86.349718 -407.155261)
			(xy 86.39964 -407.098208) (xy 86.455344 -407.046784) (xy 86.516199 -407.001573) (xy 86.581514 -406.963086)
			(xy 86.65055 -406.93176) (xy 86.722525 -406.90795) (xy 86.796623 -406.891925) (xy 86.872004 -406.883866)
			(xy 86.90991 -406.883362) (xy 86.947816 -406.883866) (xy 87.023197 -406.891925) (xy 87.097295 -406.90795)
			(xy 87.16927 -406.93176) (xy 87.238306 -406.963086) (xy 87.303621 -407.001573) (xy 87.364476 -407.046784)
			(xy 87.42018 -407.098208) (xy 87.470102 -407.155261) (xy 87.513677 -407.217297) (xy 87.550412 -407.283614)
			(xy 87.579889 -407.35346) (xy 87.601775 -407.426043) (xy 87.615822 -407.500541) (xy 87.621871 -407.576111)
			(xy 88.737949 -407.576111) (xy 88.743998 -407.500541) (xy 88.758045 -407.426043) (xy 88.779931 -407.35346)
			(xy 88.809408 -407.283614) (xy 88.846143 -407.217297) (xy 88.889718 -407.155261) (xy 88.93964 -407.098208)
			(xy 88.995344 -407.046784) (xy 89.056199 -407.001573) (xy 89.121514 -406.963086) (xy 89.19055 -406.93176)
			(xy 89.262525 -406.90795) (xy 89.336623 -406.891925) (xy 89.412004 -406.883866) (xy 89.44991 -406.883362)
			(xy 89.487816 -406.883866) (xy 89.563197 -406.891925) (xy 89.637295 -406.90795) (xy 89.70927 -406.93176)
			(xy 89.778306 -406.963086) (xy 89.843621 -407.001573) (xy 89.904476 -407.046784) (xy 89.96018 -407.098208)
			(xy 90.010102 -407.155261) (xy 90.053677 -407.217297) (xy 90.090412 -407.283614) (xy 90.119889 -407.35346)
			(xy 90.141775 -407.426043) (xy 90.155822 -407.500541) (xy 90.161871 -407.576111) (xy 91.277949 -407.576111)
			(xy 91.283998 -407.500541) (xy 91.298045 -407.426043) (xy 91.319931 -407.35346) (xy 91.349408 -407.283614)
			(xy 91.386143 -407.217297) (xy 91.429718 -407.155261) (xy 91.47964 -407.098208) (xy 91.535344 -407.046784)
			(xy 91.596199 -407.001573) (xy 91.661514 -406.963086) (xy 91.73055 -406.93176) (xy 91.802525 -406.90795)
			(xy 91.876623 -406.891925) (xy 91.952004 -406.883866) (xy 91.98991 -406.883362) (xy 92.027816 -406.883866)
			(xy 92.103197 -406.891925) (xy 92.177295 -406.90795) (xy 92.24927 -406.93176) (xy 92.318306 -406.963086)
			(xy 92.383621 -407.001573) (xy 92.444476 -407.046784) (xy 92.50018 -407.098208) (xy 92.550102 -407.155261)
			(xy 92.593677 -407.217297) (xy 92.630412 -407.283614) (xy 92.659889 -407.35346) (xy 92.681775 -407.426043)
			(xy 92.695822 -407.500541) (xy 92.701871 -407.576111) (xy 92.699852 -407.651895) (xy 92.68979 -407.727035)
			(xy 92.671798 -407.80068) (xy 92.64608 -407.871996) (xy 92.612928 -407.940173) (xy 92.572716 -408.004441)
			(xy 92.525901 -408.06407) (xy 92.473013 -408.118386) (xy 92.414651 -408.166772) (xy 92.351476 -408.20868)
			(xy 92.284205 -408.243636) (xy 92.2136 -408.271243) (xy 92.177855 -408.280991) (xy 93.154757 -408.280991)
			(xy 93.160779 -408.164808) (xy 93.174802 -408.049317) (xy 93.19676 -407.935069) (xy 93.226547 -407.822608)
			(xy 93.264022 -407.71247) (xy 93.309007 -407.60518) (xy 93.361286 -407.501249) (xy 93.420611 -407.401173)
			(xy 93.486699 -407.305427) (xy 93.559235 -407.21447) (xy 93.637874 -407.128734) (xy 93.72224 -407.048627)
			(xy 93.811932 -406.974531) (xy 93.906522 -406.906801) (xy 94.00556 -406.845757) (xy 94.108573 -406.791692)
			(xy 94.21507 -406.744862) (xy 94.324545 -406.705491) (xy 94.436475 -406.673767) (xy 94.550327 -406.649841)
			(xy 94.665559 -406.633827) (xy 94.781621 -406.6258) (xy 94.83979 -406.625298) (xy 94.897959 -406.6258)
			(xy 95.014021 -406.633827) (xy 95.129253 -406.649841) (xy 95.243105 -406.673767) (xy 95.355035 -406.705491)
			(xy 95.46451 -406.744862) (xy 95.571007 -406.791692) (xy 95.67402 -406.845757) (xy 95.773058 -406.906801)
			(xy 95.867648 -406.974531) (xy 95.95734 -407.048627) (xy 96.041706 -407.128734) (xy 96.120345 -407.21447)
			(xy 96.192881 -407.305427) (xy 96.258969 -407.401173) (xy 96.318294 -407.501249) (xy 96.370573 -407.60518)
			(xy 96.415558 -407.71247) (xy 96.453033 -407.822608) (xy 96.48282 -407.935069) (xy 96.504778 -408.049317)
			(xy 96.518801 -408.164808) (xy 96.524823 -408.280991) (xy 96.522815 -408.397313) (xy 96.512786 -408.513219)
			(xy 96.494785 -408.628156) (xy 96.468897 -408.741579) (xy 96.435246 -408.852944) (xy 96.393992 -408.961723)
			(xy 96.345331 -409.067397) (xy 96.289495 -409.169461) (xy 96.226752 -409.26743) (xy 96.157398 -409.360837)
			(xy 96.081766 -409.449237) (xy 96.000215 -409.532208) (xy 95.913134 -409.609355) (xy 95.820938 -409.68031)
			(xy 95.724066 -409.744736) (xy 95.622981 -409.802325) (xy 95.518163 -409.852802) (xy 95.410112 -409.895928)
			(xy 95.299344 -409.931497) (xy 95.186385 -409.959339) (xy 95.071775 -409.979321) (xy 94.95606 -409.991348)
			(xy 94.83979 -409.995364) (xy 94.72352 -409.991348) (xy 94.607805 -409.979321) (xy 94.493195 -409.959339)
			(xy 94.380236 -409.931497) (xy 94.269468 -409.895928) (xy 94.161417 -409.852802) (xy 94.056599 -409.802325)
			(xy 93.955514 -409.744736) (xy 93.858642 -409.68031) (xy 93.766446 -409.609355) (xy 93.679365 -409.532208)
			(xy 93.597814 -409.449237) (xy 93.522182 -409.360837) (xy 93.452828 -409.26743) (xy 93.390085 -409.169461)
			(xy 93.334249 -409.067397) (xy 93.285588 -408.961723) (xy 93.244334 -408.852944) (xy 93.210683 -408.741579)
			(xy 93.184795 -408.628156) (xy 93.166794 -408.513219) (xy 93.156765 -408.397313) (xy 93.154757 -408.280991)
			(xy 92.177855 -408.280991) (xy 92.140459 -408.291189) (xy 92.065614 -408.303248) (xy 91.98991 -408.307283)
			(xy 91.914206 -408.303248) (xy 91.839361 -408.291189) (xy 91.76622 -408.271243) (xy 91.695615 -408.243636)
			(xy 91.628344 -408.20868) (xy 91.565169 -408.166772) (xy 91.506807 -408.118386) (xy 91.453919 -408.06407)
			(xy 91.407104 -408.004441) (xy 91.366892 -407.940173) (xy 91.33374 -407.871996) (xy 91.308022 -407.80068)
			(xy 91.29003 -407.727035) (xy 91.279968 -407.651895) (xy 91.277949 -407.576111) (xy 90.161871 -407.576111)
			(xy 90.159852 -407.651895) (xy 90.14979 -407.727035) (xy 90.131798 -407.80068) (xy 90.10608 -407.871996)
			(xy 90.072928 -407.940173) (xy 90.032716 -408.004441) (xy 89.985901 -408.06407) (xy 89.933013 -408.118386)
			(xy 89.874651 -408.166772) (xy 89.811476 -408.20868) (xy 89.744205 -408.243636) (xy 89.6736 -408.271243)
			(xy 89.600459 -408.291189) (xy 89.525614 -408.303248) (xy 89.44991 -408.307283) (xy 89.374206 -408.303248)
			(xy 89.299361 -408.291189) (xy 89.22622 -408.271243) (xy 89.155615 -408.243636) (xy 89.088344 -408.20868)
			(xy 89.025169 -408.166772) (xy 88.966807 -408.118386) (xy 88.913919 -408.06407) (xy 88.867104 -408.004441)
			(xy 88.826892 -407.940173) (xy 88.79374 -407.871996) (xy 88.768022 -407.80068) (xy 88.75003 -407.727035)
			(xy 88.739968 -407.651895) (xy 88.737949 -407.576111) (xy 87.621871 -407.576111) (xy 87.619852 -407.651895)
			(xy 87.60979 -407.727035) (xy 87.591798 -407.80068) (xy 87.56608 -407.871996) (xy 87.532928 -407.940173)
			(xy 87.492716 -408.004441) (xy 87.445901 -408.06407) (xy 87.393013 -408.118386) (xy 87.334651 -408.166772)
			(xy 87.271476 -408.20868) (xy 87.204205 -408.243636) (xy 87.1336 -408.271243) (xy 87.060459 -408.291189)
			(xy 86.985614 -408.303248) (xy 86.90991 -408.307283) (xy 86.834206 -408.303248) (xy 86.759361 -408.291189)
			(xy 86.68622 -408.271243) (xy 86.615615 -408.243636) (xy 86.548344 -408.20868) (xy 86.485169 -408.166772)
			(xy 86.426807 -408.118386) (xy 86.373919 -408.06407) (xy 86.327104 -408.004441) (xy 86.286892 -407.940173)
			(xy 86.25374 -407.871996) (xy 86.228022 -407.80068) (xy 86.21003 -407.727035) (xy 86.199968 -407.651895)
			(xy 86.197949 -407.576111) (xy 43.06342 -407.576111) (xy 43.050477 -407.61024) (xy 43.001926 -407.715674)
			(xy 42.946217 -407.817508) (xy 42.883615 -407.915256) (xy 42.814419 -408.008451) (xy 42.738957 -408.096651)
			(xy 42.65759 -408.179434) (xy 42.570706 -408.256407) (xy 42.525601 -408.291121) (xy 63.647829 -408.291121)
			(xy 63.653878 -408.215551) (xy 63.667925 -408.141053) (xy 63.689811 -408.06847) (xy 63.719288 -407.998624)
			(xy 63.756023 -407.932307) (xy 63.799598 -407.870271) (xy 63.84952 -407.813218) (xy 63.905224 -407.761794)
			(xy 63.966079 -407.716583) (xy 64.031394 -407.678096) (xy 64.10043 -407.64677) (xy 64.172405 -407.62296)
			(xy 64.246503 -407.606935) (xy 64.321884 -407.598876) (xy 64.35979 -407.598372) (xy 64.397696 -407.598876)
			(xy 64.473077 -407.606935) (xy 64.547175 -407.62296) (xy 64.61915 -407.64677) (xy 64.688186 -407.678096)
			(xy 64.753501 -407.716583) (xy 64.814356 -407.761794) (xy 64.87006 -407.813218) (xy 64.919982 -407.870271)
			(xy 64.963557 -407.932307) (xy 65.000292 -407.998624) (xy 65.029769 -408.06847) (xy 65.051655 -408.141053)
			(xy 65.065702 -408.215551) (xy 65.071751 -408.291121) (xy 66.187829 -408.291121) (xy 66.193878 -408.215551)
			(xy 66.207925 -408.141053) (xy 66.229811 -408.06847) (xy 66.259288 -407.998624) (xy 66.296023 -407.932307)
			(xy 66.339598 -407.870271) (xy 66.38952 -407.813218) (xy 66.445224 -407.761794) (xy 66.506079 -407.716583)
			(xy 66.571394 -407.678096) (xy 66.64043 -407.64677) (xy 66.712405 -407.62296) (xy 66.786503 -407.606935)
			(xy 66.861884 -407.598876) (xy 66.89979 -407.598372) (xy 66.937696 -407.598876) (xy 67.013077 -407.606935)
			(xy 67.087175 -407.62296) (xy 67.15915 -407.64677) (xy 67.228186 -407.678096) (xy 67.293501 -407.716583)
			(xy 67.354356 -407.761794) (xy 67.41006 -407.813218) (xy 67.459982 -407.870271) (xy 67.503557 -407.932307)
			(xy 67.540292 -407.998624) (xy 67.569769 -408.06847) (xy 67.591655 -408.141053) (xy 67.605702 -408.215551)
			(xy 67.611751 -408.291121) (xy 68.727829 -408.291121) (xy 68.733878 -408.215551) (xy 68.747925 -408.141053)
			(xy 68.769811 -408.06847) (xy 68.799288 -407.998624) (xy 68.836023 -407.932307) (xy 68.879598 -407.870271)
			(xy 68.92952 -407.813218) (xy 68.985224 -407.761794) (xy 69.046079 -407.716583) (xy 69.111394 -407.678096)
			(xy 69.18043 -407.64677) (xy 69.252405 -407.62296) (xy 69.326503 -407.606935) (xy 69.401884 -407.598876)
			(xy 69.43979 -407.598372) (xy 69.477696 -407.598876) (xy 69.553077 -407.606935) (xy 69.627175 -407.62296)
			(xy 69.69915 -407.64677) (xy 69.768186 -407.678096) (xy 69.833501 -407.716583) (xy 69.894356 -407.761794)
			(xy 69.95006 -407.813218) (xy 69.999982 -407.870271) (xy 70.043557 -407.932307) (xy 70.080292 -407.998624)
			(xy 70.109769 -408.06847) (xy 70.131655 -408.141053) (xy 70.145702 -408.215551) (xy 70.151751 -408.291121)
			(xy 71.267829 -408.291121) (xy 71.273878 -408.215551) (xy 71.287925 -408.141053) (xy 71.309811 -408.06847)
			(xy 71.339288 -407.998624) (xy 71.376023 -407.932307) (xy 71.419598 -407.870271) (xy 71.46952 -407.813218)
			(xy 71.525224 -407.761794) (xy 71.586079 -407.716583) (xy 71.651394 -407.678096) (xy 71.72043 -407.64677)
			(xy 71.792405 -407.62296) (xy 71.866503 -407.606935) (xy 71.941884 -407.598876) (xy 71.97979 -407.598372)
			(xy 72.017696 -407.598876) (xy 72.093077 -407.606935) (xy 72.167175 -407.62296) (xy 72.23915 -407.64677)
			(xy 72.308186 -407.678096) (xy 72.373501 -407.716583) (xy 72.434356 -407.761794) (xy 72.49006 -407.813218)
			(xy 72.539982 -407.870271) (xy 72.583557 -407.932307) (xy 72.620292 -407.998624) (xy 72.649769 -408.06847)
			(xy 72.671655 -408.141053) (xy 72.685702 -408.215551) (xy 72.691751 -408.291121) (xy 73.807829 -408.291121)
			(xy 73.813878 -408.215551) (xy 73.827925 -408.141053) (xy 73.849811 -408.06847) (xy 73.879288 -407.998624)
			(xy 73.916023 -407.932307) (xy 73.959598 -407.870271) (xy 74.00952 -407.813218) (xy 74.065224 -407.761794)
			(xy 74.126079 -407.716583) (xy 74.191394 -407.678096) (xy 74.26043 -407.64677) (xy 74.332405 -407.62296)
			(xy 74.406503 -407.606935) (xy 74.481884 -407.598876) (xy 74.51979 -407.598372) (xy 74.557696 -407.598876)
			(xy 74.633077 -407.606935) (xy 74.707175 -407.62296) (xy 74.77915 -407.64677) (xy 74.848186 -407.678096)
			(xy 74.913501 -407.716583) (xy 74.974356 -407.761794) (xy 75.03006 -407.813218) (xy 75.079982 -407.870271)
			(xy 75.123557 -407.932307) (xy 75.160292 -407.998624) (xy 75.189769 -408.06847) (xy 75.211655 -408.141053)
			(xy 75.225702 -408.215551) (xy 75.231751 -408.291121) (xy 76.347829 -408.291121) (xy 76.353878 -408.215551)
			(xy 76.367925 -408.141053) (xy 76.389811 -408.06847) (xy 76.419288 -407.998624) (xy 76.456023 -407.932307)
			(xy 76.499598 -407.870271) (xy 76.54952 -407.813218) (xy 76.605224 -407.761794) (xy 76.666079 -407.716583)
			(xy 76.731394 -407.678096) (xy 76.80043 -407.64677) (xy 76.872405 -407.62296) (xy 76.946503 -407.606935)
			(xy 77.021884 -407.598876) (xy 77.05979 -407.598372) (xy 77.097696 -407.598876) (xy 77.173077 -407.606935)
			(xy 77.247175 -407.62296) (xy 77.31915 -407.64677) (xy 77.388186 -407.678096) (xy 77.453501 -407.716583)
			(xy 77.514356 -407.761794) (xy 77.57006 -407.813218) (xy 77.619982 -407.870271) (xy 77.663557 -407.932307)
			(xy 77.700292 -407.998624) (xy 77.729769 -408.06847) (xy 77.751655 -408.141053) (xy 77.765702 -408.215551)
			(xy 77.771751 -408.291121) (xy 78.887829 -408.291121) (xy 78.893878 -408.215551) (xy 78.907925 -408.141053)
			(xy 78.929811 -408.06847) (xy 78.959288 -407.998624) (xy 78.996023 -407.932307) (xy 79.039598 -407.870271)
			(xy 79.08952 -407.813218) (xy 79.145224 -407.761794) (xy 79.206079 -407.716583) (xy 79.271394 -407.678096)
			(xy 79.34043 -407.64677) (xy 79.412405 -407.62296) (xy 79.486503 -407.606935) (xy 79.561884 -407.598876)
			(xy 79.59979 -407.598372) (xy 79.637696 -407.598876) (xy 79.713077 -407.606935) (xy 79.787175 -407.62296)
			(xy 79.85915 -407.64677) (xy 79.928186 -407.678096) (xy 79.993501 -407.716583) (xy 80.054356 -407.761794)
			(xy 80.11006 -407.813218) (xy 80.159982 -407.870271) (xy 80.203557 -407.932307) (xy 80.240292 -407.998624)
			(xy 80.269769 -408.06847) (xy 80.291655 -408.141053) (xy 80.305702 -408.215551) (xy 80.311751 -408.291121)
			(xy 81.427829 -408.291121) (xy 81.433878 -408.215551) (xy 81.447925 -408.141053) (xy 81.469811 -408.06847)
			(xy 81.499288 -407.998624) (xy 81.536023 -407.932307) (xy 81.579598 -407.870271) (xy 81.62952 -407.813218)
			(xy 81.685224 -407.761794) (xy 81.746079 -407.716583) (xy 81.811394 -407.678096) (xy 81.88043 -407.64677)
			(xy 81.952405 -407.62296) (xy 82.026503 -407.606935) (xy 82.101884 -407.598876) (xy 82.13979 -407.598372)
			(xy 82.177696 -407.598876) (xy 82.253077 -407.606935) (xy 82.327175 -407.62296) (xy 82.39915 -407.64677)
			(xy 82.468186 -407.678096) (xy 82.533501 -407.716583) (xy 82.594356 -407.761794) (xy 82.65006 -407.813218)
			(xy 82.699982 -407.870271) (xy 82.743557 -407.932307) (xy 82.780292 -407.998624) (xy 82.809769 -408.06847)
			(xy 82.831655 -408.141053) (xy 82.845702 -408.215551) (xy 82.851751 -408.291121) (xy 82.849732 -408.366905)
			(xy 82.83967 -408.442045) (xy 82.821678 -408.51569) (xy 82.79596 -408.587006) (xy 82.762808 -408.655183)
			(xy 82.722596 -408.719451) (xy 82.675781 -408.77908) (xy 82.622893 -408.833396) (xy 82.607556 -408.846111)
			(xy 84.927949 -408.846111) (xy 84.933998 -408.770541) (xy 84.948045 -408.696043) (xy 84.969931 -408.62346)
			(xy 84.999408 -408.553614) (xy 85.036143 -408.487297) (xy 85.079718 -408.425261) (xy 85.12964 -408.368208)
			(xy 85.185344 -408.316784) (xy 85.246199 -408.271573) (xy 85.311514 -408.233086) (xy 85.38055 -408.20176)
			(xy 85.452525 -408.17795) (xy 85.526623 -408.161925) (xy 85.602004 -408.153866) (xy 85.63991 -408.153362)
			(xy 85.677816 -408.153866) (xy 85.753197 -408.161925) (xy 85.827295 -408.17795) (xy 85.89927 -408.20176)
			(xy 85.968306 -408.233086) (xy 86.033621 -408.271573) (xy 86.094476 -408.316784) (xy 86.15018 -408.368208)
			(xy 86.200102 -408.425261) (xy 86.243677 -408.487297) (xy 86.280412 -408.553614) (xy 86.309889 -408.62346)
			(xy 86.331775 -408.696043) (xy 86.345822 -408.770541) (xy 86.351871 -408.846111) (xy 87.467949 -408.846111)
			(xy 87.473998 -408.770541) (xy 87.488045 -408.696043) (xy 87.509931 -408.62346) (xy 87.539408 -408.553614)
			(xy 87.576143 -408.487297) (xy 87.619718 -408.425261) (xy 87.66964 -408.368208) (xy 87.725344 -408.316784)
			(xy 87.786199 -408.271573) (xy 87.851514 -408.233086) (xy 87.92055 -408.20176) (xy 87.992525 -408.17795)
			(xy 88.066623 -408.161925) (xy 88.142004 -408.153866) (xy 88.17991 -408.153362) (xy 88.217816 -408.153866)
			(xy 88.293197 -408.161925) (xy 88.367295 -408.17795) (xy 88.43927 -408.20176) (xy 88.508306 -408.233086)
			(xy 88.573621 -408.271573) (xy 88.634476 -408.316784) (xy 88.69018 -408.368208) (xy 88.740102 -408.425261)
			(xy 88.783677 -408.487297) (xy 88.820412 -408.553614) (xy 88.849889 -408.62346) (xy 88.871775 -408.696043)
			(xy 88.885822 -408.770541) (xy 88.891871 -408.846111) (xy 90.007949 -408.846111) (xy 90.013998 -408.770541)
			(xy 90.028045 -408.696043) (xy 90.049931 -408.62346) (xy 90.079408 -408.553614) (xy 90.116143 -408.487297)
			(xy 90.159718 -408.425261) (xy 90.20964 -408.368208) (xy 90.265344 -408.316784) (xy 90.326199 -408.271573)
			(xy 90.391514 -408.233086) (xy 90.46055 -408.20176) (xy 90.532525 -408.17795) (xy 90.606623 -408.161925)
			(xy 90.682004 -408.153866) (xy 90.71991 -408.153362) (xy 90.757816 -408.153866) (xy 90.833197 -408.161925)
			(xy 90.907295 -408.17795) (xy 90.97927 -408.20176) (xy 91.048306 -408.233086) (xy 91.113621 -408.271573)
			(xy 91.174476 -408.316784) (xy 91.23018 -408.368208) (xy 91.280102 -408.425261) (xy 91.323677 -408.487297)
			(xy 91.360412 -408.553614) (xy 91.389889 -408.62346) (xy 91.411775 -408.696043) (xy 91.425822 -408.770541)
			(xy 91.431871 -408.846111) (xy 91.429852 -408.921895) (xy 91.41979 -408.997035) (xy 91.401798 -409.07068)
			(xy 91.37608 -409.141996) (xy 91.342928 -409.210173) (xy 91.302716 -409.274441) (xy 91.255901 -409.33407)
			(xy 91.203013 -409.388386) (xy 91.144651 -409.436772) (xy 91.081476 -409.47868) (xy 91.014205 -409.513636)
			(xy 90.9436 -409.541243) (xy 90.870459 -409.561189) (xy 90.795614 -409.573248) (xy 90.71991 -409.577283)
			(xy 90.644206 -409.573248) (xy 90.569361 -409.561189) (xy 90.49622 -409.541243) (xy 90.425615 -409.513636)
			(xy 90.358344 -409.47868) (xy 90.295169 -409.436772) (xy 90.236807 -409.388386) (xy 90.183919 -409.33407)
			(xy 90.137104 -409.274441) (xy 90.096892 -409.210173) (xy 90.06374 -409.141996) (xy 90.038022 -409.07068)
			(xy 90.02003 -408.997035) (xy 90.009968 -408.921895) (xy 90.007949 -408.846111) (xy 88.891871 -408.846111)
			(xy 88.889852 -408.921895) (xy 88.87979 -408.997035) (xy 88.861798 -409.07068) (xy 88.83608 -409.141996)
			(xy 88.802928 -409.210173) (xy 88.762716 -409.274441) (xy 88.715901 -409.33407) (xy 88.663013 -409.388386)
			(xy 88.604651 -409.436772) (xy 88.541476 -409.47868) (xy 88.474205 -409.513636) (xy 88.4036 -409.541243)
			(xy 88.330459 -409.561189) (xy 88.255614 -409.573248) (xy 88.17991 -409.577283) (xy 88.104206 -409.573248)
			(xy 88.029361 -409.561189) (xy 87.95622 -409.541243) (xy 87.885615 -409.513636) (xy 87.818344 -409.47868)
			(xy 87.755169 -409.436772) (xy 87.696807 -409.388386) (xy 87.643919 -409.33407) (xy 87.597104 -409.274441)
			(xy 87.556892 -409.210173) (xy 87.52374 -409.141996) (xy 87.498022 -409.07068) (xy 87.48003 -408.997035)
			(xy 87.469968 -408.921895) (xy 87.467949 -408.846111) (xy 86.351871 -408.846111) (xy 86.349852 -408.921895)
			(xy 86.33979 -408.997035) (xy 86.321798 -409.07068) (xy 86.29608 -409.141996) (xy 86.262928 -409.210173)
			(xy 86.222716 -409.274441) (xy 86.175901 -409.33407) (xy 86.123013 -409.388386) (xy 86.064651 -409.436772)
			(xy 86.001476 -409.47868) (xy 85.934205 -409.513636) (xy 85.8636 -409.541243) (xy 85.790459 -409.561189)
			(xy 85.715614 -409.573248) (xy 85.63991 -409.577283) (xy 85.564206 -409.573248) (xy 85.489361 -409.561189)
			(xy 85.41622 -409.541243) (xy 85.345615 -409.513636) (xy 85.278344 -409.47868) (xy 85.215169 -409.436772)
			(xy 85.156807 -409.388386) (xy 85.103919 -409.33407) (xy 85.057104 -409.274441) (xy 85.016892 -409.210173)
			(xy 84.98374 -409.141996) (xy 84.958022 -409.07068) (xy 84.94003 -408.997035) (xy 84.929968 -408.921895)
			(xy 84.927949 -408.846111) (xy 82.607556 -408.846111) (xy 82.564531 -408.881782) (xy 82.501356 -408.92369)
			(xy 82.434085 -408.958646) (xy 82.36348 -408.986253) (xy 82.290339 -409.006199) (xy 82.215494 -409.018258)
			(xy 82.13979 -409.022293) (xy 82.064086 -409.018258) (xy 81.989241 -409.006199) (xy 81.9161 -408.986253)
			(xy 81.845495 -408.958646) (xy 81.778224 -408.92369) (xy 81.715049 -408.881782) (xy 81.656687 -408.833396)
			(xy 81.603799 -408.77908) (xy 81.556984 -408.719451) (xy 81.516772 -408.655183) (xy 81.48362 -408.587006)
			(xy 81.457902 -408.51569) (xy 81.43991 -408.442045) (xy 81.429848 -408.366905) (xy 81.427829 -408.291121)
			(xy 80.311751 -408.291121) (xy 80.309732 -408.366905) (xy 80.29967 -408.442045) (xy 80.281678 -408.51569)
			(xy 80.25596 -408.587006) (xy 80.222808 -408.655183) (xy 80.182596 -408.719451) (xy 80.135781 -408.77908)
			(xy 80.082893 -408.833396) (xy 80.024531 -408.881782) (xy 79.961356 -408.92369) (xy 79.894085 -408.958646)
			(xy 79.82348 -408.986253) (xy 79.750339 -409.006199) (xy 79.675494 -409.018258) (xy 79.59979 -409.022293)
			(xy 79.524086 -409.018258) (xy 79.449241 -409.006199) (xy 79.3761 -408.986253) (xy 79.305495 -408.958646)
			(xy 79.238224 -408.92369) (xy 79.175049 -408.881782) (xy 79.116687 -408.833396) (xy 79.063799 -408.77908)
			(xy 79.016984 -408.719451) (xy 78.976772 -408.655183) (xy 78.94362 -408.587006) (xy 78.917902 -408.51569)
			(xy 78.89991 -408.442045) (xy 78.889848 -408.366905) (xy 78.887829 -408.291121) (xy 77.771751 -408.291121)
			(xy 77.769732 -408.366905) (xy 77.75967 -408.442045) (xy 77.741678 -408.51569) (xy 77.71596 -408.587006)
			(xy 77.682808 -408.655183) (xy 77.642596 -408.719451) (xy 77.595781 -408.77908) (xy 77.542893 -408.833396)
			(xy 77.484531 -408.881782) (xy 77.421356 -408.92369) (xy 77.354085 -408.958646) (xy 77.28348 -408.986253)
			(xy 77.210339 -409.006199) (xy 77.135494 -409.018258) (xy 77.05979 -409.022293) (xy 76.984086 -409.018258)
			(xy 76.909241 -409.006199) (xy 76.8361 -408.986253) (xy 76.765495 -408.958646) (xy 76.698224 -408.92369)
			(xy 76.635049 -408.881782) (xy 76.576687 -408.833396) (xy 76.523799 -408.77908) (xy 76.476984 -408.719451)
			(xy 76.436772 -408.655183) (xy 76.40362 -408.587006) (xy 76.377902 -408.51569) (xy 76.35991 -408.442045)
			(xy 76.349848 -408.366905) (xy 76.347829 -408.291121) (xy 75.231751 -408.291121) (xy 75.229732 -408.366905)
			(xy 75.21967 -408.442045) (xy 75.201678 -408.51569) (xy 75.17596 -408.587006) (xy 75.142808 -408.655183)
			(xy 75.102596 -408.719451) (xy 75.055781 -408.77908) (xy 75.002893 -408.833396) (xy 74.944531 -408.881782)
			(xy 74.881356 -408.92369) (xy 74.814085 -408.958646) (xy 74.74348 -408.986253) (xy 74.670339 -409.006199)
			(xy 74.595494 -409.018258) (xy 74.51979 -409.022293) (xy 74.444086 -409.018258) (xy 74.369241 -409.006199)
			(xy 74.2961 -408.986253) (xy 74.225495 -408.958646) (xy 74.158224 -408.92369) (xy 74.095049 -408.881782)
			(xy 74.036687 -408.833396) (xy 73.983799 -408.77908) (xy 73.936984 -408.719451) (xy 73.896772 -408.655183)
			(xy 73.86362 -408.587006) (xy 73.837902 -408.51569) (xy 73.81991 -408.442045) (xy 73.809848 -408.366905)
			(xy 73.807829 -408.291121) (xy 72.691751 -408.291121) (xy 72.689732 -408.366905) (xy 72.67967 -408.442045)
			(xy 72.661678 -408.51569) (xy 72.63596 -408.587006) (xy 72.602808 -408.655183) (xy 72.562596 -408.719451)
			(xy 72.515781 -408.77908) (xy 72.462893 -408.833396) (xy 72.404531 -408.881782) (xy 72.341356 -408.92369)
			(xy 72.274085 -408.958646) (xy 72.20348 -408.986253) (xy 72.130339 -409.006199) (xy 72.055494 -409.018258)
			(xy 71.97979 -409.022293) (xy 71.904086 -409.018258) (xy 71.829241 -409.006199) (xy 71.7561 -408.986253)
			(xy 71.685495 -408.958646) (xy 71.618224 -408.92369) (xy 71.555049 -408.881782) (xy 71.496687 -408.833396)
			(xy 71.443799 -408.77908) (xy 71.396984 -408.719451) (xy 71.356772 -408.655183) (xy 71.32362 -408.587006)
			(xy 71.297902 -408.51569) (xy 71.27991 -408.442045) (xy 71.269848 -408.366905) (xy 71.267829 -408.291121)
			(xy 70.151751 -408.291121) (xy 70.149732 -408.366905) (xy 70.13967 -408.442045) (xy 70.121678 -408.51569)
			(xy 70.09596 -408.587006) (xy 70.062808 -408.655183) (xy 70.022596 -408.719451) (xy 69.975781 -408.77908)
			(xy 69.922893 -408.833396) (xy 69.864531 -408.881782) (xy 69.801356 -408.92369) (xy 69.734085 -408.958646)
			(xy 69.66348 -408.986253) (xy 69.590339 -409.006199) (xy 69.515494 -409.018258) (xy 69.43979 -409.022293)
			(xy 69.364086 -409.018258) (xy 69.289241 -409.006199) (xy 69.2161 -408.986253) (xy 69.145495 -408.958646)
			(xy 69.078224 -408.92369) (xy 69.015049 -408.881782) (xy 68.956687 -408.833396) (xy 68.903799 -408.77908)
			(xy 68.856984 -408.719451) (xy 68.816772 -408.655183) (xy 68.78362 -408.587006) (xy 68.757902 -408.51569)
			(xy 68.73991 -408.442045) (xy 68.729848 -408.366905) (xy 68.727829 -408.291121) (xy 67.611751 -408.291121)
			(xy 67.609732 -408.366905) (xy 67.59967 -408.442045) (xy 67.581678 -408.51569) (xy 67.55596 -408.587006)
			(xy 67.522808 -408.655183) (xy 67.482596 -408.719451) (xy 67.435781 -408.77908) (xy 67.382893 -408.833396)
			(xy 67.324531 -408.881782) (xy 67.261356 -408.92369) (xy 67.194085 -408.958646) (xy 67.12348 -408.986253)
			(xy 67.050339 -409.006199) (xy 66.975494 -409.018258) (xy 66.89979 -409.022293) (xy 66.824086 -409.018258)
			(xy 66.749241 -409.006199) (xy 66.6761 -408.986253) (xy 66.605495 -408.958646) (xy 66.538224 -408.92369)
			(xy 66.475049 -408.881782) (xy 66.416687 -408.833396) (xy 66.363799 -408.77908) (xy 66.316984 -408.719451)
			(xy 66.276772 -408.655183) (xy 66.24362 -408.587006) (xy 66.217902 -408.51569) (xy 66.19991 -408.442045)
			(xy 66.189848 -408.366905) (xy 66.187829 -408.291121) (xy 65.071751 -408.291121) (xy 65.069732 -408.366905)
			(xy 65.05967 -408.442045) (xy 65.041678 -408.51569) (xy 65.01596 -408.587006) (xy 64.982808 -408.655183)
			(xy 64.942596 -408.719451) (xy 64.895781 -408.77908) (xy 64.842893 -408.833396) (xy 64.784531 -408.881782)
			(xy 64.721356 -408.92369) (xy 64.654085 -408.958646) (xy 64.58348 -408.986253) (xy 64.510339 -409.006199)
			(xy 64.435494 -409.018258) (xy 64.35979 -409.022293) (xy 64.284086 -409.018258) (xy 64.209241 -409.006199)
			(xy 64.1361 -408.986253) (xy 64.065495 -408.958646) (xy 63.998224 -408.92369) (xy 63.935049 -408.881782)
			(xy 63.876687 -408.833396) (xy 63.823799 -408.77908) (xy 63.776984 -408.719451) (xy 63.736772 -408.655183)
			(xy 63.70362 -408.587006) (xy 63.677902 -408.51569) (xy 63.65991 -408.442045) (xy 63.649848 -408.366905)
			(xy 63.647829 -408.291121) (xy 42.525601 -408.291121) (xy 42.478719 -408.327202) (xy 42.382066 -408.391482)
			(xy 42.281209 -408.44894) (xy 42.176629 -408.499304) (xy 42.068822 -408.542332) (xy 41.958305 -408.57782)
			(xy 41.845602 -408.605599) (xy 41.731251 -408.625536) (xy 41.615797 -408.637537) (xy 41.49979 -408.641543)
			(xy 41.383783 -408.637537) (xy 41.268329 -408.625536) (xy 41.153978 -408.605599) (xy 41.041275 -408.57782)
			(xy 40.930758 -408.542332) (xy 40.822951 -408.499304) (xy 40.718371 -408.44894) (xy 40.617514 -408.391482)
			(xy 40.520861 -408.327202) (xy 40.428874 -408.256407) (xy 40.34199 -408.179434) (xy 40.260623 -408.096651)
			(xy 40.185161 -408.008451) (xy 40.115965 -407.915256) (xy 40.053363 -407.817508) (xy 39.997654 -407.715674)
			(xy 39.949103 -407.61024) (xy 39.907942 -407.501707) (xy 39.874367 -407.390593) (xy 39.848537 -407.277427)
			(xy 39.830577 -407.162749) (xy 39.820571 -407.047105) (xy 39.818567 -406.931047) (xy 28.341828 -406.931047)
			(xy 28.341828 -409.033488) (xy 29.519874 -409.033488) (xy 29.519874 -408.946588) (xy 29.527892 -408.860059)
			(xy 29.54386 -408.774639) (xy 29.567641 -408.691057) (xy 29.599033 -408.610025) (xy 29.637767 -408.532236)
			(xy 29.683514 -408.458352) (xy 29.735883 -408.389005) (xy 29.794427 -408.324785) (xy 29.858647 -408.266241)
			(xy 29.927994 -408.213872) (xy 30.001878 -408.168125) (xy 30.079667 -408.129391) (xy 30.160699 -408.097999)
			(xy 30.244281 -408.074218) (xy 30.329701 -408.05825) (xy 30.41623 -408.050232) (xy 30.45968 -408.04973)
			(xy 30.50313 -408.050232) (xy 30.589659 -408.05825) (xy 30.675079 -408.074218) (xy 30.758661 -408.097999)
			(xy 30.839693 -408.129391) (xy 30.917482 -408.168125) (xy 30.991366 -408.213872) (xy 31.060713 -408.266241)
			(xy 31.124933 -408.324785) (xy 31.183477 -408.389005) (xy 31.235846 -408.458352) (xy 31.281593 -408.532236)
			(xy 31.320327 -408.610025) (xy 31.351719 -408.691057) (xy 31.3755 -408.774639) (xy 31.391468 -408.860059)
			(xy 31.399486 -408.946588) (xy 31.399486 -409.033488) (xy 34.599874 -409.033488) (xy 34.599874 -408.946588)
			(xy 34.607892 -408.860059) (xy 34.62386 -408.774639) (xy 34.647641 -408.691057) (xy 34.679033 -408.610025)
			(xy 34.717767 -408.532236) (xy 34.763514 -408.458352) (xy 34.815883 -408.389005) (xy 34.874427 -408.324785)
			(xy 34.938647 -408.266241) (xy 35.007994 -408.213872) (xy 35.081878 -408.168125) (xy 35.159667 -408.129391)
			(xy 35.240699 -408.097999) (xy 35.324281 -408.074218) (xy 35.409701 -408.05825) (xy 35.49623 -408.050232)
			(xy 35.53968 -408.04973) (xy 35.58313 -408.050232) (xy 35.669659 -408.05825) (xy 35.755079 -408.074218)
			(xy 35.838661 -408.097999) (xy 35.919693 -408.129391) (xy 35.997482 -408.168125) (xy 36.071366 -408.213872)
			(xy 36.140713 -408.266241) (xy 36.204933 -408.324785) (xy 36.263477 -408.389005) (xy 36.315846 -408.458352)
			(xy 36.361593 -408.532236) (xy 36.400327 -408.610025) (xy 36.431719 -408.691057) (xy 36.4555 -408.774639)
			(xy 36.471468 -408.860059) (xy 36.479486 -408.946588) (xy 36.479486 -409.033488) (xy 36.471468 -409.120017)
			(xy 36.4555 -409.205437) (xy 36.431719 -409.289019) (xy 36.400327 -409.370051) (xy 36.361593 -409.44784)
			(xy 36.315846 -409.521724) (xy 36.263477 -409.591071) (xy 36.204933 -409.655291) (xy 36.140713 -409.713835)
			(xy 36.071366 -409.766204) (xy 35.997482 -409.811951) (xy 35.919693 -409.850685) (xy 35.838661 -409.882077)
			(xy 35.755079 -409.905858) (xy 35.669659 -409.921826) (xy 35.58313 -409.929844) (xy 35.49623 -409.929844)
			(xy 35.409701 -409.921826) (xy 35.324281 -409.905858) (xy 35.240699 -409.882077) (xy 35.159667 -409.850685)
			(xy 35.081878 -409.811951) (xy 35.007994 -409.766204) (xy 34.938647 -409.713835) (xy 34.874427 -409.655291)
			(xy 34.815883 -409.591071) (xy 34.763514 -409.521724) (xy 34.717767 -409.44784) (xy 34.679033 -409.370051)
			(xy 34.647641 -409.289019) (xy 34.62386 -409.205437) (xy 34.607892 -409.120017) (xy 34.599874 -409.033488)
			(xy 31.399486 -409.033488) (xy 31.391468 -409.120017) (xy 31.3755 -409.205437) (xy 31.351719 -409.289019)
			(xy 31.320327 -409.370051) (xy 31.281593 -409.44784) (xy 31.235846 -409.521724) (xy 31.183477 -409.591071)
			(xy 31.124933 -409.655291) (xy 31.060713 -409.713835) (xy 30.991366 -409.766204) (xy 30.917482 -409.811951)
			(xy 30.839693 -409.850685) (xy 30.758661 -409.882077) (xy 30.675079 -409.905858) (xy 30.589659 -409.921826)
			(xy 30.50313 -409.929844) (xy 30.41623 -409.929844) (xy 30.329701 -409.921826) (xy 30.244281 -409.905858)
			(xy 30.160699 -409.882077) (xy 30.079667 -409.850685) (xy 30.001878 -409.811951) (xy 29.927994 -409.766204)
			(xy 29.858647 -409.713835) (xy 29.794427 -409.655291) (xy 29.735883 -409.591071) (xy 29.683514 -409.521724)
			(xy 29.637767 -409.44784) (xy 29.599033 -409.370051) (xy 29.567641 -409.289019) (xy 29.54386 -409.205437)
			(xy 29.527892 -409.120017) (xy 29.519874 -409.033488) (xy 28.341828 -409.033488) (xy 28.341828 -411.573488)
			(xy 29.519874 -411.573488) (xy 29.519874 -411.486588) (xy 29.527892 -411.400059) (xy 29.54386 -411.314639)
			(xy 29.567641 -411.231057) (xy 29.599033 -411.150025) (xy 29.637767 -411.072236) (xy 29.683514 -410.998352)
			(xy 29.735883 -410.929005) (xy 29.794427 -410.864785) (xy 29.858647 -410.806241) (xy 29.927994 -410.753872)
			(xy 30.001878 -410.708125) (xy 30.079667 -410.669391) (xy 30.160699 -410.637999) (xy 30.244281 -410.614218)
			(xy 30.329701 -410.59825) (xy 30.41623 -410.590232) (xy 30.45968 -410.58973) (xy 30.50313 -410.590232)
			(xy 30.589659 -410.59825) (xy 30.675079 -410.614218) (xy 30.758661 -410.637999) (xy 30.839693 -410.669391)
			(xy 30.917482 -410.708125) (xy 30.991366 -410.753872) (xy 31.060713 -410.806241) (xy 31.124933 -410.864785)
			(xy 31.183477 -410.929005) (xy 31.235846 -410.998352) (xy 31.281593 -411.072236) (xy 31.320327 -411.150025)
			(xy 31.351719 -411.231057) (xy 31.3755 -411.314639) (xy 31.391468 -411.400059) (xy 31.399486 -411.486588)
			(xy 31.399486 -411.573488) (xy 34.599874 -411.573488) (xy 34.599874 -411.486588) (xy 34.607892 -411.400059)
			(xy 34.62386 -411.314639) (xy 34.647641 -411.231057) (xy 34.679033 -411.150025) (xy 34.717767 -411.072236)
			(xy 34.763514 -410.998352) (xy 34.815883 -410.929005) (xy 34.874427 -410.864785) (xy 34.938647 -410.806241)
			(xy 35.007994 -410.753872) (xy 35.081878 -410.708125) (xy 35.159667 -410.669391) (xy 35.240699 -410.637999)
			(xy 35.324281 -410.614218) (xy 35.409701 -410.59825) (xy 35.49623 -410.590232) (xy 35.53968 -410.58973)
			(xy 35.58313 -410.590232) (xy 35.669659 -410.59825) (xy 35.755079 -410.614218) (xy 35.838661 -410.637999)
			(xy 35.919693 -410.669391) (xy 35.997482 -410.708125) (xy 36.071366 -410.753872) (xy 36.140713 -410.806241)
			(xy 36.204933 -410.864785) (xy 36.263477 -410.929005) (xy 36.315846 -410.998352) (xy 36.361593 -411.072236)
			(xy 36.400327 -411.150025) (xy 36.431719 -411.231057) (xy 36.4555 -411.314639) (xy 36.471468 -411.400059)
			(xy 36.479486 -411.486588) (xy 36.479486 -411.573488) (xy 36.471468 -411.660017) (xy 36.4555 -411.745437)
			(xy 36.431719 -411.829019) (xy 36.400327 -411.910051) (xy 36.366143 -411.978703) (xy 65.802248 -411.978703)
			(xy 65.802248 -411.907381) (xy 65.810234 -411.836507) (xy 65.826104 -411.766972) (xy 65.849661 -411.699652)
			(xy 65.880606 -411.635393) (xy 65.918552 -411.575002) (xy 65.963021 -411.51924) (xy 66.013454 -411.468807)
			(xy 66.069216 -411.424338) (xy 66.129607 -411.386392) (xy 66.193866 -411.355447) (xy 66.261186 -411.33189)
			(xy 66.330721 -411.31602) (xy 66.401595 -411.308034) (xy 66.437256 -411.307534) (xy 66.472917 -411.308034)
			(xy 66.543791 -411.31602) (xy 66.613326 -411.33189) (xy 66.680646 -411.355447) (xy 66.744905 -411.386392)
			(xy 66.805296 -411.424338) (xy 66.861058 -411.468807) (xy 66.911491 -411.51924) (xy 66.95596 -411.575002)
			(xy 66.993906 -411.635393) (xy 67.024851 -411.699652) (xy 67.048408 -411.766972) (xy 67.064278 -411.836507)
			(xy 67.072264 -411.907381) (xy 67.072264 -411.978703) (xy 68.79386 -411.978703) (xy 68.79386 -411.907381)
			(xy 68.801846 -411.836507) (xy 68.817716 -411.766972) (xy 68.841273 -411.699652) (xy 68.872218 -411.635393)
			(xy 68.910164 -411.575002) (xy 68.954633 -411.51924) (xy 69.005066 -411.468807) (xy 69.060828 -411.424338)
			(xy 69.121219 -411.386392) (xy 69.185478 -411.355447) (xy 69.252798 -411.33189) (xy 69.322333 -411.31602)
			(xy 69.393207 -411.308034) (xy 69.428868 -411.307534) (xy 69.464529 -411.308034) (xy 69.535403 -411.31602)
			(xy 69.604938 -411.33189) (xy 69.672258 -411.355447) (xy 69.736517 -411.386392) (xy 69.796908 -411.424338)
			(xy 69.85267 -411.468807) (xy 69.903103 -411.51924) (xy 69.947572 -411.575002) (xy 69.985518 -411.635393)
			(xy 70.016463 -411.699652) (xy 70.04002 -411.766972) (xy 70.05589 -411.836507) (xy 70.063876 -411.907381)
			(xy 70.063876 -411.978703) (xy 70.05589 -412.049577) (xy 70.04002 -412.119112) (xy 70.016463 -412.186432)
			(xy 69.985518 -412.250691) (xy 69.947572 -412.311082) (xy 69.903103 -412.366844) (xy 69.85267 -412.417277)
			(xy 69.796908 -412.461746) (xy 69.736517 -412.499692) (xy 69.672258 -412.530637) (xy 69.604938 -412.554194)
			(xy 69.535403 -412.570064) (xy 69.464529 -412.57805) (xy 69.393207 -412.57805) (xy 69.322333 -412.570064)
			(xy 69.252798 -412.554194) (xy 69.185478 -412.530637) (xy 69.121219 -412.499692) (xy 69.060828 -412.461746)
			(xy 69.005066 -412.417277) (xy 68.954633 -412.366844) (xy 68.910164 -412.311082) (xy 68.872218 -412.250691)
			(xy 68.841273 -412.186432) (xy 68.817716 -412.119112) (xy 68.801846 -412.049577) (xy 68.79386 -411.978703)
			(xy 67.072264 -411.978703) (xy 67.064278 -412.049577) (xy 67.048408 -412.119112) (xy 67.024851 -412.186432)
			(xy 66.993906 -412.250691) (xy 66.95596 -412.311082) (xy 66.911491 -412.366844) (xy 66.861058 -412.417277)
			(xy 66.805296 -412.461746) (xy 66.744905 -412.499692) (xy 66.680646 -412.530637) (xy 66.613326 -412.554194)
			(xy 66.543791 -412.570064) (xy 66.472917 -412.57805) (xy 66.401595 -412.57805) (xy 66.330721 -412.570064)
			(xy 66.261186 -412.554194) (xy 66.193866 -412.530637) (xy 66.129607 -412.499692) (xy 66.069216 -412.461746)
			(xy 66.013454 -412.417277) (xy 65.963021 -412.366844) (xy 65.918552 -412.311082) (xy 65.880606 -412.250691)
			(xy 65.849661 -412.186432) (xy 65.826104 -412.119112) (xy 65.810234 -412.049577) (xy 65.802248 -411.978703)
			(xy 36.366143 -411.978703) (xy 36.361593 -411.98784) (xy 36.315846 -412.061724) (xy 36.263477 -412.131071)
			(xy 36.204933 -412.195291) (xy 36.140713 -412.253835) (xy 36.071366 -412.306204) (xy 35.997482 -412.351951)
			(xy 35.919693 -412.390685) (xy 35.838661 -412.422077) (xy 35.755079 -412.445858) (xy 35.669659 -412.461826)
			(xy 35.58313 -412.469844) (xy 35.49623 -412.469844) (xy 35.409701 -412.461826) (xy 35.324281 -412.445858)
			(xy 35.240699 -412.422077) (xy 35.159667 -412.390685) (xy 35.081878 -412.351951) (xy 35.007994 -412.306204)
			(xy 34.938647 -412.253835) (xy 34.874427 -412.195291) (xy 34.815883 -412.131071) (xy 34.763514 -412.061724)
			(xy 34.717767 -411.98784) (xy 34.679033 -411.910051) (xy 34.647641 -411.829019) (xy 34.62386 -411.745437)
			(xy 34.607892 -411.660017) (xy 34.599874 -411.573488) (xy 31.399486 -411.573488) (xy 31.391468 -411.660017)
			(xy 31.3755 -411.745437) (xy 31.351719 -411.829019) (xy 31.320327 -411.910051) (xy 31.281593 -411.98784)
			(xy 31.235846 -412.061724) (xy 31.183477 -412.131071) (xy 31.124933 -412.195291) (xy 31.060713 -412.253835)
			(xy 30.991366 -412.306204) (xy 30.917482 -412.351951) (xy 30.839693 -412.390685) (xy 30.758661 -412.422077)
			(xy 30.675079 -412.445858) (xy 30.589659 -412.461826) (xy 30.50313 -412.469844) (xy 30.41623 -412.469844)
			(xy 30.329701 -412.461826) (xy 30.244281 -412.445858) (xy 30.160699 -412.422077) (xy 30.079667 -412.390685)
			(xy 30.001878 -412.351951) (xy 29.927994 -412.306204) (xy 29.858647 -412.253835) (xy 29.794427 -412.195291)
			(xy 29.735883 -412.131071) (xy 29.683514 -412.061724) (xy 29.637767 -411.98784) (xy 29.599033 -411.910051)
			(xy 29.567641 -411.829019) (xy 29.54386 -411.745437) (xy 29.527892 -411.660017) (xy 29.519874 -411.573488)
			(xy 28.341828 -411.573488) (xy 28.341828 -414.113488) (xy 29.519874 -414.113488) (xy 29.519874 -414.026588)
			(xy 29.527892 -413.940059) (xy 29.54386 -413.854639) (xy 29.567641 -413.771057) (xy 29.599033 -413.690025)
			(xy 29.637767 -413.612236) (xy 29.683514 -413.538352) (xy 29.735883 -413.469005) (xy 29.794427 -413.404785)
			(xy 29.858647 -413.346241) (xy 29.927994 -413.293872) (xy 30.001878 -413.248125) (xy 30.079667 -413.209391)
			(xy 30.160699 -413.177999) (xy 30.244281 -413.154218) (xy 30.329701 -413.13825) (xy 30.41623 -413.130232)
			(xy 30.45968 -413.12973) (xy 30.50313 -413.130232) (xy 30.589659 -413.13825) (xy 30.675079 -413.154218)
			(xy 30.758661 -413.177999) (xy 30.839693 -413.209391) (xy 30.917482 -413.248125) (xy 30.991366 -413.293872)
			(xy 31.060713 -413.346241) (xy 31.124933 -413.404785) (xy 31.183477 -413.469005) (xy 31.235846 -413.538352)
			(xy 31.281593 -413.612236) (xy 31.320327 -413.690025) (xy 31.351719 -413.771057) (xy 31.3755 -413.854639)
			(xy 31.391468 -413.940059) (xy 31.399486 -414.026588) (xy 31.399486 -414.113488) (xy 34.599874 -414.113488)
			(xy 34.599874 -414.026588) (xy 34.607892 -413.940059) (xy 34.62386 -413.854639) (xy 34.647641 -413.771057)
			(xy 34.679033 -413.690025) (xy 34.717767 -413.612236) (xy 34.763514 -413.538352) (xy 34.815883 -413.469005)
			(xy 34.874427 -413.404785) (xy 34.938647 -413.346241) (xy 35.007994 -413.293872) (xy 35.081878 -413.248125)
			(xy 35.159667 -413.209391) (xy 35.240699 -413.177999) (xy 35.324281 -413.154218) (xy 35.409701 -413.13825)
			(xy 35.49623 -413.130232) (xy 35.53968 -413.12973) (xy 35.58313 -413.130232) (xy 35.669659 -413.13825)
			(xy 35.755079 -413.154218) (xy 35.838661 -413.177999) (xy 35.919693 -413.209391) (xy 35.997482 -413.248125)
			(xy 36.071366 -413.293872) (xy 36.140713 -413.346241) (xy 36.204933 -413.404785) (xy 36.263477 -413.469005)
			(xy 36.315846 -413.538352) (xy 36.361593 -413.612236) (xy 36.400327 -413.690025) (xy 36.431719 -413.771057)
			(xy 36.4555 -413.854639) (xy 36.471468 -413.940059) (xy 36.479486 -414.026588) (xy 36.479486 -414.113488)
			(xy 36.471468 -414.200017) (xy 36.4555 -414.285437) (xy 36.431719 -414.369019) (xy 36.400327 -414.450051)
			(xy 36.361593 -414.52784) (xy 36.315846 -414.601724) (xy 36.279757 -414.649513) (xy 65.802248 -414.649513)
			(xy 65.802248 -414.578191) (xy 65.810234 -414.507317) (xy 65.826104 -414.437782) (xy 65.849661 -414.370462)
			(xy 65.880606 -414.306203) (xy 65.918552 -414.245812) (xy 65.963021 -414.19005) (xy 66.013454 -414.139617)
			(xy 66.069216 -414.095148) (xy 66.129607 -414.057202) (xy 66.193866 -414.026257) (xy 66.261186 -414.0027)
			(xy 66.330721 -413.98683) (xy 66.401595 -413.978844) (xy 66.437256 -413.978344) (xy 66.472917 -413.978844)
			(xy 66.543791 -413.98683) (xy 66.613326 -414.0027) (xy 66.680646 -414.026257) (xy 66.744905 -414.057202)
			(xy 66.805296 -414.095148) (xy 66.861058 -414.139617) (xy 66.911491 -414.19005) (xy 66.95596 -414.245812)
			(xy 66.993906 -414.306203) (xy 67.024851 -414.370462) (xy 67.048408 -414.437782) (xy 67.064278 -414.507317)
			(xy 67.072264 -414.578191) (xy 67.072264 -414.649513) (xy 68.79386 -414.649513) (xy 68.79386 -414.578191)
			(xy 68.801846 -414.507317) (xy 68.817716 -414.437782) (xy 68.841273 -414.370462) (xy 68.872218 -414.306203)
			(xy 68.910164 -414.245812) (xy 68.954633 -414.19005) (xy 69.005066 -414.139617) (xy 69.060828 -414.095148)
			(xy 69.121219 -414.057202) (xy 69.185478 -414.026257) (xy 69.252798 -414.0027) (xy 69.322333 -413.98683)
			(xy 69.393207 -413.978844) (xy 69.428868 -413.978344) (xy 69.464529 -413.978844) (xy 69.535403 -413.98683)
			(xy 69.604938 -414.0027) (xy 69.672258 -414.026257) (xy 69.736517 -414.057202) (xy 69.796908 -414.095148)
			(xy 69.85267 -414.139617) (xy 69.903103 -414.19005) (xy 69.947572 -414.245812) (xy 69.985518 -414.306203)
			(xy 70.016463 -414.370462) (xy 70.04002 -414.437782) (xy 70.05589 -414.507317) (xy 70.063876 -414.578191)
			(xy 70.063876 -414.649513) (xy 70.05589 -414.720387) (xy 70.04002 -414.789922) (xy 70.016463 -414.857242)
			(xy 69.985518 -414.921501) (xy 69.947572 -414.981892) (xy 69.903103 -415.037654) (xy 69.85267 -415.088087)
			(xy 69.796908 -415.132556) (xy 69.736517 -415.170502) (xy 69.672258 -415.201447) (xy 69.604938 -415.225004)
			(xy 69.535403 -415.240874) (xy 69.464529 -415.24886) (xy 69.393207 -415.24886) (xy 69.322333 -415.240874)
			(xy 69.252798 -415.225004) (xy 69.185478 -415.201447) (xy 69.121219 -415.170502) (xy 69.060828 -415.132556)
			(xy 69.005066 -415.088087) (xy 68.954633 -415.037654) (xy 68.910164 -414.981892) (xy 68.872218 -414.921501)
			(xy 68.841273 -414.857242) (xy 68.817716 -414.789922) (xy 68.801846 -414.720387) (xy 68.79386 -414.649513)
			(xy 67.072264 -414.649513) (xy 67.064278 -414.720387) (xy 67.048408 -414.789922) (xy 67.024851 -414.857242)
			(xy 66.993906 -414.921501) (xy 66.95596 -414.981892) (xy 66.911491 -415.037654) (xy 66.861058 -415.088087)
			(xy 66.805296 -415.132556) (xy 66.744905 -415.170502) (xy 66.680646 -415.201447) (xy 66.613326 -415.225004)
			(xy 66.543791 -415.240874) (xy 66.472917 -415.24886) (xy 66.401595 -415.24886) (xy 66.330721 -415.240874)
			(xy 66.261186 -415.225004) (xy 66.193866 -415.201447) (xy 66.129607 -415.170502) (xy 66.069216 -415.132556)
			(xy 66.013454 -415.088087) (xy 65.963021 -415.037654) (xy 65.918552 -414.981892) (xy 65.880606 -414.921501)
			(xy 65.849661 -414.857242) (xy 65.826104 -414.789922) (xy 65.810234 -414.720387) (xy 65.802248 -414.649513)
			(xy 36.279757 -414.649513) (xy 36.263477 -414.671071) (xy 36.204933 -414.735291) (xy 36.140713 -414.793835)
			(xy 36.071366 -414.846204) (xy 35.997482 -414.891951) (xy 35.919693 -414.930685) (xy 35.838661 -414.962077)
			(xy 35.755079 -414.985858) (xy 35.669659 -415.001826) (xy 35.58313 -415.009844) (xy 35.49623 -415.009844)
			(xy 35.409701 -415.001826) (xy 35.324281 -414.985858) (xy 35.240699 -414.962077) (xy 35.159667 -414.930685)
			(xy 35.081878 -414.891951) (xy 35.007994 -414.846204) (xy 34.938647 -414.793835) (xy 34.874427 -414.735291)
			(xy 34.815883 -414.671071) (xy 34.763514 -414.601724) (xy 34.717767 -414.52784) (xy 34.679033 -414.450051)
			(xy 34.647641 -414.369019) (xy 34.62386 -414.285437) (xy 34.607892 -414.200017) (xy 34.599874 -414.113488)
			(xy 31.399486 -414.113488) (xy 31.391468 -414.200017) (xy 31.3755 -414.285437) (xy 31.351719 -414.369019)
			(xy 31.320327 -414.450051) (xy 31.281593 -414.52784) (xy 31.235846 -414.601724) (xy 31.183477 -414.671071)
			(xy 31.124933 -414.735291) (xy 31.060713 -414.793835) (xy 30.991366 -414.846204) (xy 30.917482 -414.891951)
			(xy 30.839693 -414.930685) (xy 30.758661 -414.962077) (xy 30.675079 -414.985858) (xy 30.589659 -415.001826)
			(xy 30.50313 -415.009844) (xy 30.41623 -415.009844) (xy 30.329701 -415.001826) (xy 30.244281 -414.985858)
			(xy 30.160699 -414.962077) (xy 30.079667 -414.930685) (xy 30.001878 -414.891951) (xy 29.927994 -414.846204)
			(xy 29.858647 -414.793835) (xy 29.794427 -414.735291) (xy 29.735883 -414.671071) (xy 29.683514 -414.601724)
			(xy 29.637767 -414.52784) (xy 29.599033 -414.450051) (xy 29.567641 -414.369019) (xy 29.54386 -414.285437)
			(xy 29.527892 -414.200017) (xy 29.519874 -414.113488) (xy 28.341828 -414.113488) (xy 28.341828 -416.653488)
			(xy 29.519874 -416.653488) (xy 29.519874 -416.566588) (xy 29.527892 -416.480059) (xy 29.54386 -416.394639)
			(xy 29.567641 -416.311057) (xy 29.599033 -416.230025) (xy 29.637767 -416.152236) (xy 29.683514 -416.078352)
			(xy 29.735883 -416.009005) (xy 29.794427 -415.944785) (xy 29.858647 -415.886241) (xy 29.927994 -415.833872)
			(xy 30.001878 -415.788125) (xy 30.079667 -415.749391) (xy 30.160699 -415.717999) (xy 30.244281 -415.694218)
			(xy 30.329701 -415.67825) (xy 30.41623 -415.670232) (xy 30.45968 -415.66973) (xy 30.50313 -415.670232)
			(xy 30.589659 -415.67825) (xy 30.675079 -415.694218) (xy 30.758661 -415.717999) (xy 30.839693 -415.749391)
			(xy 30.917482 -415.788125) (xy 30.991366 -415.833872) (xy 31.060713 -415.886241) (xy 31.124933 -415.944785)
			(xy 31.183477 -416.009005) (xy 31.235846 -416.078352) (xy 31.281593 -416.152236) (xy 31.320327 -416.230025)
			(xy 31.351719 -416.311057) (xy 31.3755 -416.394639) (xy 31.391468 -416.480059) (xy 31.399486 -416.566588)
			(xy 31.399486 -416.653488) (xy 34.599874 -416.653488) (xy 34.599874 -416.566588) (xy 34.607892 -416.480059)
			(xy 34.62386 -416.394639) (xy 34.647641 -416.311057) (xy 34.679033 -416.230025) (xy 34.717767 -416.152236)
			(xy 34.763514 -416.078352) (xy 34.815883 -416.009005) (xy 34.874427 -415.944785) (xy 34.938647 -415.886241)
			(xy 35.007994 -415.833872) (xy 35.081878 -415.788125) (xy 35.159667 -415.749391) (xy 35.240699 -415.717999)
			(xy 35.324281 -415.694218) (xy 35.409701 -415.67825) (xy 35.49623 -415.670232) (xy 35.53968 -415.66973)
			(xy 35.58313 -415.670232) (xy 35.669659 -415.67825) (xy 35.755079 -415.694218) (xy 35.838661 -415.717999)
			(xy 35.919693 -415.749391) (xy 35.997482 -415.788125) (xy 36.071366 -415.833872) (xy 36.140713 -415.886241)
			(xy 36.204933 -415.944785) (xy 36.263477 -416.009005) (xy 36.315846 -416.078352) (xy 36.361593 -416.152236)
			(xy 36.400327 -416.230025) (xy 36.431719 -416.311057) (xy 36.4555 -416.394639) (xy 36.471468 -416.480059)
			(xy 36.479486 -416.566588) (xy 36.479486 -416.653488) (xy 36.471468 -416.740017) (xy 36.4555 -416.825437)
			(xy 36.431719 -416.909019) (xy 36.400327 -416.990051) (xy 36.361593 -417.06784) (xy 36.315846 -417.141724)
			(xy 36.263477 -417.211071) (xy 36.204933 -417.275291) (xy 36.158321 -417.317783) (xy 65.802248 -417.317783)
			(xy 65.802248 -417.246461) (xy 65.810234 -417.175587) (xy 65.826104 -417.106052) (xy 65.849661 -417.038732)
			(xy 65.880606 -416.974473) (xy 65.918552 -416.914082) (xy 65.963021 -416.85832) (xy 66.013454 -416.807887)
			(xy 66.069216 -416.763418) (xy 66.129607 -416.725472) (xy 66.193866 -416.694527) (xy 66.261186 -416.67097)
			(xy 66.330721 -416.6551) (xy 66.401595 -416.647114) (xy 66.437256 -416.646614) (xy 66.472917 -416.647114)
			(xy 66.543791 -416.6551) (xy 66.613326 -416.67097) (xy 66.680646 -416.694527) (xy 66.744905 -416.725472)
			(xy 66.805296 -416.763418) (xy 66.861058 -416.807887) (xy 66.911491 -416.85832) (xy 66.95596 -416.914082)
			(xy 66.993906 -416.974473) (xy 67.024851 -417.038732) (xy 67.048408 -417.106052) (xy 67.064278 -417.175587)
			(xy 67.072264 -417.246461) (xy 67.072264 -417.317783) (xy 68.79386 -417.317783) (xy 68.79386 -417.246461)
			(xy 68.801846 -417.175587) (xy 68.817716 -417.106052) (xy 68.841273 -417.038732) (xy 68.872218 -416.974473)
			(xy 68.910164 -416.914082) (xy 68.954633 -416.85832) (xy 69.005066 -416.807887) (xy 69.060828 -416.763418)
			(xy 69.121219 -416.725472) (xy 69.185478 -416.694527) (xy 69.252798 -416.67097) (xy 69.322333 -416.6551)
			(xy 69.393207 -416.647114) (xy 69.428868 -416.646614) (xy 69.464529 -416.647114) (xy 69.535403 -416.6551)
			(xy 69.604938 -416.67097) (xy 69.672258 -416.694527) (xy 69.736517 -416.725472) (xy 69.796908 -416.763418)
			(xy 69.85267 -416.807887) (xy 69.903103 -416.85832) (xy 69.947572 -416.914082) (xy 69.985518 -416.974473)
			(xy 70.016463 -417.038732) (xy 70.04002 -417.106052) (xy 70.05589 -417.175587) (xy 70.063876 -417.246461)
			(xy 70.063876 -417.317783) (xy 70.05589 -417.388657) (xy 70.04002 -417.458192) (xy 70.016463 -417.525512)
			(xy 69.985518 -417.589771) (xy 69.947572 -417.650162) (xy 69.903103 -417.705924) (xy 69.85267 -417.756357)
			(xy 69.796908 -417.800826) (xy 69.736517 -417.838772) (xy 69.672258 -417.869717) (xy 69.604938 -417.893274)
			(xy 69.535403 -417.909144) (xy 69.464529 -417.91713) (xy 69.393207 -417.91713) (xy 69.322333 -417.909144)
			(xy 69.252798 -417.893274) (xy 69.185478 -417.869717) (xy 69.121219 -417.838772) (xy 69.060828 -417.800826)
			(xy 69.005066 -417.756357) (xy 68.954633 -417.705924) (xy 68.910164 -417.650162) (xy 68.872218 -417.589771)
			(xy 68.841273 -417.525512) (xy 68.817716 -417.458192) (xy 68.801846 -417.388657) (xy 68.79386 -417.317783)
			(xy 67.072264 -417.317783) (xy 67.064278 -417.388657) (xy 67.048408 -417.458192) (xy 67.024851 -417.525512)
			(xy 66.993906 -417.589771) (xy 66.95596 -417.650162) (xy 66.911491 -417.705924) (xy 66.861058 -417.756357)
			(xy 66.805296 -417.800826) (xy 66.744905 -417.838772) (xy 66.680646 -417.869717) (xy 66.613326 -417.893274)
			(xy 66.543791 -417.909144) (xy 66.472917 -417.91713) (xy 66.401595 -417.91713) (xy 66.330721 -417.909144)
			(xy 66.261186 -417.893274) (xy 66.193866 -417.869717) (xy 66.129607 -417.838772) (xy 66.069216 -417.800826)
			(xy 66.013454 -417.756357) (xy 65.963021 -417.705924) (xy 65.918552 -417.650162) (xy 65.880606 -417.589771)
			(xy 65.849661 -417.525512) (xy 65.826104 -417.458192) (xy 65.810234 -417.388657) (xy 65.802248 -417.317783)
			(xy 36.158321 -417.317783) (xy 36.140713 -417.333835) (xy 36.071366 -417.386204) (xy 35.997482 -417.431951)
			(xy 35.919693 -417.470685) (xy 35.838661 -417.502077) (xy 35.755079 -417.525858) (xy 35.669659 -417.541826)
			(xy 35.58313 -417.549844) (xy 35.49623 -417.549844) (xy 35.409701 -417.541826) (xy 35.324281 -417.525858)
			(xy 35.240699 -417.502077) (xy 35.159667 -417.470685) (xy 35.081878 -417.431951) (xy 35.007994 -417.386204)
			(xy 34.938647 -417.333835) (xy 34.874427 -417.275291) (xy 34.815883 -417.211071) (xy 34.763514 -417.141724)
			(xy 34.717767 -417.06784) (xy 34.679033 -416.990051) (xy 34.647641 -416.909019) (xy 34.62386 -416.825437)
			(xy 34.607892 -416.740017) (xy 34.599874 -416.653488) (xy 31.399486 -416.653488) (xy 31.391468 -416.740017)
			(xy 31.3755 -416.825437) (xy 31.351719 -416.909019) (xy 31.320327 -416.990051) (xy 31.281593 -417.06784)
			(xy 31.235846 -417.141724) (xy 31.183477 -417.211071) (xy 31.124933 -417.275291) (xy 31.060713 -417.333835)
			(xy 30.991366 -417.386204) (xy 30.917482 -417.431951) (xy 30.839693 -417.470685) (xy 30.758661 -417.502077)
			(xy 30.675079 -417.525858) (xy 30.589659 -417.541826) (xy 30.50313 -417.549844) (xy 30.41623 -417.549844)
			(xy 30.329701 -417.541826) (xy 30.244281 -417.525858) (xy 30.160699 -417.502077) (xy 30.079667 -417.470685)
			(xy 30.001878 -417.431951) (xy 29.927994 -417.386204) (xy 29.858647 -417.333835) (xy 29.794427 -417.275291)
			(xy 29.735883 -417.211071) (xy 29.683514 -417.141724) (xy 29.637767 -417.06784) (xy 29.599033 -416.990051)
			(xy 29.567641 -416.909019) (xy 29.54386 -416.825437) (xy 29.527892 -416.740017) (xy 29.519874 -416.653488)
			(xy 28.341828 -416.653488) (xy 28.341828 -417.811204) (xy 51.478688 -417.811204) (xy 53.130196 -417.811204)
			(xy 53.130196 -419.462712) (xy 51.478688 -419.462712) (xy 51.478688 -417.811204) (xy 28.341828 -417.811204)
			(xy 28.341828 -419.193488) (xy 29.519874 -419.193488) (xy 29.519874 -419.106588) (xy 29.527892 -419.020059)
			(xy 29.54386 -418.934639) (xy 29.567641 -418.851057) (xy 29.599033 -418.770025) (xy 29.637767 -418.692236)
			(xy 29.683514 -418.618352) (xy 29.735883 -418.549005) (xy 29.794427 -418.484785) (xy 29.858647 -418.426241)
			(xy 29.927994 -418.373872) (xy 30.001878 -418.328125) (xy 30.079667 -418.289391) (xy 30.160699 -418.257999)
			(xy 30.244281 -418.234218) (xy 30.329701 -418.21825) (xy 30.41623 -418.210232) (xy 30.45968 -418.20973)
			(xy 30.50313 -418.210232) (xy 30.589659 -418.21825) (xy 30.675079 -418.234218) (xy 30.758661 -418.257999)
			(xy 30.839693 -418.289391) (xy 30.917482 -418.328125) (xy 30.991366 -418.373872) (xy 31.060713 -418.426241)
			(xy 31.124933 -418.484785) (xy 31.183477 -418.549005) (xy 31.235846 -418.618352) (xy 31.281593 -418.692236)
			(xy 31.320327 -418.770025) (xy 31.351719 -418.851057) (xy 31.3755 -418.934639) (xy 31.391468 -419.020059)
			(xy 31.399486 -419.106588) (xy 31.399486 -419.193488) (xy 34.599874 -419.193488) (xy 34.599874 -419.106588)
			(xy 34.607892 -419.020059) (xy 34.62386 -418.934639) (xy 34.647641 -418.851057) (xy 34.679033 -418.770025)
			(xy 34.717767 -418.692236) (xy 34.763514 -418.618352) (xy 34.815883 -418.549005) (xy 34.874427 -418.484785)
			(xy 34.938647 -418.426241) (xy 35.007994 -418.373872) (xy 35.081878 -418.328125) (xy 35.159667 -418.289391)
			(xy 35.240699 -418.257999) (xy 35.324281 -418.234218) (xy 35.409701 -418.21825) (xy 35.49623 -418.210232)
			(xy 35.53968 -418.20973) (xy 35.58313 -418.210232) (xy 35.669659 -418.21825) (xy 35.755079 -418.234218)
			(xy 35.838661 -418.257999) (xy 35.919693 -418.289391) (xy 35.997482 -418.328125) (xy 36.071366 -418.373872)
			(xy 36.140713 -418.426241) (xy 36.204933 -418.484785) (xy 36.263477 -418.549005) (xy 36.315846 -418.618352)
			(xy 36.361593 -418.692236) (xy 36.400327 -418.770025) (xy 36.431719 -418.851057) (xy 36.4555 -418.934639)
			(xy 36.471468 -419.020059) (xy 36.479486 -419.106588) (xy 36.479486 -419.193488) (xy 36.471468 -419.280017)
			(xy 36.4555 -419.365437) (xy 36.431719 -419.449019) (xy 36.400327 -419.530051) (xy 36.361593 -419.60784)
			(xy 36.315846 -419.681724) (xy 36.310064 -419.689381) (xy 65.802248 -419.689381) (xy 65.802248 -419.618059)
			(xy 65.810234 -419.547185) (xy 65.826104 -419.47765) (xy 65.849661 -419.41033) (xy 65.880606 -419.346071)
			(xy 65.918552 -419.28568) (xy 65.963021 -419.229918) (xy 66.013454 -419.179485) (xy 66.069216 -419.135016)
			(xy 66.129607 -419.09707) (xy 66.193866 -419.066125) (xy 66.261186 -419.042568) (xy 66.330721 -419.026698)
			(xy 66.401595 -419.018712) (xy 66.437256 -419.018212) (xy 66.472917 -419.018712) (xy 66.543791 -419.026698)
			(xy 66.613326 -419.042568) (xy 66.680646 -419.066125) (xy 66.744905 -419.09707) (xy 66.805296 -419.135016)
			(xy 66.861058 -419.179485) (xy 66.911491 -419.229918) (xy 66.95596 -419.28568) (xy 66.993906 -419.346071)
			(xy 67.024851 -419.41033) (xy 67.048408 -419.47765) (xy 67.064278 -419.547185) (xy 67.072264 -419.618059)
			(xy 67.072264 -419.689381) (xy 68.79386 -419.689381) (xy 68.79386 -419.618059) (xy 68.801846 -419.547185)
			(xy 68.817716 -419.47765) (xy 68.841273 -419.41033) (xy 68.872218 -419.346071) (xy 68.910164 -419.28568)
			(xy 68.954633 -419.229918) (xy 69.005066 -419.179485) (xy 69.060828 -419.135016) (xy 69.121219 -419.09707)
			(xy 69.185478 -419.066125) (xy 69.252798 -419.042568) (xy 69.322333 -419.026698) (xy 69.393207 -419.018712)
			(xy 69.428868 -419.018212) (xy 69.464529 -419.018712) (xy 69.535403 -419.026698) (xy 69.604938 -419.042568)
			(xy 69.672258 -419.066125) (xy 69.736517 -419.09707) (xy 69.796908 -419.135016) (xy 69.85267 -419.179485)
			(xy 69.903103 -419.229918) (xy 69.947572 -419.28568) (xy 69.985518 -419.346071) (xy 70.016463 -419.41033)
			(xy 70.04002 -419.47765) (xy 70.05589 -419.547185) (xy 70.063876 -419.618059) (xy 70.063876 -419.689381)
			(xy 70.05589 -419.760255) (xy 70.04002 -419.82979) (xy 70.016463 -419.89711) (xy 69.985518 -419.961369)
			(xy 69.947572 -420.02176) (xy 69.903103 -420.077522) (xy 69.870214 -420.110411) (xy 86.399122 -420.110411)
			(xy 86.401115 -419.910283) (xy 86.411112 -419.710394) (xy 86.429099 -419.511066) (xy 86.455047 -419.312617)
			(xy 86.488914 -419.115365) (xy 86.530646 -418.919626) (xy 86.580175 -418.725713) (xy 86.637424 -418.533938)
			(xy 86.702299 -418.344606) (xy 86.774698 -418.158022) (xy 86.854504 -417.974483) (xy 86.941589 -417.794285)
			(xy 87.035814 -417.617715) (xy 87.137028 -417.445056) (xy 87.245069 -417.276586) (xy 87.359764 -417.112572)
			(xy 87.48093 -416.953279) (xy 87.608371 -416.798962) (xy 87.741885 -416.649866) (xy 87.881257 -416.506232)
			(xy 88.026264 -416.36829) (xy 88.176675 -416.236259) (xy 88.332247 -416.110352) (xy 88.492732 -415.99077)
			(xy 88.657873 -415.877705) (xy 88.827405 -415.771337) (xy 89.001058 -415.671838) (xy 89.178552 -415.579366)
			(xy 89.359604 -415.49407) (xy 89.543924 -415.416086) (xy 89.731216 -415.345538) (xy 89.921181 -415.282541)
			(xy 90.113514 -415.227195) (xy 90.307908 -415.179588) (xy 90.504051 -415.139797) (xy 90.701628 -415.107885)
			(xy 90.900325 -415.083904) (xy 91.099821 -415.067891) (xy 91.299799 -415.059874) (xy 91.399868 -415.059368)
			(xy 91.499937 -415.059864) (xy 91.699915 -415.067861) (xy 91.899414 -415.083853) (xy 92.098112 -415.107814)
			(xy 92.295693 -415.139706) (xy 92.49184 -415.179477) (xy 92.686239 -415.227064) (xy 92.878578 -415.282391)
			(xy 93.068549 -415.345369) (xy 93.255848 -415.415897) (xy 93.440176 -415.493863) (xy 93.621237 -415.579141)
			(xy 93.79874 -415.671594) (xy 93.972403 -415.771076) (xy 94.141946 -415.877426) (xy 94.307099 -415.990475)
			(xy 94.467596 -416.11004) (xy 94.623181 -416.235932) (xy 94.773605 -416.367947) (xy 94.918626 -416.505875)
			(xy 95.058012 -416.649495) (xy 95.191541 -416.798576) (xy 95.318999 -416.952881) (xy 95.44018 -417.112162)
			(xy 95.554892 -417.276163) (xy 95.66295 -417.444623) (xy 95.764182 -417.617272) (xy 95.858425 -417.793832)
			(xy 95.945528 -417.974022) (xy 96.025353 -418.157552) (xy 96.09777 -418.344129) (xy 96.162665 -418.533454)
			(xy 96.219933 -418.725224) (xy 96.269483 -418.919131) (xy 96.311234 -419.114866) (xy 96.345121 -419.312115)
			(xy 96.371089 -419.510561) (xy 96.389096 -419.709888) (xy 96.399114 -419.909775) (xy 96.401127 -420.109903)
			(xy 96.395131 -420.309951) (xy 96.381135 -420.5096) (xy 96.359164 -420.708528) (xy 96.32925 -420.906418)
			(xy 96.291443 -421.102953) (xy 96.245804 -421.297818) (xy 96.192404 -421.490701) (xy 96.13133 -421.681293)
			(xy 96.062679 -421.869288) (xy 95.986561 -422.054387) (xy 95.903099 -422.236292) (xy 95.812426 -422.414711)
			(xy 95.714687 -422.589361) (xy 95.610038 -422.75996) (xy 95.498648 -422.926235) (xy 95.380694 -423.08792)
			(xy 95.256365 -423.244757) (xy 95.125862 -423.396494) (xy 94.989391 -423.542888) (xy 94.847173 -423.683704)
			(xy 94.699435 -423.818718) (xy 94.546413 -423.947713) (xy 94.388353 -424.070482) (xy 94.225507 -424.186829)
			(xy 94.058137 -424.296567) (xy 93.88651 -424.399521) (xy 93.710902 -424.495526) (xy 93.531592 -424.584428)
			(xy 93.34887 -424.666084) (xy 93.163027 -424.740365) (xy 92.97436 -424.807151) (xy 92.783173 -424.866334)
			(xy 92.589771 -424.917821) (xy 92.394464 -424.961529) (xy 92.197564 -424.997388) (xy 91.999387 -425.02534)
			(xy 91.800251 -425.04534) (xy 91.600474 -425.057358) (xy 91.400376 -425.061372) (xy 91.200278 -425.057378)
			(xy 91.000499 -425.045381) (xy 90.801361 -425.025401) (xy 90.603182 -424.997469) (xy 90.406278 -424.96163)
			(xy 90.210967 -424.917942) (xy 90.017559 -424.866475) (xy 89.826366 -424.807311) (xy 89.637693 -424.740544)
			(xy 89.451842 -424.666282) (xy 89.269111 -424.584644) (xy 89.089793 -424.495761) (xy 88.914175 -424.399774)
			(xy 88.742537 -424.296837) (xy 88.575156 -424.187116) (xy 88.412298 -424.070785) (xy 88.254226 -423.948032)
			(xy 88.101191 -423.819053) (xy 87.953439 -423.684055) (xy 87.811206 -423.543252) (xy 87.674721 -423.396872)
			(xy 87.544202 -423.245149) (xy 87.419858 -423.088325) (xy 87.301888 -422.926651) (xy 87.19048 -422.760387)
			(xy 87.085814 -422.589799) (xy 86.988057 -422.41516) (xy 86.897366 -422.236749) (xy 86.813885 -422.054853)
			(xy 86.737749 -421.869762) (xy 86.669079 -421.681773) (xy 86.607986 -421.491188) (xy 86.554566 -421.29831)
			(xy 86.508906 -421.10345) (xy 86.47108 -420.906919) (xy 86.441146 -420.709032) (xy 86.419154 -420.510106)
			(xy 86.405139 -420.310459) (xy 86.399122 -420.110411) (xy 69.870214 -420.110411) (xy 69.85267 -420.127955)
			(xy 69.796908 -420.172424) (xy 69.736517 -420.21037) (xy 69.672258 -420.241315) (xy 69.604938 -420.264872)
			(xy 69.535403 -420.280742) (xy 69.464529 -420.288728) (xy 69.393207 -420.288728) (xy 69.322333 -420.280742)
			(xy 69.252798 -420.264872) (xy 69.185478 -420.241315) (xy 69.121219 -420.21037) (xy 69.060828 -420.172424)
			(xy 69.005066 -420.127955) (xy 68.954633 -420.077522) (xy 68.910164 -420.02176) (xy 68.872218 -419.961369)
			(xy 68.841273 -419.89711) (xy 68.817716 -419.82979) (xy 68.801846 -419.760255) (xy 68.79386 -419.689381)
			(xy 67.072264 -419.689381) (xy 67.064278 -419.760255) (xy 67.048408 -419.82979) (xy 67.024851 -419.89711)
			(xy 66.993906 -419.961369) (xy 66.95596 -420.02176) (xy 66.911491 -420.077522) (xy 66.861058 -420.127955)
			(xy 66.805296 -420.172424) (xy 66.744905 -420.21037) (xy 66.680646 -420.241315) (xy 66.613326 -420.264872)
			(xy 66.543791 -420.280742) (xy 66.472917 -420.288728) (xy 66.401595 -420.288728) (xy 66.330721 -420.280742)
			(xy 66.261186 -420.264872) (xy 66.193866 -420.241315) (xy 66.129607 -420.21037) (xy 66.069216 -420.172424)
			(xy 66.013454 -420.127955) (xy 65.963021 -420.077522) (xy 65.918552 -420.02176) (xy 65.880606 -419.961369)
			(xy 65.849661 -419.89711) (xy 65.826104 -419.82979) (xy 65.810234 -419.760255) (xy 65.802248 -419.689381)
			(xy 36.310064 -419.689381) (xy 36.263477 -419.751071) (xy 36.204933 -419.815291) (xy 36.140713 -419.873835)
			(xy 36.071366 -419.926204) (xy 35.997482 -419.971951) (xy 35.919693 -420.010685) (xy 35.838661 -420.042077)
			(xy 35.755079 -420.065858) (xy 35.669659 -420.081826) (xy 35.58313 -420.089844) (xy 35.49623 -420.089844)
			(xy 35.409701 -420.081826) (xy 35.324281 -420.065858) (xy 35.240699 -420.042077) (xy 35.159667 -420.010685)
			(xy 35.081878 -419.971951) (xy 35.007994 -419.926204) (xy 34.938647 -419.873835) (xy 34.874427 -419.815291)
			(xy 34.815883 -419.751071) (xy 34.763514 -419.681724) (xy 34.717767 -419.60784) (xy 34.679033 -419.530051)
			(xy 34.647641 -419.449019) (xy 34.62386 -419.365437) (xy 34.607892 -419.280017) (xy 34.599874 -419.193488)
			(xy 31.399486 -419.193488) (xy 31.391468 -419.280017) (xy 31.3755 -419.365437) (xy 31.351719 -419.449019)
			(xy 31.320327 -419.530051) (xy 31.281593 -419.60784) (xy 31.235846 -419.681724) (xy 31.183477 -419.751071)
			(xy 31.124933 -419.815291) (xy 31.060713 -419.873835) (xy 30.991366 -419.926204) (xy 30.917482 -419.971951)
			(xy 30.839693 -420.010685) (xy 30.758661 -420.042077) (xy 30.675079 -420.065858) (xy 30.589659 -420.081826)
			(xy 30.50313 -420.089844) (xy 30.41623 -420.089844) (xy 30.329701 -420.081826) (xy 30.244281 -420.065858)
			(xy 30.160699 -420.042077) (xy 30.079667 -420.010685) (xy 30.001878 -419.971951) (xy 29.927994 -419.926204)
			(xy 29.858647 -419.873835) (xy 29.794427 -419.815291) (xy 29.735883 -419.751071) (xy 29.683514 -419.681724)
			(xy 29.637767 -419.60784) (xy 29.599033 -419.530051) (xy 29.567641 -419.449019) (xy 29.54386 -419.365437)
			(xy 29.527892 -419.280017) (xy 29.519874 -419.193488) (xy 28.341828 -419.193488) (xy 28.341828 -421.733488)
			(xy 29.519874 -421.733488) (xy 29.519874 -421.646588) (xy 29.527892 -421.560059) (xy 29.54386 -421.474639)
			(xy 29.567641 -421.391057) (xy 29.599033 -421.310025) (xy 29.637767 -421.232236) (xy 29.683514 -421.158352)
			(xy 29.735883 -421.089005) (xy 29.794427 -421.024785) (xy 29.858647 -420.966241) (xy 29.927994 -420.913872)
			(xy 30.001878 -420.868125) (xy 30.079667 -420.829391) (xy 30.160699 -420.797999) (xy 30.244281 -420.774218)
			(xy 30.329701 -420.75825) (xy 30.41623 -420.750232) (xy 30.45968 -420.74973) (xy 30.50313 -420.750232)
			(xy 30.589659 -420.75825) (xy 30.675079 -420.774218) (xy 30.758661 -420.797999) (xy 30.839693 -420.829391)
			(xy 30.917482 -420.868125) (xy 30.991366 -420.913872) (xy 31.060713 -420.966241) (xy 31.124933 -421.024785)
			(xy 31.183477 -421.089005) (xy 31.235846 -421.158352) (xy 31.281593 -421.232236) (xy 31.320327 -421.310025)
			(xy 31.351719 -421.391057) (xy 31.3755 -421.474639) (xy 31.391468 -421.560059) (xy 31.399486 -421.646588)
			(xy 31.399486 -421.733488) (xy 34.599874 -421.733488) (xy 34.599874 -421.646588) (xy 34.607892 -421.560059)
			(xy 34.62386 -421.474639) (xy 34.647641 -421.391057) (xy 34.679033 -421.310025) (xy 34.717767 -421.232236)
			(xy 34.763514 -421.158352) (xy 34.815883 -421.089005) (xy 34.874427 -421.024785) (xy 34.938647 -420.966241)
			(xy 35.007994 -420.913872) (xy 35.081878 -420.868125) (xy 35.159667 -420.829391) (xy 35.240699 -420.797999)
			(xy 35.324281 -420.774218) (xy 35.409701 -420.75825) (xy 35.49623 -420.750232) (xy 35.53968 -420.74973)
			(xy 35.58313 -420.750232) (xy 35.669659 -420.75825) (xy 35.755079 -420.774218) (xy 35.838661 -420.797999)
			(xy 35.919693 -420.829391) (xy 35.997482 -420.868125) (xy 36.071366 -420.913872) (xy 36.140713 -420.966241)
			(xy 36.152134 -420.976653) (xy 39.62196 -420.976653) (xy 39.62196 -420.905331) (xy 39.629946 -420.834457)
			(xy 39.645816 -420.764922) (xy 39.669373 -420.697602) (xy 39.700318 -420.633343) (xy 39.738264 -420.572952)
			(xy 39.782733 -420.51719) (xy 39.833166 -420.466757) (xy 39.888928 -420.422288) (xy 39.949319 -420.384342)
			(xy 40.013578 -420.353397) (xy 40.080898 -420.32984) (xy 40.150433 -420.31397) (xy 40.221307 -420.305984)
			(xy 40.256968 -420.305484) (xy 40.292629 -420.305984) (xy 40.363503 -420.31397) (xy 40.433038 -420.32984)
			(xy 40.500358 -420.353397) (xy 40.564617 -420.384342) (xy 40.625008 -420.422288) (xy 40.68077 -420.466757)
			(xy 40.731203 -420.51719) (xy 40.775672 -420.572952) (xy 40.813618 -420.633343) (xy 40.844563 -420.697602)
			(xy 40.86812 -420.764922) (xy 40.88399 -420.834457) (xy 40.891976 -420.905331) (xy 40.891976 -420.976653)
			(xy 40.88399 -421.047527) (xy 40.86812 -421.117062) (xy 40.844563 -421.184382) (xy 40.813618 -421.248641)
			(xy 40.775672 -421.309032) (xy 40.731203 -421.364794) (xy 40.68077 -421.415227) (xy 40.625008 -421.459696)
			(xy 40.564617 -421.497642) (xy 40.500358 -421.528587) (xy 40.433038 -421.552144) (xy 40.363503 -421.568014)
			(xy 40.292629 -421.576) (xy 40.221307 -421.576) (xy 40.150433 -421.568014) (xy 40.080898 -421.552144)
			(xy 40.013578 -421.528587) (xy 39.949319 -421.497642) (xy 39.888928 -421.459696) (xy 39.833166 -421.415227)
			(xy 39.782733 -421.364794) (xy 39.738264 -421.309032) (xy 39.700318 -421.248641) (xy 39.669373 -421.184382)
			(xy 39.645816 -421.117062) (xy 39.629946 -421.047527) (xy 39.62196 -420.976653) (xy 36.152134 -420.976653)
			(xy 36.204933 -421.024785) (xy 36.263477 -421.089005) (xy 36.315846 -421.158352) (xy 36.361593 -421.232236)
			(xy 36.400327 -421.310025) (xy 36.431719 -421.391057) (xy 36.4555 -421.474639) (xy 36.471468 -421.560059)
			(xy 36.479486 -421.646588) (xy 36.479486 -421.652293) (xy 65.802248 -421.652293) (xy 65.802248 -421.580971)
			(xy 65.810234 -421.510097) (xy 65.826104 -421.440562) (xy 65.849661 -421.373242) (xy 65.880606 -421.308983)
			(xy 65.918552 -421.248592) (xy 65.963021 -421.19283) (xy 66.013454 -421.142397) (xy 66.069216 -421.097928)
			(xy 66.129607 -421.059982) (xy 66.193866 -421.029037) (xy 66.261186 -421.00548) (xy 66.330721 -420.98961)
			(xy 66.401595 -420.981624) (xy 66.437256 -420.981124) (xy 66.472917 -420.981624) (xy 66.543791 -420.98961)
			(xy 66.613326 -421.00548) (xy 66.680646 -421.029037) (xy 66.744905 -421.059982) (xy 66.805296 -421.097928)
			(xy 66.861058 -421.142397) (xy 66.911491 -421.19283) (xy 66.95596 -421.248592) (xy 66.993906 -421.308983)
			(xy 67.024851 -421.373242) (xy 67.048408 -421.440562) (xy 67.064278 -421.510097) (xy 67.072264 -421.580971)
			(xy 67.072264 -421.652293) (xy 68.79386 -421.652293) (xy 68.79386 -421.580971) (xy 68.801846 -421.510097)
			(xy 68.817716 -421.440562) (xy 68.841273 -421.373242) (xy 68.872218 -421.308983) (xy 68.910164 -421.248592)
			(xy 68.954633 -421.19283) (xy 69.005066 -421.142397) (xy 69.060828 -421.097928) (xy 69.121219 -421.059982)
			(xy 69.185478 -421.029037) (xy 69.252798 -421.00548) (xy 69.322333 -420.98961) (xy 69.393207 -420.981624)
			(xy 69.428868 -420.981124) (xy 69.464529 -420.981624) (xy 69.535403 -420.98961) (xy 69.604938 -421.00548)
			(xy 69.672258 -421.029037) (xy 69.736517 -421.059982) (xy 69.796908 -421.097928) (xy 69.85267 -421.142397)
			(xy 69.903103 -421.19283) (xy 69.947572 -421.248592) (xy 69.985518 -421.308983) (xy 70.016463 -421.373242)
			(xy 70.04002 -421.440562) (xy 70.05589 -421.510097) (xy 70.063876 -421.580971) (xy 70.063876 -421.652293)
			(xy 70.05589 -421.723167) (xy 70.04002 -421.792702) (xy 70.016463 -421.860022) (xy 69.985518 -421.924281)
			(xy 69.947572 -421.984672) (xy 69.903103 -422.040434) (xy 69.85267 -422.090867) (xy 69.796908 -422.135336)
			(xy 69.736517 -422.173282) (xy 69.672258 -422.204227) (xy 69.604938 -422.227784) (xy 69.535403 -422.243654)
			(xy 69.464529 -422.25164) (xy 69.393207 -422.25164) (xy 69.322333 -422.243654) (xy 69.252798 -422.227784)
			(xy 69.185478 -422.204227) (xy 69.121219 -422.173282) (xy 69.060828 -422.135336) (xy 69.005066 -422.090867)
			(xy 68.954633 -422.040434) (xy 68.910164 -421.984672) (xy 68.872218 -421.924281) (xy 68.841273 -421.860022)
			(xy 68.817716 -421.792702) (xy 68.801846 -421.723167) (xy 68.79386 -421.652293) (xy 67.072264 -421.652293)
			(xy 67.064278 -421.723167) (xy 67.048408 -421.792702) (xy 67.024851 -421.860022) (xy 66.993906 -421.924281)
			(xy 66.95596 -421.984672) (xy 66.911491 -422.040434) (xy 66.861058 -422.090867) (xy 66.805296 -422.135336)
			(xy 66.744905 -422.173282) (xy 66.680646 -422.204227) (xy 66.613326 -422.227784) (xy 66.543791 -422.243654)
			(xy 66.472917 -422.25164) (xy 66.401595 -422.25164) (xy 66.330721 -422.243654) (xy 66.261186 -422.227784)
			(xy 66.193866 -422.204227) (xy 66.129607 -422.173282) (xy 66.069216 -422.135336) (xy 66.013454 -422.090867)
			(xy 65.963021 -422.040434) (xy 65.918552 -421.984672) (xy 65.880606 -421.924281) (xy 65.849661 -421.860022)
			(xy 65.826104 -421.792702) (xy 65.810234 -421.723167) (xy 65.802248 -421.652293) (xy 36.479486 -421.652293)
			(xy 36.479486 -421.733488) (xy 36.471468 -421.820017) (xy 36.4555 -421.905437) (xy 36.431719 -421.989019)
			(xy 36.400327 -422.070051) (xy 36.361593 -422.14784) (xy 36.315846 -422.221724) (xy 36.263477 -422.291071)
			(xy 36.204933 -422.355291) (xy 36.140713 -422.413835) (xy 36.071366 -422.466204) (xy 35.997482 -422.511951)
			(xy 35.919693 -422.550685) (xy 35.838661 -422.582077) (xy 35.755079 -422.605858) (xy 35.669659 -422.621826)
			(xy 35.58313 -422.629844) (xy 35.49623 -422.629844) (xy 35.409701 -422.621826) (xy 35.324281 -422.605858)
			(xy 35.240699 -422.582077) (xy 35.159667 -422.550685) (xy 35.081878 -422.511951) (xy 35.007994 -422.466204)
			(xy 34.938647 -422.413835) (xy 34.874427 -422.355291) (xy 34.815883 -422.291071) (xy 34.763514 -422.221724)
			(xy 34.717767 -422.14784) (xy 34.679033 -422.070051) (xy 34.647641 -421.989019) (xy 34.62386 -421.905437)
			(xy 34.607892 -421.820017) (xy 34.599874 -421.733488) (xy 31.399486 -421.733488) (xy 31.391468 -421.820017)
			(xy 31.3755 -421.905437) (xy 31.351719 -421.989019) (xy 31.320327 -422.070051) (xy 31.281593 -422.14784)
			(xy 31.235846 -422.221724) (xy 31.183477 -422.291071) (xy 31.124933 -422.355291) (xy 31.060713 -422.413835)
			(xy 30.991366 -422.466204) (xy 30.917482 -422.511951) (xy 30.839693 -422.550685) (xy 30.758661 -422.582077)
			(xy 30.675079 -422.605858) (xy 30.589659 -422.621826) (xy 30.50313 -422.629844) (xy 30.41623 -422.629844)
			(xy 30.329701 -422.621826) (xy 30.244281 -422.605858) (xy 30.160699 -422.582077) (xy 30.079667 -422.550685)
			(xy 30.001878 -422.511951) (xy 29.927994 -422.466204) (xy 29.858647 -422.413835) (xy 29.794427 -422.355291)
			(xy 29.735883 -422.291071) (xy 29.683514 -422.221724) (xy 29.637767 -422.14784) (xy 29.599033 -422.070051)
			(xy 29.567641 -421.989019) (xy 29.54386 -421.905437) (xy 29.527892 -421.820017) (xy 29.519874 -421.733488)
			(xy 28.341828 -421.733488) (xy 28.341828 -424.273488) (xy 29.519874 -424.273488) (xy 29.519874 -424.186588)
			(xy 29.527892 -424.100059) (xy 29.54386 -424.014639) (xy 29.567641 -423.931057) (xy 29.599033 -423.850025)
			(xy 29.637767 -423.772236) (xy 29.683514 -423.698352) (xy 29.735883 -423.629005) (xy 29.794427 -423.564785)
			(xy 29.858647 -423.506241) (xy 29.927994 -423.453872) (xy 30.001878 -423.408125) (xy 30.079667 -423.369391)
			(xy 30.160699 -423.337999) (xy 30.244281 -423.314218) (xy 30.329701 -423.29825) (xy 30.41623 -423.290232)
			(xy 30.45968 -423.28973) (xy 30.50313 -423.290232) (xy 30.589659 -423.29825) (xy 30.675079 -423.314218)
			(xy 30.758661 -423.337999) (xy 30.839693 -423.369391) (xy 30.917482 -423.408125) (xy 30.991366 -423.453872)
			(xy 31.060713 -423.506241) (xy 31.124933 -423.564785) (xy 31.183477 -423.629005) (xy 31.235846 -423.698352)
			(xy 31.281593 -423.772236) (xy 31.320327 -423.850025) (xy 31.351719 -423.931057) (xy 31.3755 -424.014639)
			(xy 31.391468 -424.100059) (xy 31.399486 -424.186588) (xy 31.399486 -424.273488) (xy 34.599874 -424.273488)
			(xy 34.599874 -424.186588) (xy 34.607892 -424.100059) (xy 34.62386 -424.014639) (xy 34.647641 -423.931057)
			(xy 34.679033 -423.850025) (xy 34.717767 -423.772236) (xy 34.763514 -423.698352) (xy 34.815883 -423.629005)
			(xy 34.874427 -423.564785) (xy 34.938647 -423.506241) (xy 35.007994 -423.453872) (xy 35.081878 -423.408125)
			(xy 35.159667 -423.369391) (xy 35.240699 -423.337999) (xy 35.324281 -423.314218) (xy 35.409701 -423.29825)
			(xy 35.49623 -423.290232) (xy 35.53968 -423.28973) (xy 35.58313 -423.290232) (xy 35.669659 -423.29825)
			(xy 35.755079 -423.314218) (xy 35.838661 -423.337999) (xy 35.919693 -423.369391) (xy 35.997482 -423.408125)
			(xy 36.071366 -423.453872) (xy 36.140713 -423.506241) (xy 36.204933 -423.564785) (xy 36.263477 -423.629005)
			(xy 36.277416 -423.647463) (xy 39.62196 -423.647463) (xy 39.62196 -423.576141) (xy 39.629946 -423.505267)
			(xy 39.645816 -423.435732) (xy 39.669373 -423.368412) (xy 39.700318 -423.304153) (xy 39.738264 -423.243762)
			(xy 39.782733 -423.188) (xy 39.833166 -423.137567) (xy 39.888928 -423.093098) (xy 39.949319 -423.055152)
			(xy 40.013578 -423.024207) (xy 40.080898 -423.00065) (xy 40.150433 -422.98478) (xy 40.221307 -422.976794)
			(xy 40.256968 -422.976294) (xy 40.292629 -422.976794) (xy 40.363503 -422.98478) (xy 40.433038 -423.00065)
			(xy 40.500358 -423.024207) (xy 40.564617 -423.055152) (xy 40.625008 -423.093098) (xy 40.68077 -423.137567)
			(xy 40.731203 -423.188) (xy 40.775672 -423.243762) (xy 40.813618 -423.304153) (xy 40.844563 -423.368412)
			(xy 40.86812 -423.435732) (xy 40.88399 -423.505267) (xy 40.891976 -423.576141) (xy 40.891976 -423.647463)
			(xy 40.88399 -423.718337) (xy 40.86812 -423.787872) (xy 40.865346 -423.795799) (xy 65.802248 -423.795799)
			(xy 65.802248 -423.724477) (xy 65.810234 -423.653603) (xy 65.826104 -423.584068) (xy 65.849661 -423.516748)
			(xy 65.880606 -423.452489) (xy 65.918552 -423.392098) (xy 65.963021 -423.336336) (xy 66.013454 -423.285903)
			(xy 66.069216 -423.241434) (xy 66.129607 -423.203488) (xy 66.193866 -423.172543) (xy 66.261186 -423.148986)
			(xy 66.330721 -423.133116) (xy 66.401595 -423.12513) (xy 66.437256 -423.12463) (xy 66.472917 -423.12513)
			(xy 66.543791 -423.133116) (xy 66.613326 -423.148986) (xy 66.680646 -423.172543) (xy 66.744905 -423.203488)
			(xy 66.805296 -423.241434) (xy 66.861058 -423.285903) (xy 66.911491 -423.336336) (xy 66.95596 -423.392098)
			(xy 66.993906 -423.452489) (xy 67.024851 -423.516748) (xy 67.048408 -423.584068) (xy 67.064278 -423.653603)
			(xy 67.072264 -423.724477) (xy 67.072264 -423.795799) (xy 68.79386 -423.795799) (xy 68.79386 -423.724477)
			(xy 68.801846 -423.653603) (xy 68.817716 -423.584068) (xy 68.841273 -423.516748) (xy 68.872218 -423.452489)
			(xy 68.910164 -423.392098) (xy 68.954633 -423.336336) (xy 69.005066 -423.285903) (xy 69.060828 -423.241434)
			(xy 69.121219 -423.203488) (xy 69.185478 -423.172543) (xy 69.252798 -423.148986) (xy 69.322333 -423.133116)
			(xy 69.393207 -423.12513) (xy 69.428868 -423.12463) (xy 69.464529 -423.12513) (xy 69.535403 -423.133116)
			(xy 69.604938 -423.148986) (xy 69.672258 -423.172543) (xy 69.736517 -423.203488) (xy 69.796908 -423.241434)
			(xy 69.85267 -423.285903) (xy 69.903103 -423.336336) (xy 69.947572 -423.392098) (xy 69.985518 -423.452489)
			(xy 70.016463 -423.516748) (xy 70.04002 -423.584068) (xy 70.05589 -423.653603) (xy 70.063876 -423.724477)
			(xy 70.063876 -423.795799) (xy 70.05589 -423.866673) (xy 70.04002 -423.936208) (xy 70.016463 -424.003528)
			(xy 69.985518 -424.067787) (xy 69.947572 -424.128178) (xy 69.903103 -424.18394) (xy 69.85267 -424.234373)
			(xy 69.796908 -424.278842) (xy 69.736517 -424.316788) (xy 69.672258 -424.347733) (xy 69.604938 -424.37129)
			(xy 69.535403 -424.38716) (xy 69.464529 -424.395146) (xy 69.393207 -424.395146) (xy 69.322333 -424.38716)
			(xy 69.252798 -424.37129) (xy 69.185478 -424.347733) (xy 69.121219 -424.316788) (xy 69.060828 -424.278842)
			(xy 69.005066 -424.234373) (xy 68.954633 -424.18394) (xy 68.910164 -424.128178) (xy 68.872218 -424.067787)
			(xy 68.841273 -424.003528) (xy 68.817716 -423.936208) (xy 68.801846 -423.866673) (xy 68.79386 -423.795799)
			(xy 67.072264 -423.795799) (xy 67.064278 -423.866673) (xy 67.048408 -423.936208) (xy 67.024851 -424.003528)
			(xy 66.993906 -424.067787) (xy 66.95596 -424.128178) (xy 66.911491 -424.18394) (xy 66.861058 -424.234373)
			(xy 66.805296 -424.278842) (xy 66.744905 -424.316788) (xy 66.680646 -424.347733) (xy 66.613326 -424.37129)
			(xy 66.543791 -424.38716) (xy 66.472917 -424.395146) (xy 66.401595 -424.395146) (xy 66.330721 -424.38716)
			(xy 66.261186 -424.37129) (xy 66.193866 -424.347733) (xy 66.129607 -424.316788) (xy 66.069216 -424.278842)
			(xy 66.013454 -424.234373) (xy 65.963021 -424.18394) (xy 65.918552 -424.128178) (xy 65.880606 -424.067787)
			(xy 65.849661 -424.003528) (xy 65.826104 -423.936208) (xy 65.810234 -423.866673) (xy 65.802248 -423.795799)
			(xy 40.865346 -423.795799) (xy 40.844563 -423.855192) (xy 40.813618 -423.919451) (xy 40.775672 -423.979842)
			(xy 40.731203 -424.035604) (xy 40.68077 -424.086037) (xy 40.625008 -424.130506) (xy 40.564617 -424.168452)
			(xy 40.500358 -424.199397) (xy 40.433038 -424.222954) (xy 40.363503 -424.238824) (xy 40.292629 -424.24681)
			(xy 40.221307 -424.24681) (xy 40.150433 -424.238824) (xy 40.080898 -424.222954) (xy 40.013578 -424.199397)
			(xy 39.949319 -424.168452) (xy 39.888928 -424.130506) (xy 39.833166 -424.086037) (xy 39.782733 -424.035604)
			(xy 39.738264 -423.979842) (xy 39.700318 -423.919451) (xy 39.669373 -423.855192) (xy 39.645816 -423.787872)
			(xy 39.629946 -423.718337) (xy 39.62196 -423.647463) (xy 36.277416 -423.647463) (xy 36.315846 -423.698352)
			(xy 36.361593 -423.772236) (xy 36.400327 -423.850025) (xy 36.431719 -423.931057) (xy 36.4555 -424.014639)
			(xy 36.471468 -424.100059) (xy 36.479486 -424.186588) (xy 36.479486 -424.273488) (xy 36.471468 -424.360017)
			(xy 36.4555 -424.445437) (xy 36.431719 -424.529019) (xy 36.400327 -424.610051) (xy 36.361593 -424.68784)
			(xy 36.315846 -424.761724) (xy 36.263477 -424.831071) (xy 36.204933 -424.895291) (xy 36.140713 -424.953835)
			(xy 36.071366 -425.006204) (xy 35.997482 -425.051951) (xy 35.919693 -425.090685) (xy 35.838661 -425.122077)
			(xy 35.755079 -425.145858) (xy 35.669659 -425.161826) (xy 35.58313 -425.169844) (xy 35.49623 -425.169844)
			(xy 35.409701 -425.161826) (xy 35.324281 -425.145858) (xy 35.240699 -425.122077) (xy 35.159667 -425.090685)
			(xy 35.081878 -425.051951) (xy 35.007994 -425.006204) (xy 34.938647 -424.953835) (xy 34.874427 -424.895291)
			(xy 34.815883 -424.831071) (xy 34.763514 -424.761724) (xy 34.717767 -424.68784) (xy 34.679033 -424.610051)
			(xy 34.647641 -424.529019) (xy 34.62386 -424.445437) (xy 34.607892 -424.360017) (xy 34.599874 -424.273488)
			(xy 31.399486 -424.273488) (xy 31.391468 -424.360017) (xy 31.3755 -424.445437) (xy 31.351719 -424.529019)
			(xy 31.320327 -424.610051) (xy 31.281593 -424.68784) (xy 31.235846 -424.761724) (xy 31.183477 -424.831071)
			(xy 31.124933 -424.895291) (xy 31.060713 -424.953835) (xy 30.991366 -425.006204) (xy 30.917482 -425.051951)
			(xy 30.839693 -425.090685) (xy 30.758661 -425.122077) (xy 30.675079 -425.145858) (xy 30.589659 -425.161826)
			(xy 30.50313 -425.169844) (xy 30.41623 -425.169844) (xy 30.329701 -425.161826) (xy 30.244281 -425.145858)
			(xy 30.160699 -425.122077) (xy 30.079667 -425.090685) (xy 30.001878 -425.051951) (xy 29.927994 -425.006204)
			(xy 29.858647 -424.953835) (xy 29.794427 -424.895291) (xy 29.735883 -424.831071) (xy 29.683514 -424.761724)
			(xy 29.637767 -424.68784) (xy 29.599033 -424.610051) (xy 29.567641 -424.529019) (xy 29.54386 -424.445437)
			(xy 29.527892 -424.360017) (xy 29.519874 -424.273488) (xy 28.341828 -424.273488) (xy 28.341828 -426.813488)
			(xy 29.519874 -426.813488) (xy 29.519874 -426.726588) (xy 29.527892 -426.640059) (xy 29.54386 -426.554639)
			(xy 29.567641 -426.471057) (xy 29.599033 -426.390025) (xy 29.637767 -426.312236) (xy 29.683514 -426.238352)
			(xy 29.735883 -426.169005) (xy 29.794427 -426.104785) (xy 29.858647 -426.046241) (xy 29.927994 -425.993872)
			(xy 30.001878 -425.948125) (xy 30.079667 -425.909391) (xy 30.160699 -425.877999) (xy 30.244281 -425.854218)
			(xy 30.329701 -425.83825) (xy 30.41623 -425.830232) (xy 30.45968 -425.82973) (xy 30.50313 -425.830232)
			(xy 30.589659 -425.83825) (xy 30.675079 -425.854218) (xy 30.758661 -425.877999) (xy 30.839693 -425.909391)
			(xy 30.917482 -425.948125) (xy 30.991366 -425.993872) (xy 31.060713 -426.046241) (xy 31.124933 -426.104785)
			(xy 31.183477 -426.169005) (xy 31.235846 -426.238352) (xy 31.281593 -426.312236) (xy 31.320327 -426.390025)
			(xy 31.351719 -426.471057) (xy 31.3755 -426.554639) (xy 31.391468 -426.640059) (xy 31.399486 -426.726588)
			(xy 31.399486 -426.813488) (xy 34.599874 -426.813488) (xy 34.599874 -426.726588) (xy 34.607892 -426.640059)
			(xy 34.62386 -426.554639) (xy 34.647641 -426.471057) (xy 34.679033 -426.390025) (xy 34.717767 -426.312236)
			(xy 34.763514 -426.238352) (xy 34.815883 -426.169005) (xy 34.874427 -426.104785) (xy 34.938647 -426.046241)
			(xy 35.007994 -425.993872) (xy 35.081878 -425.948125) (xy 35.159667 -425.909391) (xy 35.240699 -425.877999)
			(xy 35.324281 -425.854218) (xy 35.409701 -425.83825) (xy 35.49623 -425.830232) (xy 35.53968 -425.82973)
			(xy 35.58313 -425.830232) (xy 35.669659 -425.83825) (xy 35.755079 -425.854218) (xy 35.838661 -425.877999)
			(xy 35.919693 -425.909391) (xy 35.997482 -425.948125) (xy 36.071366 -425.993872) (xy 36.140713 -426.046241)
			(xy 36.204933 -426.104785) (xy 36.263477 -426.169005) (xy 36.315846 -426.238352) (xy 36.361593 -426.312236)
			(xy 36.363334 -426.315733) (xy 39.62196 -426.315733) (xy 39.62196 -426.244411) (xy 39.629946 -426.173537)
			(xy 39.645816 -426.104002) (xy 39.669373 -426.036682) (xy 39.700318 -425.972423) (xy 39.738264 -425.912032)
			(xy 39.782733 -425.85627) (xy 39.833166 -425.805837) (xy 39.888928 -425.761368) (xy 39.949319 -425.723422)
			(xy 40.013578 -425.692477) (xy 40.080898 -425.66892) (xy 40.150433 -425.65305) (xy 40.221307 -425.645064)
			(xy 40.256968 -425.644564) (xy 40.292629 -425.645064) (xy 40.363503 -425.65305) (xy 40.433038 -425.66892)
			(xy 40.500358 -425.692477) (xy 40.564617 -425.723422) (xy 40.625008 -425.761368) (xy 40.68077 -425.805837)
			(xy 40.731203 -425.85627) (xy 40.758328 -425.890283) (xy 64.063364 -425.890283) (xy 64.063364 -425.818961)
			(xy 64.07135 -425.748087) (xy 64.08722 -425.678552) (xy 64.110777 -425.611232) (xy 64.141722 -425.546973)
			(xy 64.179668 -425.486582) (xy 64.224137 -425.43082) (xy 64.27457 -425.380387) (xy 64.330332 -425.335918)
			(xy 64.390723 -425.297972) (xy 64.454982 -425.267027) (xy 64.522302 -425.24347) (xy 64.591837 -425.2276)
			(xy 64.662711 -425.219614) (xy 64.698372 -425.219114) (xy 64.734033 -425.219614) (xy 64.804907 -425.2276)
			(xy 64.874442 -425.24347) (xy 64.941762 -425.267027) (xy 65.006021 -425.297972) (xy 65.066412 -425.335918)
			(xy 65.122174 -425.380387) (xy 65.172607 -425.43082) (xy 65.217076 -425.486582) (xy 65.255022 -425.546973)
			(xy 65.285967 -425.611232) (xy 65.309524 -425.678552) (xy 65.325394 -425.748087) (xy 65.33338 -425.818961)
			(xy 65.33338 -425.890283) (xy 66.867778 -425.890283) (xy 66.867778 -425.818961) (xy 66.875764 -425.748087)
			(xy 66.891634 -425.678552) (xy 66.915191 -425.611232) (xy 66.946136 -425.546973) (xy 66.984082 -425.486582)
			(xy 67.028551 -425.43082) (xy 67.078984 -425.380387) (xy 67.134746 -425.335918) (xy 67.195137 -425.297972)
			(xy 67.259396 -425.267027) (xy 67.326716 -425.24347) (xy 67.396251 -425.2276) (xy 67.467125 -425.219614)
			(xy 67.502786 -425.219114) (xy 67.538447 -425.219614) (xy 67.609321 -425.2276) (xy 67.678856 -425.24347)
			(xy 67.746176 -425.267027) (xy 67.810435 -425.297972) (xy 67.870826 -425.335918) (xy 67.926588 -425.380387)
			(xy 67.977021 -425.43082) (xy 68.02149 -425.486582) (xy 68.059436 -425.546973) (xy 68.090381 -425.611232)
			(xy 68.113938 -425.678552) (xy 68.129808 -425.748087) (xy 68.137794 -425.818961) (xy 68.137794 -425.890283)
			(xy 68.129808 -425.961157) (xy 68.113938 -426.030692) (xy 68.090381 -426.098012) (xy 68.059436 -426.162271)
			(xy 68.02149 -426.222662) (xy 67.977021 -426.278424) (xy 67.926588 -426.328857) (xy 67.870826 -426.373326)
			(xy 67.810435 -426.411272) (xy 67.746176 -426.442217) (xy 67.678856 -426.465774) (xy 67.609321 -426.481644)
			(xy 67.538447 -426.48963) (xy 67.467125 -426.48963) (xy 67.396251 -426.481644) (xy 67.326716 -426.465774)
			(xy 67.259396 -426.442217) (xy 67.195137 -426.411272) (xy 67.134746 -426.373326) (xy 67.078984 -426.328857)
			(xy 67.028551 -426.278424) (xy 66.984082 -426.222662) (xy 66.946136 -426.162271) (xy 66.915191 -426.098012)
			(xy 66.891634 -426.030692) (xy 66.875764 -425.961157) (xy 66.867778 -425.890283) (xy 65.33338 -425.890283)
			(xy 65.325394 -425.961157) (xy 65.309524 -426.030692) (xy 65.285967 -426.098012) (xy 65.255022 -426.162271)
			(xy 65.217076 -426.222662) (xy 65.172607 -426.278424) (xy 65.122174 -426.328857) (xy 65.066412 -426.373326)
			(xy 65.006021 -426.411272) (xy 64.941762 -426.442217) (xy 64.874442 -426.465774) (xy 64.804907 -426.481644)
			(xy 64.734033 -426.48963) (xy 64.662711 -426.48963) (xy 64.591837 -426.481644) (xy 64.522302 -426.465774)
			(xy 64.454982 -426.442217) (xy 64.390723 -426.411272) (xy 64.330332 -426.373326) (xy 64.27457 -426.328857)
			(xy 64.224137 -426.278424) (xy 64.179668 -426.222662) (xy 64.141722 -426.162271) (xy 64.110777 -426.098012)
			(xy 64.08722 -426.030692) (xy 64.07135 -425.961157) (xy 64.063364 -425.890283) (xy 40.758328 -425.890283)
			(xy 40.775672 -425.912032) (xy 40.813618 -425.972423) (xy 40.844563 -426.036682) (xy 40.86812 -426.104002)
			(xy 40.88399 -426.173537) (xy 40.891976 -426.244411) (xy 40.891976 -426.315733) (xy 40.88399 -426.386607)
			(xy 40.86812 -426.456142) (xy 40.844563 -426.523462) (xy 40.813618 -426.587721) (xy 40.775672 -426.648112)
			(xy 40.731203 -426.703874) (xy 40.68077 -426.754307) (xy 40.625008 -426.798776) (xy 40.564617 -426.836722)
			(xy 40.500358 -426.867667) (xy 40.433038 -426.891224) (xy 40.363503 -426.907094) (xy 40.292629 -426.91508)
			(xy 40.221307 -426.91508) (xy 40.150433 -426.907094) (xy 40.080898 -426.891224) (xy 40.013578 -426.867667)
			(xy 39.949319 -426.836722) (xy 39.888928 -426.798776) (xy 39.833166 -426.754307) (xy 39.782733 -426.703874)
			(xy 39.738264 -426.648112) (xy 39.700318 -426.587721) (xy 39.669373 -426.523462) (xy 39.645816 -426.456142)
			(xy 39.629946 -426.386607) (xy 39.62196 -426.315733) (xy 36.363334 -426.315733) (xy 36.400327 -426.390025)
			(xy 36.431719 -426.471057) (xy 36.4555 -426.554639) (xy 36.471468 -426.640059) (xy 36.479486 -426.726588)
			(xy 36.479486 -426.813488) (xy 36.471468 -426.900017) (xy 36.4555 -426.985437) (xy 36.431719 -427.069019)
			(xy 36.400327 -427.150051) (xy 36.361593 -427.22784) (xy 36.315846 -427.301724) (xy 36.263477 -427.371071)
			(xy 36.204933 -427.435291) (xy 36.140713 -427.493835) (xy 36.071366 -427.546204) (xy 35.997482 -427.591951)
			(xy 35.919693 -427.630685) (xy 35.838661 -427.662077) (xy 35.755079 -427.685858) (xy 35.669659 -427.701826)
			(xy 35.58313 -427.709844) (xy 35.49623 -427.709844) (xy 35.409701 -427.701826) (xy 35.324281 -427.685858)
			(xy 35.240699 -427.662077) (xy 35.159667 -427.630685) (xy 35.081878 -427.591951) (xy 35.007994 -427.546204)
			(xy 34.938647 -427.493835) (xy 34.874427 -427.435291) (xy 34.815883 -427.371071) (xy 34.763514 -427.301724)
			(xy 34.717767 -427.22784) (xy 34.679033 -427.150051) (xy 34.647641 -427.069019) (xy 34.62386 -426.985437)
			(xy 34.607892 -426.900017) (xy 34.599874 -426.813488) (xy 31.399486 -426.813488) (xy 31.391468 -426.900017)
			(xy 31.3755 -426.985437) (xy 31.351719 -427.069019) (xy 31.320327 -427.150051) (xy 31.281593 -427.22784)
			(xy 31.235846 -427.301724) (xy 31.183477 -427.371071) (xy 31.124933 -427.435291) (xy 31.060713 -427.493835)
			(xy 30.991366 -427.546204) (xy 30.917482 -427.591951) (xy 30.839693 -427.630685) (xy 30.758661 -427.662077)
			(xy 30.675079 -427.685858) (xy 30.589659 -427.701826) (xy 30.50313 -427.709844) (xy 30.41623 -427.709844)
			(xy 30.329701 -427.701826) (xy 30.244281 -427.685858) (xy 30.160699 -427.662077) (xy 30.079667 -427.630685)
			(xy 30.001878 -427.591951) (xy 29.927994 -427.546204) (xy 29.858647 -427.493835) (xy 29.794427 -427.435291)
			(xy 29.735883 -427.371071) (xy 29.683514 -427.301724) (xy 29.637767 -427.22784) (xy 29.599033 -427.150051)
			(xy 29.567641 -427.069019) (xy 29.54386 -426.985437) (xy 29.527892 -426.900017) (xy 29.519874 -426.813488)
			(xy 28.341828 -426.813488) (xy 28.341828 -429.353488) (xy 29.519874 -429.353488) (xy 29.519874 -429.266588)
			(xy 29.527892 -429.180059) (xy 29.54386 -429.094639) (xy 29.567641 -429.011057) (xy 29.599033 -428.930025)
			(xy 29.637767 -428.852236) (xy 29.683514 -428.778352) (xy 29.735883 -428.709005) (xy 29.794427 -428.644785)
			(xy 29.858647 -428.586241) (xy 29.927994 -428.533872) (xy 30.001878 -428.488125) (xy 30.079667 -428.449391)
			(xy 30.160699 -428.417999) (xy 30.244281 -428.394218) (xy 30.329701 -428.37825) (xy 30.41623 -428.370232)
			(xy 30.45968 -428.36973) (xy 30.50313 -428.370232) (xy 30.589659 -428.37825) (xy 30.675079 -428.394218)
			(xy 30.758661 -428.417999) (xy 30.839693 -428.449391) (xy 30.917482 -428.488125) (xy 30.991366 -428.533872)
			(xy 31.060713 -428.586241) (xy 31.124933 -428.644785) (xy 31.183477 -428.709005) (xy 31.235846 -428.778352)
			(xy 31.281593 -428.852236) (xy 31.320327 -428.930025) (xy 31.351719 -429.011057) (xy 31.3755 -429.094639)
			(xy 31.391468 -429.180059) (xy 31.399486 -429.266588) (xy 31.399486 -429.353488) (xy 34.599874 -429.353488)
			(xy 34.599874 -429.266588) (xy 34.607892 -429.180059) (xy 34.62386 -429.094639) (xy 34.647641 -429.011057)
			(xy 34.679033 -428.930025) (xy 34.717767 -428.852236) (xy 34.763514 -428.778352) (xy 34.815883 -428.709005)
			(xy 34.874427 -428.644785) (xy 34.938647 -428.586241) (xy 35.007994 -428.533872) (xy 35.081878 -428.488125)
			(xy 35.159667 -428.449391) (xy 35.240699 -428.417999) (xy 35.324281 -428.394218) (xy 35.409701 -428.37825)
			(xy 35.49623 -428.370232) (xy 35.53968 -428.36973) (xy 35.58313 -428.370232) (xy 35.669659 -428.37825)
			(xy 35.755079 -428.394218) (xy 35.838661 -428.417999) (xy 35.919693 -428.449391) (xy 35.997482 -428.488125)
			(xy 36.071366 -428.533872) (xy 36.140713 -428.586241) (xy 36.204933 -428.644785) (xy 36.243719 -428.687331)
			(xy 39.62196 -428.687331) (xy 39.62196 -428.616009) (xy 39.629946 -428.545135) (xy 39.645816 -428.4756)
			(xy 39.669373 -428.40828) (xy 39.700318 -428.344021) (xy 39.738264 -428.28363) (xy 39.782733 -428.227868)
			(xy 39.833166 -428.177435) (xy 39.888928 -428.132966) (xy 39.949319 -428.09502) (xy 40.013578 -428.064075)
			(xy 40.080898 -428.040518) (xy 40.150433 -428.024648) (xy 40.221307 -428.016662) (xy 40.256968 -428.016162)
			(xy 40.292629 -428.016662) (xy 40.363503 -428.024648) (xy 40.433038 -428.040518) (xy 40.500358 -428.064075)
			(xy 40.564617 -428.09502) (xy 40.625008 -428.132966) (xy 40.68077 -428.177435) (xy 40.731203 -428.227868)
			(xy 40.775672 -428.28363) (xy 40.813618 -428.344021) (xy 40.844563 -428.40828) (xy 40.86812 -428.4756)
			(xy 40.88399 -428.545135) (xy 40.885788 -428.561093) (xy 64.063364 -428.561093) (xy 64.063364 -428.489771)
			(xy 64.07135 -428.418897) (xy 64.08722 -428.349362) (xy 64.110777 -428.282042) (xy 64.141722 -428.217783)
			(xy 64.179668 -428.157392) (xy 64.224137 -428.10163) (xy 64.27457 -428.051197) (xy 64.330332 -428.006728)
			(xy 64.390723 -427.968782) (xy 64.454982 -427.937837) (xy 64.522302 -427.91428) (xy 64.591837 -427.89841)
			(xy 64.662711 -427.890424) (xy 64.698372 -427.889924) (xy 64.734033 -427.890424) (xy 64.804907 -427.89841)
			(xy 64.874442 -427.91428) (xy 64.941762 -427.937837) (xy 65.006021 -427.968782) (xy 65.066412 -428.006728)
			(xy 65.122174 -428.051197) (xy 65.172607 -428.10163) (xy 65.217076 -428.157392) (xy 65.255022 -428.217783)
			(xy 65.285967 -428.282042) (xy 65.309524 -428.349362) (xy 65.325394 -428.418897) (xy 65.33338 -428.489771)
			(xy 65.33338 -428.561093) (xy 66.867778 -428.561093) (xy 66.867778 -428.489771) (xy 66.875764 -428.418897)
			(xy 66.891634 -428.349362) (xy 66.915191 -428.282042) (xy 66.946136 -428.217783) (xy 66.984082 -428.157392)
			(xy 67.028551 -428.10163) (xy 67.078984 -428.051197) (xy 67.134746 -428.006728) (xy 67.195137 -427.968782)
			(xy 67.259396 -427.937837) (xy 67.326716 -427.91428) (xy 67.396251 -427.89841) (xy 67.467125 -427.890424)
			(xy 67.502786 -427.889924) (xy 67.538447 -427.890424) (xy 67.609321 -427.89841) (xy 67.678856 -427.91428)
			(xy 67.746176 -427.937837) (xy 67.810435 -427.968782) (xy 67.870826 -428.006728) (xy 67.926588 -428.051197)
			(xy 67.977021 -428.10163) (xy 68.02149 -428.157392) (xy 68.059436 -428.217783) (xy 68.090381 -428.282042)
			(xy 68.113938 -428.349362) (xy 68.129808 -428.418897) (xy 68.137794 -428.489771) (xy 68.137794 -428.561093)
			(xy 68.129808 -428.631967) (xy 68.113938 -428.701502) (xy 68.090381 -428.768822) (xy 68.059436 -428.833081)
			(xy 68.02149 -428.893472) (xy 67.977021 -428.949234) (xy 67.926588 -428.999667) (xy 67.870826 -429.044136)
			(xy 67.810435 -429.082082) (xy 67.746176 -429.113027) (xy 67.678856 -429.136584) (xy 67.609321 -429.152454)
			(xy 67.538447 -429.16044) (xy 67.467125 -429.16044) (xy 67.396251 -429.152454) (xy 67.326716 -429.136584)
			(xy 67.259396 -429.113027) (xy 67.195137 -429.082082) (xy 67.134746 -429.044136) (xy 67.078984 -428.999667)
			(xy 67.028551 -428.949234) (xy 66.984082 -428.893472) (xy 66.946136 -428.833081) (xy 66.915191 -428.768822)
			(xy 66.891634 -428.701502) (xy 66.875764 -428.631967) (xy 66.867778 -428.561093) (xy 65.33338 -428.561093)
			(xy 65.325394 -428.631967) (xy 65.309524 -428.701502) (xy 65.285967 -428.768822) (xy 65.255022 -428.833081)
			(xy 65.217076 -428.893472) (xy 65.172607 -428.949234) (xy 65.122174 -428.999667) (xy 65.066412 -429.044136)
			(xy 65.006021 -429.082082) (xy 64.941762 -429.113027) (xy 64.874442 -429.136584) (xy 64.804907 -429.152454)
			(xy 64.734033 -429.16044) (xy 64.662711 -429.16044) (xy 64.591837 -429.152454) (xy 64.522302 -429.136584)
			(xy 64.454982 -429.113027) (xy 64.390723 -429.082082) (xy 64.330332 -429.044136) (xy 64.27457 -428.999667)
			(xy 64.224137 -428.949234) (xy 64.179668 -428.893472) (xy 64.141722 -428.833081) (xy 64.110777 -428.768822)
			(xy 64.08722 -428.701502) (xy 64.07135 -428.631967) (xy 64.063364 -428.561093) (xy 40.885788 -428.561093)
			(xy 40.891976 -428.616009) (xy 40.891976 -428.687331) (xy 40.88399 -428.758205) (xy 40.86812 -428.82774)
			(xy 40.844563 -428.89506) (xy 40.813618 -428.959319) (xy 40.775672 -429.01971) (xy 40.731203 -429.075472)
			(xy 40.68077 -429.125905) (xy 40.625008 -429.170374) (xy 40.564617 -429.20832) (xy 40.500358 -429.239265)
			(xy 40.433038 -429.262822) (xy 40.363503 -429.278692) (xy 40.292629 -429.286678) (xy 40.221307 -429.286678)
			(xy 40.150433 -429.278692) (xy 40.080898 -429.262822) (xy 40.013578 -429.239265) (xy 39.949319 -429.20832)
			(xy 39.888928 -429.170374) (xy 39.833166 -429.125905) (xy 39.782733 -429.075472) (xy 39.738264 -429.01971)
			(xy 39.700318 -428.959319) (xy 39.669373 -428.89506) (xy 39.645816 -428.82774) (xy 39.629946 -428.758205)
			(xy 39.62196 -428.687331) (xy 36.243719 -428.687331) (xy 36.263477 -428.709005) (xy 36.315846 -428.778352)
			(xy 36.361593 -428.852236) (xy 36.400327 -428.930025) (xy 36.431719 -429.011057) (xy 36.4555 -429.094639)
			(xy 36.471468 -429.180059) (xy 36.479486 -429.266588) (xy 36.479486 -429.353488) (xy 36.471468 -429.440017)
			(xy 36.4555 -429.525437) (xy 36.431719 -429.609019) (xy 36.400327 -429.690051) (xy 36.361593 -429.76784)
			(xy 36.315846 -429.841724) (xy 36.263477 -429.911071) (xy 36.204933 -429.975291) (xy 36.140713 -430.033835)
			(xy 36.071366 -430.086204) (xy 35.997482 -430.131951) (xy 35.919693 -430.170685) (xy 35.838661 -430.202077)
			(xy 35.755079 -430.225858) (xy 35.669659 -430.241826) (xy 35.58313 -430.249844) (xy 35.49623 -430.249844)
			(xy 35.409701 -430.241826) (xy 35.324281 -430.225858) (xy 35.240699 -430.202077) (xy 35.159667 -430.170685)
			(xy 35.081878 -430.131951) (xy 35.007994 -430.086204) (xy 34.938647 -430.033835) (xy 34.874427 -429.975291)
			(xy 34.815883 -429.911071) (xy 34.763514 -429.841724) (xy 34.717767 -429.76784) (xy 34.679033 -429.690051)
			(xy 34.647641 -429.609019) (xy 34.62386 -429.525437) (xy 34.607892 -429.440017) (xy 34.599874 -429.353488)
			(xy 31.399486 -429.353488) (xy 31.391468 -429.440017) (xy 31.3755 -429.525437) (xy 31.351719 -429.609019)
			(xy 31.320327 -429.690051) (xy 31.281593 -429.76784) (xy 31.235846 -429.841724) (xy 31.183477 -429.911071)
			(xy 31.124933 -429.975291) (xy 31.060713 -430.033835) (xy 30.991366 -430.086204) (xy 30.917482 -430.131951)
			(xy 30.839693 -430.170685) (xy 30.758661 -430.202077) (xy 30.675079 -430.225858) (xy 30.589659 -430.241826)
			(xy 30.50313 -430.249844) (xy 30.41623 -430.249844) (xy 30.329701 -430.241826) (xy 30.244281 -430.225858)
			(xy 30.160699 -430.202077) (xy 30.079667 -430.170685) (xy 30.001878 -430.131951) (xy 29.927994 -430.086204)
			(xy 29.858647 -430.033835) (xy 29.794427 -429.975291) (xy 29.735883 -429.911071) (xy 29.683514 -429.841724)
			(xy 29.637767 -429.76784) (xy 29.599033 -429.690051) (xy 29.567641 -429.609019) (xy 29.54386 -429.525437)
			(xy 29.527892 -429.440017) (xy 29.519874 -429.353488) (xy 28.341828 -429.353488) (xy 28.341828 -430.650243)
			(xy 39.62196 -430.650243) (xy 39.62196 -430.578921) (xy 39.629946 -430.508047) (xy 39.645816 -430.438512)
			(xy 39.669373 -430.371192) (xy 39.700318 -430.306933) (xy 39.738264 -430.246542) (xy 39.782733 -430.19078)
			(xy 39.833166 -430.140347) (xy 39.888928 -430.095878) (xy 39.949319 -430.057932) (xy 40.013578 -430.026987)
			(xy 40.080898 -430.00343) (xy 40.150433 -429.98756) (xy 40.221307 -429.979574) (xy 40.256968 -429.979074)
			(xy 40.292629 -429.979574) (xy 40.363503 -429.98756) (xy 40.433038 -430.00343) (xy 40.500358 -430.026987)
			(xy 40.564617 -430.057932) (xy 40.625008 -430.095878) (xy 40.68077 -430.140347) (xy 40.731203 -430.19078)
			(xy 40.738598 -430.200053) (xy 72.999096 -430.200053) (xy 73.001098 -429.999925) (xy 73.011106 -429.800037)
			(xy 73.029103 -429.60071) (xy 73.055061 -429.402262) (xy 73.088938 -429.205012) (xy 73.13068 -429.009275)
			(xy 73.180219 -428.815365) (xy 73.237477 -428.623592) (xy 73.302362 -428.434263) (xy 73.37477 -428.247683)
			(xy 73.454586 -428.064148) (xy 73.54168 -427.883954) (xy 73.635914 -427.707389) (xy 73.737137 -427.534736)
			(xy 73.845187 -427.366271) (xy 73.95989 -427.202263) (xy 74.081064 -427.042976) (xy 74.208513 -426.888665)
			(xy 74.342034 -426.739577) (xy 74.481414 -426.59595) (xy 74.626428 -426.458014) (xy 74.776845 -426.325991)
			(xy 74.932423 -426.200092) (xy 75.092915 -426.080518) (xy 75.258061 -425.967462) (xy 75.427599 -425.861103)
			(xy 75.601257 -425.761612) (xy 75.778756 -425.669149) (xy 75.959812 -425.583862) (xy 76.144136 -425.505887)
			(xy 76.331432 -425.43535) (xy 76.5214 -425.372362) (xy 76.713736 -425.317025) (xy 76.908132 -425.269428)
			(xy 77.104277 -425.229647) (xy 77.301856 -425.197745) (xy 77.500553 -425.173774) (xy 77.700051 -425.157772)
			(xy 77.900029 -425.149765) (xy 78.000098 -425.149264) (xy 78.100167 -425.149765) (xy 78.300145 -425.157772)
			(xy 78.499643 -425.173774) (xy 78.69834 -425.197745) (xy 78.895919 -425.229647) (xy 79.092064 -425.269428)
			(xy 79.28646 -425.317025) (xy 79.478796 -425.372362) (xy 79.668764 -425.43535) (xy 79.85606 -425.505887)
			(xy 80.040384 -425.583862) (xy 80.22144 -425.669149) (xy 80.398939 -425.761612) (xy 80.572597 -425.861103)
			(xy 80.742135 -425.967462) (xy 80.907281 -426.080518) (xy 81.067773 -426.200092) (xy 81.223351 -426.325991)
			(xy 81.373768 -426.458014) (xy 81.518782 -426.59595) (xy 81.658162 -426.739577) (xy 81.791683 -426.888665)
			(xy 81.919132 -427.042976) (xy 82.040306 -427.202263) (xy 82.155009 -427.366271) (xy 82.263059 -427.534736)
			(xy 82.364282 -427.707389) (xy 82.458516 -427.883954) (xy 82.54561 -428.064148) (xy 82.625426 -428.247683)
			(xy 82.697834 -428.434263) (xy 82.762719 -428.623592) (xy 82.819977 -428.815365) (xy 82.869516 -429.009275)
			(xy 82.911258 -429.205012) (xy 82.945135 -429.402262) (xy 82.971093 -429.60071) (xy 82.98909 -429.800037)
			(xy 82.999098 -429.999925) (xy 83.0011 -430.200053) (xy 82.995094 -430.400101) (xy 82.981089 -430.599749)
			(xy 82.959107 -430.798676) (xy 82.929183 -430.996565) (xy 82.891366 -431.193098) (xy 82.845717 -431.38796)
			(xy 82.792307 -431.58084) (xy 82.731223 -431.771429) (xy 82.662563 -431.959421) (xy 82.586436 -432.144516)
			(xy 82.502965 -432.326416) (xy 82.412282 -432.504832) (xy 82.314534 -432.679476) (xy 82.209877 -432.850069)
			(xy 82.098478 -433.016339) (xy 81.980516 -433.178018) (xy 81.85618 -433.334849) (xy 81.725668 -433.486579)
			(xy 81.589191 -433.632966) (xy 81.446965 -433.773775) (xy 81.29922 -433.908782) (xy 81.146192 -434.037769)
			(xy 80.988125 -434.16053) (xy 80.825274 -434.276868) (xy 80.657898 -434.386598) (xy 80.486266 -434.489543)
			(xy 80.310652 -434.585539) (xy 80.131339 -434.674432) (xy 79.948612 -434.756079) (xy 79.762765 -434.830351)
			(xy 79.574095 -434.897127) (xy 79.382905 -434.956301) (xy 79.1895 -435.007778) (xy 78.994191 -435.051476)
			(xy 78.797289 -435.087324) (xy 78.599111 -435.115266) (xy 78.399974 -435.135257) (xy 78.200196 -435.147264)
			(xy 78.000098 -435.151269) (xy 77.8 -435.147264) (xy 77.600222 -435.135257) (xy 77.401085 -435.115266)
			(xy 77.202907 -435.087324) (xy 77.006005 -435.051476) (xy 76.810696 -435.007778) (xy 76.617291 -434.956301)
			(xy 76.426101 -434.897127) (xy 76.237431 -434.830351) (xy 76.051584 -434.756079) (xy 75.868857 -434.674432)
			(xy 75.689544 -434.585539) (xy 75.51393 -434.489543) (xy 75.342298 -434.386598) (xy 75.174922 -434.276868)
			(xy 75.012071 -434.16053) (xy 74.854004 -434.037769) (xy 74.700976 -433.908782) (xy 74.553231 -433.773775)
			(xy 74.411005 -433.632966) (xy 74.274528 -433.486579) (xy 74.144016 -433.334849) (xy 74.01968 -433.178018)
			(xy 73.901718 -433.016339) (xy 73.790319 -432.850069) (xy 73.685662 -432.679476) (xy 73.587914 -432.504832)
			(xy 73.497231 -432.326416) (xy 73.41376 -432.144516) (xy 73.337633 -431.959421) (xy 73.268973 -431.771429)
			(xy 73.207889 -431.58084) (xy 73.154479 -431.38796) (xy 73.10883 -431.193098) (xy 73.071013 -430.996565)
			(xy 73.041089 -430.798676) (xy 73.019107 -430.599749) (xy 73.005102 -430.400101) (xy 72.999096 -430.200053)
			(xy 40.738598 -430.200053) (xy 40.775672 -430.246542) (xy 40.813618 -430.306933) (xy 40.844563 -430.371192)
			(xy 40.86812 -430.438512) (xy 40.88399 -430.508047) (xy 40.891976 -430.578921) (xy 40.891976 -430.650243)
			(xy 40.88399 -430.721117) (xy 40.86812 -430.790652) (xy 40.844563 -430.857972) (xy 40.813618 -430.922231)
			(xy 40.775672 -430.982622) (xy 40.731203 -431.038384) (xy 40.68077 -431.088817) (xy 40.625008 -431.133286)
			(xy 40.564617 -431.171232) (xy 40.500358 -431.202177) (xy 40.433038 -431.225734) (xy 40.417137 -431.229363)
			(xy 64.063364 -431.229363) (xy 64.063364 -431.158041) (xy 64.07135 -431.087167) (xy 64.08722 -431.017632)
			(xy 64.110777 -430.950312) (xy 64.141722 -430.886053) (xy 64.179668 -430.825662) (xy 64.224137 -430.7699)
			(xy 64.27457 -430.719467) (xy 64.330332 -430.674998) (xy 64.390723 -430.637052) (xy 64.454982 -430.606107)
			(xy 64.522302 -430.58255) (xy 64.591837 -430.56668) (xy 64.662711 -430.558694) (xy 64.698372 -430.558194)
			(xy 64.734033 -430.558694) (xy 64.804907 -430.56668) (xy 64.874442 -430.58255) (xy 64.941762 -430.606107)
			(xy 65.006021 -430.637052) (xy 65.066412 -430.674998) (xy 65.122174 -430.719467) (xy 65.172607 -430.7699)
			(xy 65.217076 -430.825662) (xy 65.255022 -430.886053) (xy 65.285967 -430.950312) (xy 65.309524 -431.017632)
			(xy 65.325394 -431.087167) (xy 65.33338 -431.158041) (xy 65.33338 -431.229363) (xy 66.867778 -431.229363)
			(xy 66.867778 -431.158041) (xy 66.875764 -431.087167) (xy 66.891634 -431.017632) (xy 66.915191 -430.950312)
			(xy 66.946136 -430.886053) (xy 66.984082 -430.825662) (xy 67.028551 -430.7699) (xy 67.078984 -430.719467)
			(xy 67.134746 -430.674998) (xy 67.195137 -430.637052) (xy 67.259396 -430.606107) (xy 67.326716 -430.58255)
			(xy 67.396251 -430.56668) (xy 67.467125 -430.558694) (xy 67.502786 -430.558194) (xy 67.538447 -430.558694)
			(xy 67.609321 -430.56668) (xy 67.678856 -430.58255) (xy 67.746176 -430.606107) (xy 67.810435 -430.637052)
			(xy 67.870826 -430.674998) (xy 67.926588 -430.719467) (xy 67.977021 -430.7699) (xy 68.02149 -430.825662)
			(xy 68.059436 -430.886053) (xy 68.090381 -430.950312) (xy 68.113938 -431.017632) (xy 68.129808 -431.087167)
			(xy 68.137794 -431.158041) (xy 68.137794 -431.229363) (xy 68.129808 -431.300237) (xy 68.113938 -431.369772)
			(xy 68.090381 -431.437092) (xy 68.059436 -431.501351) (xy 68.02149 -431.561742) (xy 67.977021 -431.617504)
			(xy 67.926588 -431.667937) (xy 67.870826 -431.712406) (xy 67.810435 -431.750352) (xy 67.746176 -431.781297)
			(xy 67.678856 -431.804854) (xy 67.609321 -431.820724) (xy 67.538447 -431.82871) (xy 67.467125 -431.82871)
			(xy 67.396251 -431.820724) (xy 67.326716 -431.804854) (xy 67.259396 -431.781297) (xy 67.195137 -431.750352)
			(xy 67.134746 -431.712406) (xy 67.078984 -431.667937) (xy 67.028551 -431.617504) (xy 66.984082 -431.561742)
			(xy 66.946136 -431.501351) (xy 66.915191 -431.437092) (xy 66.891634 -431.369772) (xy 66.875764 -431.300237)
			(xy 66.867778 -431.229363) (xy 65.33338 -431.229363) (xy 65.325394 -431.300237) (xy 65.309524 -431.369772)
			(xy 65.285967 -431.437092) (xy 65.255022 -431.501351) (xy 65.217076 -431.561742) (xy 65.172607 -431.617504)
			(xy 65.122174 -431.667937) (xy 65.066412 -431.712406) (xy 65.006021 -431.750352) (xy 64.941762 -431.781297)
			(xy 64.874442 -431.804854) (xy 64.804907 -431.820724) (xy 64.734033 -431.82871) (xy 64.662711 -431.82871)
			(xy 64.591837 -431.820724) (xy 64.522302 -431.804854) (xy 64.454982 -431.781297) (xy 64.390723 -431.750352)
			(xy 64.330332 -431.712406) (xy 64.27457 -431.667937) (xy 64.224137 -431.617504) (xy 64.179668 -431.561742)
			(xy 64.141722 -431.501351) (xy 64.110777 -431.437092) (xy 64.08722 -431.369772) (xy 64.07135 -431.300237)
			(xy 64.063364 -431.229363) (xy 40.417137 -431.229363) (xy 40.363503 -431.241604) (xy 40.292629 -431.24959)
			(xy 40.221307 -431.24959) (xy 40.150433 -431.241604) (xy 40.080898 -431.225734) (xy 40.013578 -431.202177)
			(xy 39.949319 -431.171232) (xy 39.888928 -431.133286) (xy 39.833166 -431.088817) (xy 39.782733 -431.038384)
			(xy 39.738264 -430.982622) (xy 39.700318 -430.922231) (xy 39.669373 -430.857972) (xy 39.645816 -430.790652)
			(xy 39.629946 -430.721117) (xy 39.62196 -430.650243) (xy 28.341828 -430.650243) (xy 28.341828 -431.893488)
			(xy 29.519874 -431.893488) (xy 29.519874 -431.806588) (xy 29.527892 -431.720059) (xy 29.54386 -431.634639)
			(xy 29.567641 -431.551057) (xy 29.599033 -431.470025) (xy 29.637767 -431.392236) (xy 29.683514 -431.318352)
			(xy 29.735883 -431.249005) (xy 29.794427 -431.184785) (xy 29.858647 -431.126241) (xy 29.927994 -431.073872)
			(xy 30.001878 -431.028125) (xy 30.079667 -430.989391) (xy 30.160699 -430.957999) (xy 30.244281 -430.934218)
			(xy 30.329701 -430.91825) (xy 30.41623 -430.910232) (xy 30.45968 -430.90973) (xy 30.50313 -430.910232)
			(xy 30.589659 -430.91825) (xy 30.675079 -430.934218) (xy 30.758661 -430.957999) (xy 30.839693 -430.989391)
			(xy 30.917482 -431.028125) (xy 30.991366 -431.073872) (xy 31.060713 -431.126241) (xy 31.124933 -431.184785)
			(xy 31.183477 -431.249005) (xy 31.235846 -431.318352) (xy 31.281593 -431.392236) (xy 31.320327 -431.470025)
			(xy 31.351719 -431.551057) (xy 31.3755 -431.634639) (xy 31.391468 -431.720059) (xy 31.399486 -431.806588)
			(xy 31.399486 -431.893488) (xy 34.599874 -431.893488) (xy 34.599874 -431.806588) (xy 34.607892 -431.720059)
			(xy 34.62386 -431.634639) (xy 34.647641 -431.551057) (xy 34.679033 -431.470025) (xy 34.717767 -431.392236)
			(xy 34.763514 -431.318352) (xy 34.815883 -431.249005) (xy 34.874427 -431.184785) (xy 34.938647 -431.126241)
			(xy 35.007994 -431.073872) (xy 35.081878 -431.028125) (xy 35.159667 -430.989391) (xy 35.240699 -430.957999)
			(xy 35.324281 -430.934218) (xy 35.409701 -430.91825) (xy 35.49623 -430.910232) (xy 35.53968 -430.90973)
			(xy 35.58313 -430.910232) (xy 35.669659 -430.91825) (xy 35.755079 -430.934218) (xy 35.838661 -430.957999)
			(xy 35.919693 -430.989391) (xy 35.997482 -431.028125) (xy 36.071366 -431.073872) (xy 36.140713 -431.126241)
			(xy 36.204933 -431.184785) (xy 36.263477 -431.249005) (xy 36.315846 -431.318352) (xy 36.361593 -431.392236)
			(xy 36.400327 -431.470025) (xy 36.431719 -431.551057) (xy 36.4555 -431.634639) (xy 36.471468 -431.720059)
			(xy 36.479486 -431.806588) (xy 36.479486 -431.893488) (xy 36.471468 -431.980017) (xy 36.4555 -432.065437)
			(xy 36.431719 -432.149019) (xy 36.400327 -432.230051) (xy 36.361593 -432.30784) (xy 36.315846 -432.381724)
			(xy 36.263477 -432.451071) (xy 36.204933 -432.515291) (xy 36.140713 -432.573835) (xy 36.071366 -432.626204)
			(xy 35.997482 -432.671951) (xy 35.919693 -432.710685) (xy 35.838661 -432.742077) (xy 35.755079 -432.765858)
			(xy 35.669659 -432.781826) (xy 35.58313 -432.789844) (xy 35.49623 -432.789844) (xy 35.409701 -432.781826)
			(xy 35.324281 -432.765858) (xy 35.240699 -432.742077) (xy 35.159667 -432.710685) (xy 35.081878 -432.671951)
			(xy 35.007994 -432.626204) (xy 34.938647 -432.573835) (xy 34.874427 -432.515291) (xy 34.815883 -432.451071)
			(xy 34.763514 -432.381724) (xy 34.717767 -432.30784) (xy 34.679033 -432.230051) (xy 34.647641 -432.149019)
			(xy 34.62386 -432.065437) (xy 34.607892 -431.980017) (xy 34.599874 -431.893488) (xy 31.399486 -431.893488)
			(xy 31.391468 -431.980017) (xy 31.3755 -432.065437) (xy 31.351719 -432.149019) (xy 31.320327 -432.230051)
			(xy 31.281593 -432.30784) (xy 31.235846 -432.381724) (xy 31.183477 -432.451071) (xy 31.124933 -432.515291)
			(xy 31.060713 -432.573835) (xy 30.991366 -432.626204) (xy 30.917482 -432.671951) (xy 30.839693 -432.710685)
			(xy 30.758661 -432.742077) (xy 30.675079 -432.765858) (xy 30.589659 -432.781826) (xy 30.50313 -432.789844)
			(xy 30.41623 -432.789844) (xy 30.329701 -432.781826) (xy 30.244281 -432.765858) (xy 30.160699 -432.742077)
			(xy 30.079667 -432.710685) (xy 30.001878 -432.671951) (xy 29.927994 -432.626204) (xy 29.858647 -432.573835)
			(xy 29.794427 -432.515291) (xy 29.735883 -432.451071) (xy 29.683514 -432.381724) (xy 29.637767 -432.30784)
			(xy 29.599033 -432.230051) (xy 29.567641 -432.149019) (xy 29.54386 -432.065437) (xy 29.527892 -431.980017)
			(xy 29.519874 -431.893488) (xy 28.341828 -431.893488) (xy 28.341828 -432.793749) (xy 39.62196 -432.793749)
			(xy 39.62196 -432.722427) (xy 39.629946 -432.651553) (xy 39.645816 -432.582018) (xy 39.669373 -432.514698)
			(xy 39.700318 -432.450439) (xy 39.738264 -432.390048) (xy 39.782733 -432.334286) (xy 39.833166 -432.283853)
			(xy 39.888928 -432.239384) (xy 39.949319 -432.201438) (xy 40.013578 -432.170493) (xy 40.080898 -432.146936)
			(xy 40.150433 -432.131066) (xy 40.221307 -432.12308) (xy 40.256968 -432.12258) (xy 40.292629 -432.12308)
			(xy 40.363503 -432.131066) (xy 40.433038 -432.146936) (xy 40.500358 -432.170493) (xy 40.564617 -432.201438)
			(xy 40.625008 -432.239384) (xy 40.68077 -432.283853) (xy 40.731203 -432.334286) (xy 40.775672 -432.390048)
			(xy 40.813618 -432.450439) (xy 40.844563 -432.514698) (xy 40.86812 -432.582018) (xy 40.88399 -432.651553)
			(xy 40.891976 -432.722427) (xy 40.891976 -432.793749) (xy 40.88399 -432.864623) (xy 40.86812 -432.934158)
			(xy 40.844563 -433.001478) (xy 40.813618 -433.065737) (xy 40.775672 -433.126128) (xy 40.731203 -433.18189)
			(xy 40.68077 -433.232323) (xy 40.625008 -433.276792) (xy 40.564617 -433.314738) (xy 40.500358 -433.345683)
			(xy 40.433038 -433.36924) (xy 40.363503 -433.38511) (xy 40.292629 -433.393096) (xy 40.221307 -433.393096)
			(xy 40.150433 -433.38511) (xy 40.080898 -433.36924) (xy 40.013578 -433.345683) (xy 39.949319 -433.314738)
			(xy 39.888928 -433.276792) (xy 39.833166 -433.232323) (xy 39.782733 -433.18189) (xy 39.738264 -433.126128)
			(xy 39.700318 -433.065737) (xy 39.669373 -433.001478) (xy 39.645816 -432.934158) (xy 39.629946 -432.864623)
			(xy 39.62196 -432.793749) (xy 28.341828 -432.793749) (xy 28.341828 -434.433488) (xy 29.519874 -434.433488)
			(xy 29.519874 -434.346588) (xy 29.527892 -434.260059) (xy 29.54386 -434.174639) (xy 29.567641 -434.091057)
			(xy 29.599033 -434.010025) (xy 29.637767 -433.932236) (xy 29.683514 -433.858352) (xy 29.735883 -433.789005)
			(xy 29.794427 -433.724785) (xy 29.858647 -433.666241) (xy 29.927994 -433.613872) (xy 30.001878 -433.568125)
			(xy 30.079667 -433.529391) (xy 30.160699 -433.497999) (xy 30.244281 -433.474218) (xy 30.329701 -433.45825)
			(xy 30.41623 -433.450232) (xy 30.45968 -433.44973) (xy 30.50313 -433.450232) (xy 30.589659 -433.45825)
			(xy 30.675079 -433.474218) (xy 30.758661 -433.497999) (xy 30.839693 -433.529391) (xy 30.917482 -433.568125)
			(xy 30.991366 -433.613872) (xy 31.060713 -433.666241) (xy 31.124933 -433.724785) (xy 31.183477 -433.789005)
			(xy 31.235846 -433.858352) (xy 31.281593 -433.932236) (xy 31.320327 -434.010025) (xy 31.351719 -434.091057)
			(xy 31.3755 -434.174639) (xy 31.391468 -434.260059) (xy 31.399486 -434.346588) (xy 31.399486 -434.433488)
			(xy 34.599874 -434.433488) (xy 34.599874 -434.346588) (xy 34.607892 -434.260059) (xy 34.62386 -434.174639)
			(xy 34.647641 -434.091057) (xy 34.679033 -434.010025) (xy 34.717767 -433.932236) (xy 34.763514 -433.858352)
			(xy 34.815883 -433.789005) (xy 34.874427 -433.724785) (xy 34.938647 -433.666241) (xy 35.007994 -433.613872)
			(xy 35.081878 -433.568125) (xy 35.159667 -433.529391) (xy 35.240699 -433.497999) (xy 35.324281 -433.474218)
			(xy 35.409701 -433.45825) (xy 35.49623 -433.450232) (xy 35.53968 -433.44973) (xy 35.58313 -433.450232)
			(xy 35.669659 -433.45825) (xy 35.755079 -433.474218) (xy 35.838661 -433.497999) (xy 35.919693 -433.529391)
			(xy 35.997482 -433.568125) (xy 36.050514 -433.600961) (xy 64.063364 -433.600961) (xy 64.063364 -433.529639)
			(xy 64.07135 -433.458765) (xy 64.08722 -433.38923) (xy 64.110777 -433.32191) (xy 64.141722 -433.257651)
			(xy 64.179668 -433.19726) (xy 64.224137 -433.141498) (xy 64.27457 -433.091065) (xy 64.330332 -433.046596)
			(xy 64.390723 -433.00865) (xy 64.454982 -432.977705) (xy 64.522302 -432.954148) (xy 64.591837 -432.938278)
			(xy 64.662711 -432.930292) (xy 64.698372 -432.929792) (xy 64.734033 -432.930292) (xy 64.804907 -432.938278)
			(xy 64.874442 -432.954148) (xy 64.941762 -432.977705) (xy 65.006021 -433.00865) (xy 65.066412 -433.046596)
			(xy 65.122174 -433.091065) (xy 65.172607 -433.141498) (xy 65.217076 -433.19726) (xy 65.255022 -433.257651)
			(xy 65.285967 -433.32191) (xy 65.309524 -433.38923) (xy 65.325394 -433.458765) (xy 65.33338 -433.529639)
			(xy 65.33338 -433.600961) (xy 66.867778 -433.600961) (xy 66.867778 -433.529639) (xy 66.875764 -433.458765)
			(xy 66.891634 -433.38923) (xy 66.915191 -433.32191) (xy 66.946136 -433.257651) (xy 66.984082 -433.19726)
			(xy 67.028551 -433.141498) (xy 67.078984 -433.091065) (xy 67.134746 -433.046596) (xy 67.195137 -433.00865)
			(xy 67.259396 -432.977705) (xy 67.326716 -432.954148) (xy 67.396251 -432.938278) (xy 67.467125 -432.930292)
			(xy 67.502786 -432.929792) (xy 67.538447 -432.930292) (xy 67.609321 -432.938278) (xy 67.678856 -432.954148)
			(xy 67.746176 -432.977705) (xy 67.810435 -433.00865) (xy 67.870826 -433.046596) (xy 67.926588 -433.091065)
			(xy 67.977021 -433.141498) (xy 68.02149 -433.19726) (xy 68.059436 -433.257651) (xy 68.090381 -433.32191)
			(xy 68.113938 -433.38923) (xy 68.129808 -433.458765) (xy 68.137794 -433.529639) (xy 68.137794 -433.600961)
			(xy 68.129808 -433.671835) (xy 68.113938 -433.74137) (xy 68.090381 -433.80869) (xy 68.059436 -433.872949)
			(xy 68.02149 -433.93334) (xy 67.977021 -433.989102) (xy 67.926588 -434.039535) (xy 67.870826 -434.084004)
			(xy 67.810435 -434.12195) (xy 67.746176 -434.152895) (xy 67.678856 -434.176452) (xy 67.609321 -434.192322)
			(xy 67.538447 -434.200308) (xy 67.467125 -434.200308) (xy 67.396251 -434.192322) (xy 67.326716 -434.176452)
			(xy 67.259396 -434.152895) (xy 67.195137 -434.12195) (xy 67.134746 -434.084004) (xy 67.078984 -434.039535)
			(xy 67.028551 -433.989102) (xy 66.984082 -433.93334) (xy 66.946136 -433.872949) (xy 66.915191 -433.80869)
			(xy 66.891634 -433.74137) (xy 66.875764 -433.671835) (xy 66.867778 -433.600961) (xy 65.33338 -433.600961)
			(xy 65.325394 -433.671835) (xy 65.309524 -433.74137) (xy 65.285967 -433.80869) (xy 65.255022 -433.872949)
			(xy 65.217076 -433.93334) (xy 65.172607 -433.989102) (xy 65.122174 -434.039535) (xy 65.066412 -434.084004)
			(xy 65.006021 -434.12195) (xy 64.941762 -434.152895) (xy 64.874442 -434.176452) (xy 64.804907 -434.192322)
			(xy 64.734033 -434.200308) (xy 64.662711 -434.200308) (xy 64.591837 -434.192322) (xy 64.522302 -434.176452)
			(xy 64.454982 -434.152895) (xy 64.390723 -434.12195) (xy 64.330332 -434.084004) (xy 64.27457 -434.039535)
			(xy 64.224137 -433.989102) (xy 64.179668 -433.93334) (xy 64.141722 -433.872949) (xy 64.110777 -433.80869)
			(xy 64.08722 -433.74137) (xy 64.07135 -433.671835) (xy 64.063364 -433.600961) (xy 36.050514 -433.600961)
			(xy 36.071366 -433.613872) (xy 36.140713 -433.666241) (xy 36.204933 -433.724785) (xy 36.263477 -433.789005)
			(xy 36.315846 -433.858352) (xy 36.361593 -433.932236) (xy 36.400327 -434.010025) (xy 36.431719 -434.091057)
			(xy 36.4555 -434.174639) (xy 36.471468 -434.260059) (xy 36.479486 -434.346588) (xy 36.479486 -434.433488)
			(xy 36.471468 -434.520017) (xy 36.4555 -434.605437) (xy 36.431719 -434.689019) (xy 36.400327 -434.770051)
			(xy 36.361593 -434.84784) (xy 36.315846 -434.921724) (xy 36.263477 -434.991071) (xy 36.204933 -435.055291)
			(xy 36.140713 -435.113835) (xy 36.071366 -435.166204) (xy 35.997482 -435.211951) (xy 35.919693 -435.250685)
			(xy 35.838661 -435.282077) (xy 35.755079 -435.305858) (xy 35.669659 -435.321826) (xy 35.58313 -435.329844)
			(xy 35.49623 -435.329844) (xy 35.409701 -435.321826) (xy 35.324281 -435.305858) (xy 35.240699 -435.282077)
			(xy 35.159667 -435.250685) (xy 35.081878 -435.211951) (xy 35.007994 -435.166204) (xy 34.938647 -435.113835)
			(xy 34.874427 -435.055291) (xy 34.815883 -434.991071) (xy 34.763514 -434.921724) (xy 34.717767 -434.84784)
			(xy 34.679033 -434.770051) (xy 34.647641 -434.689019) (xy 34.62386 -434.605437) (xy 34.607892 -434.520017)
			(xy 34.599874 -434.433488) (xy 31.399486 -434.433488) (xy 31.391468 -434.520017) (xy 31.3755 -434.605437)
			(xy 31.351719 -434.689019) (xy 31.320327 -434.770051) (xy 31.281593 -434.84784) (xy 31.235846 -434.921724)
			(xy 31.183477 -434.991071) (xy 31.124933 -435.055291) (xy 31.060713 -435.113835) (xy 30.991366 -435.166204)
			(xy 30.917482 -435.211951) (xy 30.839693 -435.250685) (xy 30.758661 -435.282077) (xy 30.675079 -435.305858)
			(xy 30.589659 -435.321826) (xy 30.50313 -435.329844) (xy 30.41623 -435.329844) (xy 30.329701 -435.321826)
			(xy 30.244281 -435.305858) (xy 30.160699 -435.282077) (xy 30.079667 -435.250685) (xy 30.001878 -435.211951)
			(xy 29.927994 -435.166204) (xy 29.858647 -435.113835) (xy 29.794427 -435.055291) (xy 29.735883 -434.991071)
			(xy 29.683514 -434.921724) (xy 29.637767 -434.84784) (xy 29.599033 -434.770051) (xy 29.567641 -434.689019)
			(xy 29.54386 -434.605437) (xy 29.527892 -434.520017) (xy 29.519874 -434.433488) (xy 28.341828 -434.433488)
			(xy 28.341828 -435.563873) (xy 64.063364 -435.563873) (xy 64.063364 -435.492551) (xy 64.07135 -435.421677)
			(xy 64.08722 -435.352142) (xy 64.110777 -435.284822) (xy 64.141722 -435.220563) (xy 64.179668 -435.160172)
			(xy 64.224137 -435.10441) (xy 64.27457 -435.053977) (xy 64.330332 -435.009508) (xy 64.390723 -434.971562)
			(xy 64.454982 -434.940617) (xy 64.522302 -434.91706) (xy 64.591837 -434.90119) (xy 64.662711 -434.893204)
			(xy 64.698372 -434.892704) (xy 64.734033 -434.893204) (xy 64.804907 -434.90119) (xy 64.874442 -434.91706)
			(xy 64.941762 -434.940617) (xy 65.006021 -434.971562) (xy 65.066412 -435.009508) (xy 65.122174 -435.053977)
			(xy 65.172607 -435.10441) (xy 65.217076 -435.160172) (xy 65.255022 -435.220563) (xy 65.285967 -435.284822)
			(xy 65.309524 -435.352142) (xy 65.325394 -435.421677) (xy 65.33338 -435.492551) (xy 65.33338 -435.563873)
			(xy 66.867778 -435.563873) (xy 66.867778 -435.492551) (xy 66.875764 -435.421677) (xy 66.891634 -435.352142)
			(xy 66.915191 -435.284822) (xy 66.946136 -435.220563) (xy 66.984082 -435.160172) (xy 67.028551 -435.10441)
			(xy 67.078984 -435.053977) (xy 67.134746 -435.009508) (xy 67.195137 -434.971562) (xy 67.259396 -434.940617)
			(xy 67.326716 -434.91706) (xy 67.396251 -434.90119) (xy 67.467125 -434.893204) (xy 67.502786 -434.892704)
			(xy 67.538447 -434.893204) (xy 67.609321 -434.90119) (xy 67.678856 -434.91706) (xy 67.746176 -434.940617)
			(xy 67.810435 -434.971562) (xy 67.870826 -435.009508) (xy 67.926588 -435.053977) (xy 67.977021 -435.10441)
			(xy 68.02149 -435.160172) (xy 68.059436 -435.220563) (xy 68.090381 -435.284822) (xy 68.113938 -435.352142)
			(xy 68.129808 -435.421677) (xy 68.137794 -435.492551) (xy 68.137794 -435.563873) (xy 68.129808 -435.634747)
			(xy 68.113938 -435.704282) (xy 68.090381 -435.771602) (xy 68.059436 -435.835861) (xy 68.02149 -435.896252)
			(xy 67.977021 -435.952014) (xy 67.926588 -436.002447) (xy 67.870826 -436.046916) (xy 67.810435 -436.084862)
			(xy 67.746176 -436.115807) (xy 67.678856 -436.139364) (xy 67.609321 -436.155234) (xy 67.538447 -436.16322)
			(xy 67.467125 -436.16322) (xy 67.396251 -436.155234) (xy 67.326716 -436.139364) (xy 67.259396 -436.115807)
			(xy 67.195137 -436.084862) (xy 67.134746 -436.046916) (xy 67.078984 -436.002447) (xy 67.028551 -435.952014)
			(xy 66.984082 -435.896252) (xy 66.946136 -435.835861) (xy 66.915191 -435.771602) (xy 66.891634 -435.704282)
			(xy 66.875764 -435.634747) (xy 66.867778 -435.563873) (xy 65.33338 -435.563873) (xy 65.325394 -435.634747)
			(xy 65.309524 -435.704282) (xy 65.285967 -435.771602) (xy 65.255022 -435.835861) (xy 65.217076 -435.896252)
			(xy 65.172607 -435.952014) (xy 65.122174 -436.002447) (xy 65.066412 -436.046916) (xy 65.006021 -436.084862)
			(xy 64.941762 -436.115807) (xy 64.874442 -436.139364) (xy 64.804907 -436.155234) (xy 64.734033 -436.16322)
			(xy 64.662711 -436.16322) (xy 64.591837 -436.155234) (xy 64.522302 -436.139364) (xy 64.454982 -436.115807)
			(xy 64.390723 -436.084862) (xy 64.330332 -436.046916) (xy 64.27457 -436.002447) (xy 64.224137 -435.952014)
			(xy 64.179668 -435.896252) (xy 64.141722 -435.835861) (xy 64.110777 -435.771602) (xy 64.08722 -435.704282)
			(xy 64.07135 -435.634747) (xy 64.063364 -435.563873) (xy 28.341828 -435.563873) (xy 28.341828 -436.39613)
			(xy 29.085794 -437.140096) (xy 29.102436 -437.156031) (xy 29.14035 -437.182203) (xy 29.18236 -437.201112)
			(xy 29.227091 -437.212139) (xy 29.273077 -437.214922) (xy 29.318811 -437.209371) (xy 29.362796 -437.195667)
			(xy 29.40359 -437.17426) (xy 29.439857 -437.145849) (xy 29.470409 -437.111367) (xy 29.494245 -437.071943)
			(xy 29.510585 -437.028868) (xy 29.518892 -436.983553) (xy 29.519372 -436.960518) (xy 29.519372 -435.989984)
			(xy 31.399988 -435.989984) (xy 31.399988 -436.973488) (xy 34.599874 -436.973488) (xy 34.599874 -436.886588)
			(xy 34.607892 -436.800059) (xy 34.62386 -436.714639) (xy 34.647641 -436.631057) (xy 34.679033 -436.550025)
			(xy 34.717767 -436.472236) (xy 34.763514 -436.398352) (xy 34.815883 -436.329005) (xy 34.874427 -436.264785)
			(xy 34.938647 -436.206241) (xy 35.007994 -436.153872) (xy 35.081878 -436.108125) (xy 35.159667 -436.069391)
			(xy 35.240699 -436.037999) (xy 35.324281 -436.014218) (xy 35.409701 -435.99825) (xy 35.49623 -435.990232)
			(xy 35.53968 -435.98973) (xy 35.58313 -435.990232) (xy 35.669659 -435.99825) (xy 35.755079 -436.014218)
			(xy 35.838661 -436.037999) (xy 35.919693 -436.069391) (xy 35.997482 -436.108125) (xy 36.071366 -436.153872)
			(xy 36.140713 -436.206241) (xy 36.204933 -436.264785) (xy 36.263477 -436.329005) (xy 36.315846 -436.398352)
			(xy 36.361593 -436.472236) (xy 36.400327 -436.550025) (xy 36.431719 -436.631057) (xy 36.4555 -436.714639)
			(xy 36.471468 -436.800059) (xy 36.479486 -436.886588) (xy 36.479486 -436.973488) (xy 36.471468 -437.060017)
			(xy 36.4555 -437.145437) (xy 36.431719 -437.229019) (xy 36.400327 -437.310051) (xy 36.361593 -437.38784)
			(xy 36.317396 -437.459221) (xy 63.99707 -437.459221) (xy 63.99707 -437.387899) (xy 64.005056 -437.317025)
			(xy 64.020926 -437.24749) (xy 64.044483 -437.18017) (xy 64.075428 -437.115911) (xy 64.113374 -437.05552)
			(xy 64.157843 -436.999758) (xy 64.208276 -436.949325) (xy 64.264038 -436.904856) (xy 64.324429 -436.86691)
			(xy 64.388688 -436.835965) (xy 64.456008 -436.812408) (xy 64.525543 -436.796538) (xy 64.596417 -436.788552)
			(xy 64.632078 -436.788052) (xy 64.667739 -436.788552) (xy 64.738613 -436.796538) (xy 64.808148 -436.812408)
			(xy 64.875468 -436.835965) (xy 64.939727 -436.86691) (xy 65.000118 -436.904856) (xy 65.05588 -436.949325)
			(xy 65.106313 -436.999758) (xy 65.150782 -437.05552) (xy 65.188728 -437.115911) (xy 65.219673 -437.18017)
			(xy 65.24323 -437.24749) (xy 65.2591 -437.317025) (xy 65.267086 -437.387899) (xy 65.267086 -437.459221)
			(xy 66.801484 -437.459221) (xy 66.801484 -437.387899) (xy 66.80947 -437.317025) (xy 66.82534 -437.24749)
			(xy 66.848897 -437.18017) (xy 66.879842 -437.115911) (xy 66.917788 -437.05552) (xy 66.962257 -436.999758)
			(xy 67.01269 -436.949325) (xy 67.068452 -436.904856) (xy 67.128843 -436.86691) (xy 67.193102 -436.835965)
			(xy 67.260422 -436.812408) (xy 67.329957 -436.796538) (xy 67.400831 -436.788552) (xy 67.436492 -436.788052)
			(xy 67.472153 -436.788552) (xy 67.543027 -436.796538) (xy 67.612562 -436.812408) (xy 67.679882 -436.835965)
			(xy 67.744141 -436.86691) (xy 67.804532 -436.904856) (xy 67.860294 -436.949325) (xy 67.910727 -436.999758)
			(xy 67.955196 -437.05552) (xy 67.993142 -437.115911) (xy 68.024087 -437.18017) (xy 68.047644 -437.24749)
			(xy 68.063514 -437.317025) (xy 68.0715 -437.387899) (xy 68.0715 -437.459221) (xy 68.063514 -437.530095)
			(xy 68.047644 -437.59963) (xy 68.024087 -437.66695) (xy 67.993142 -437.731209) (xy 67.955196 -437.7916)
			(xy 67.910727 -437.847362) (xy 67.860294 -437.897795) (xy 67.804532 -437.942264) (xy 67.744141 -437.98021)
			(xy 67.679882 -438.011155) (xy 67.612562 -438.034712) (xy 67.543027 -438.050582) (xy 67.472153 -438.058568)
			(xy 67.400831 -438.058568) (xy 67.329957 -438.050582) (xy 67.260422 -438.034712) (xy 67.193102 -438.011155)
			(xy 67.128843 -437.98021) (xy 67.068452 -437.942264) (xy 67.01269 -437.897795) (xy 66.962257 -437.847362)
			(xy 66.917788 -437.7916) (xy 66.879842 -437.731209) (xy 66.848897 -437.66695) (xy 66.82534 -437.59963)
			(xy 66.80947 -437.530095) (xy 66.801484 -437.459221) (xy 65.267086 -437.459221) (xy 65.2591 -437.530095)
			(xy 65.24323 -437.59963) (xy 65.219673 -437.66695) (xy 65.188728 -437.731209) (xy 65.150782 -437.7916)
			(xy 65.106313 -437.847362) (xy 65.05588 -437.897795) (xy 65.000118 -437.942264) (xy 64.939727 -437.98021)
			(xy 64.875468 -438.011155) (xy 64.808148 -438.034712) (xy 64.738613 -438.050582) (xy 64.667739 -438.058568)
			(xy 64.596417 -438.058568) (xy 64.525543 -438.050582) (xy 64.456008 -438.034712) (xy 64.388688 -438.011155)
			(xy 64.324429 -437.98021) (xy 64.264038 -437.942264) (xy 64.208276 -437.897795) (xy 64.157843 -437.847362)
			(xy 64.113374 -437.7916) (xy 64.075428 -437.731209) (xy 64.044483 -437.66695) (xy 64.020926 -437.59963)
			(xy 64.005056 -437.530095) (xy 63.99707 -437.459221) (xy 36.317396 -437.459221) (xy 36.315846 -437.461724)
			(xy 36.263477 -437.531071) (xy 36.204933 -437.595291) (xy 36.140713 -437.653835) (xy 36.071366 -437.706204)
			(xy 35.997482 -437.751951) (xy 35.919693 -437.790685) (xy 35.838661 -437.822077) (xy 35.755079 -437.845858)
			(xy 35.669659 -437.861826) (xy 35.58313 -437.869844) (xy 35.49623 -437.869844) (xy 35.409701 -437.861826)
			(xy 35.324281 -437.845858) (xy 35.240699 -437.822077) (xy 35.159667 -437.790685) (xy 35.081878 -437.751951)
			(xy 35.007994 -437.706204) (xy 34.938647 -437.653835) (xy 34.874427 -437.595291) (xy 34.815883 -437.531071)
			(xy 34.763514 -437.461724) (xy 34.717767 -437.38784) (xy 34.679033 -437.310051) (xy 34.647641 -437.229019)
			(xy 34.62386 -437.145437) (xy 34.607892 -437.060017) (xy 34.599874 -436.973488) (xy 31.399988 -436.973488)
			(xy 31.399988 -437.870092) (xy 30.4292 -437.870092) (xy 30.406157 -437.870601) (xy 30.360829 -437.878925)
			(xy 30.317743 -437.895283) (xy 30.278311 -437.919138) (xy 30.243824 -437.94971) (xy 30.215413 -437.985997)
			(xy 30.194006 -438.02681) (xy 30.180307 -438.070813) (xy 30.174762 -438.116565) (xy 30.177554 -438.162566)
			(xy 30.188592 -438.207311) (xy 30.207513 -438.249334) (xy 30.233699 -438.287259) (xy 30.249622 -438.303924)
			(xy 30.88312 -438.9374) (xy 51.342544 -438.9374) (xy 52.994052 -438.9374) (xy 52.994052 -440.588908)
			(xy 51.342544 -440.588908) (xy 51.342544 -438.9374) (xy 30.88312 -438.9374) (xy 32.133093 -440.18733)
			(xy 41.65141 -440.18733) (xy 41.65141 -440.127394) (xy 41.659233 -440.067972) (xy 41.674746 -440.010079)
			(xy 41.697682 -439.954706) (xy 41.727649 -439.9028) (xy 41.764136 -439.85525) (xy 41.806516 -439.81287)
			(xy 41.854066 -439.776383) (xy 41.905972 -439.746416) (xy 41.961345 -439.72348) (xy 42.019238 -439.707967)
			(xy 42.07866 -439.700144) (xy 42.108628 -439.699654) (xy 42.138596 -439.700144) (xy 42.198018 -439.707967)
			(xy 42.255911 -439.72348) (xy 42.311284 -439.746416) (xy 42.36319 -439.776383) (xy 42.41074 -439.81287)
			(xy 42.45312 -439.85525) (xy 42.489607 -439.9028) (xy 42.519574 -439.954706) (xy 42.54251 -440.010079)
			(xy 42.558023 -440.067972) (xy 42.565846 -440.127394) (xy 42.565846 -440.18733) (xy 42.558023 -440.246752)
			(xy 42.54251 -440.304645) (xy 42.519574 -440.360018) (xy 42.489607 -440.411924) (xy 42.45312 -440.459474)
			(xy 42.41074 -440.501854) (xy 42.36319 -440.538341) (xy 42.311284 -440.568308) (xy 42.255911 -440.591244)
			(xy 42.198018 -440.606757) (xy 42.138596 -440.61458) (xy 42.07866 -440.61458) (xy 42.019238 -440.606757)
			(xy 41.961345 -440.591244) (xy 41.905972 -440.568308) (xy 41.854066 -440.538341) (xy 41.806516 -440.501854)
			(xy 41.764136 -440.459474) (xy 41.727649 -440.411924) (xy 41.697682 -440.360018) (xy 41.674746 -440.304645)
			(xy 41.659233 -440.246752) (xy 41.65141 -440.18733) (xy 32.133093 -440.18733) (xy 33.646478 -441.700662)
			(xy 36.341794 -441.700662) (xy 36.341794 -441.640726) (xy 36.349617 -441.581304) (xy 36.36513 -441.523411)
			(xy 36.388066 -441.468038) (xy 36.418033 -441.416132) (xy 36.45452 -441.368582) (xy 36.4969 -441.326202)
			(xy 36.54445 -441.289715) (xy 36.596356 -441.259748) (xy 36.651729 -441.236812) (xy 36.709622 -441.221299)
			(xy 36.769044 -441.213476) (xy 36.799012 -441.212986) (xy 36.82898 -441.213476) (xy 36.888402 -441.221299)
			(xy 36.921821 -441.230254) (xy 37.721268 -441.230254) (xy 37.721268 -441.170318) (xy 37.729091 -441.110896)
			(xy 37.744604 -441.053003) (xy 37.76754 -440.99763) (xy 37.797507 -440.945724) (xy 37.833994 -440.898174)
			(xy 37.876374 -440.855794) (xy 37.923924 -440.819307) (xy 37.97583 -440.78934) (xy 38.031203 -440.766404)
			(xy 38.089096 -440.750891) (xy 38.148518 -440.743068) (xy 38.178486 -440.742578) (xy 38.208454 -440.743068)
			(xy 38.267876 -440.750891) (xy 38.325769 -440.766404) (xy 38.360833 -440.780928) (xy 39.213264 -440.780928)
			(xy 39.213264 -440.720992) (xy 39.221087 -440.66157) (xy 39.2366 -440.603677) (xy 39.259536 -440.548304)
			(xy 39.289503 -440.496398) (xy 39.32599 -440.448848) (xy 39.36837 -440.406468) (xy 39.41592 -440.369981)
			(xy 39.467826 -440.340014) (xy 39.523199 -440.317078) (xy 39.581092 -440.301565) (xy 39.640514 -440.293742)
			(xy 39.670482 -440.293252) (xy 39.70045 -440.293742) (xy 39.759872 -440.301565) (xy 39.817765 -440.317078)
			(xy 39.873138 -440.340014) (xy 39.925044 -440.369981) (xy 39.972594 -440.406468) (xy 40.014974 -440.448848)
			(xy 40.051461 -440.496398) (xy 40.081428 -440.548304) (xy 40.104364 -440.603677) (xy 40.119877 -440.66157)
			(xy 40.1277 -440.720992) (xy 40.1277 -440.780928) (xy 40.119877 -440.84035) (xy 40.104364 -440.898243)
			(xy 40.081428 -440.953616) (xy 40.051461 -441.005522) (xy 40.014974 -441.053072) (xy 39.972594 -441.095452)
			(xy 39.925044 -441.131939) (xy 39.873138 -441.161906) (xy 39.817765 -441.184842) (xy 39.759872 -441.200355)
			(xy 39.70045 -441.208178) (xy 39.640514 -441.208178) (xy 39.581092 -441.200355) (xy 39.523199 -441.184842)
			(xy 39.467826 -441.161906) (xy 39.41592 -441.131939) (xy 39.36837 -441.095452) (xy 39.32599 -441.053072)
			(xy 39.289503 -441.005522) (xy 39.259536 -440.953616) (xy 39.2366 -440.898243) (xy 39.221087 -440.84035)
			(xy 39.213264 -440.780928) (xy 38.360833 -440.780928) (xy 38.381142 -440.78934) (xy 38.433048 -440.819307)
			(xy 38.480598 -440.855794) (xy 38.522978 -440.898174) (xy 38.559465 -440.945724) (xy 38.589432 -440.99763)
			(xy 38.612368 -441.053003) (xy 38.627881 -441.110896) (xy 38.635704 -441.170318) (xy 38.635704 -441.230254)
			(xy 38.627881 -441.289676) (xy 38.612368 -441.347569) (xy 38.596783 -441.385194) (xy 41.01006 -441.385194)
			(xy 41.01006 -441.325258) (xy 41.017883 -441.265836) (xy 41.033396 -441.207943) (xy 41.056332 -441.15257)
			(xy 41.086299 -441.100664) (xy 41.122786 -441.053114) (xy 41.165166 -441.010734) (xy 41.212716 -440.974247)
			(xy 41.264622 -440.94428) (xy 41.319995 -440.921344) (xy 41.377888 -440.905831) (xy 41.43731 -440.898008)
			(xy 41.467278 -440.897518) (xy 41.497246 -440.898008) (xy 41.556668 -440.905831) (xy 41.614561 -440.921344)
			(xy 41.669934 -440.94428) (xy 41.72184 -440.974247) (xy 41.738358 -440.986922) (xy 43.584858 -440.986922)
			(xy 43.584858 -440.926986) (xy 43.592681 -440.867564) (xy 43.608194 -440.809671) (xy 43.63113 -440.754298)
			(xy 43.661097 -440.702392) (xy 43.697584 -440.654842) (xy 43.739964 -440.612462) (xy 43.787514 -440.575975)
			(xy 43.83942 -440.546008) (xy 43.894793 -440.523072) (xy 43.952686 -440.507559) (xy 44.012108 -440.499736)
			(xy 44.042076 -440.499246) (xy 44.072044 -440.499736) (xy 44.131466 -440.507559) (xy 44.189359 -440.523072)
			(xy 44.244732 -440.546008) (xy 44.296638 -440.575975) (xy 44.344188 -440.612462) (xy 44.386568 -440.654842)
			(xy 44.423055 -440.702392) (xy 44.453022 -440.754298) (xy 44.475958 -440.809671) (xy 44.491471 -440.867564)
			(xy 44.499294 -440.926986) (xy 44.499294 -440.986922) (xy 44.491471 -441.046344) (xy 44.475958 -441.104237)
			(xy 44.453022 -441.15961) (xy 44.423055 -441.211516) (xy 44.386568 -441.259066) (xy 44.344188 -441.301446)
			(xy 44.296638 -441.337933) (xy 44.244732 -441.3679) (xy 44.189359 -441.390836) (xy 44.131466 -441.406349)
			(xy 44.072044 -441.414172) (xy 44.012108 -441.414172) (xy 43.952686 -441.406349) (xy 43.894793 -441.390836)
			(xy 43.83942 -441.3679) (xy 43.787514 -441.337933) (xy 43.739964 -441.301446) (xy 43.697584 -441.259066)
			(xy 43.661097 -441.211516) (xy 43.63113 -441.15961) (xy 43.608194 -441.104237) (xy 43.592681 -441.046344)
			(xy 43.584858 -440.986922) (xy 41.738358 -440.986922) (xy 41.76939 -441.010734) (xy 41.81177 -441.053114)
			(xy 41.848257 -441.100664) (xy 41.878224 -441.15257) (xy 41.90116 -441.207943) (xy 41.916673 -441.265836)
			(xy 41.924496 -441.325258) (xy 41.924496 -441.385194) (xy 41.916673 -441.444616) (xy 41.90116 -441.502509)
			(xy 41.878224 -441.557882) (xy 41.848257 -441.609788) (xy 41.81177 -441.657338) (xy 41.76939 -441.699718)
			(xy 41.72184 -441.736205) (xy 41.669934 -441.766172) (xy 41.615305 -441.7888) (xy 42.253136 -441.7888)
			(xy 42.253136 -441.728864) (xy 42.260959 -441.669442) (xy 42.276472 -441.611549) (xy 42.299408 -441.556176)
			(xy 42.329375 -441.50427) (xy 42.365862 -441.45672) (xy 42.408242 -441.41434) (xy 42.455792 -441.377853)
			(xy 42.507698 -441.347886) (xy 42.563071 -441.32495) (xy 42.620964 -441.309437) (xy 42.680386 -441.301614)
			(xy 42.710354 -441.301124) (xy 42.740322 -441.301614) (xy 42.799744 -441.309437) (xy 42.857637 -441.32495)
			(xy 42.91301 -441.347886) (xy 42.964916 -441.377853) (xy 43.012466 -441.41434) (xy 43.054846 -441.45672)
			(xy 43.091333 -441.50427) (xy 43.1213 -441.556176) (xy 43.144236 -441.611549) (xy 43.159749 -441.669442)
			(xy 43.167572 -441.728864) (xy 43.167572 -441.7888) (xy 43.159749 -441.848222) (xy 43.144236 -441.906115)
			(xy 43.1213 -441.961488) (xy 43.091333 -442.013394) (xy 43.054846 -442.060944) (xy 43.012466 -442.103324)
			(xy 42.964916 -442.139811) (xy 42.91301 -442.169778) (xy 42.857637 -442.192714) (xy 42.799744 -442.208227)
			(xy 42.740322 -442.21605) (xy 42.680386 -442.21605) (xy 42.620964 -442.208227) (xy 42.563071 -442.192714)
			(xy 42.507698 -442.169778) (xy 42.455792 -442.139811) (xy 42.408242 -442.103324) (xy 42.365862 -442.060944)
			(xy 42.329375 -442.013394) (xy 42.299408 -441.961488) (xy 42.276472 -441.906115) (xy 42.260959 -441.848222)
			(xy 42.253136 -441.7888) (xy 41.615305 -441.7888) (xy 41.614561 -441.789108) (xy 41.556668 -441.804621)
			(xy 41.497246 -441.812444) (xy 41.43731 -441.812444) (xy 41.377888 -441.804621) (xy 41.319995 -441.789108)
			(xy 41.264622 -441.766172) (xy 41.212716 -441.736205) (xy 41.165166 -441.699718) (xy 41.122786 -441.657338)
			(xy 41.086299 -441.609788) (xy 41.056332 -441.557882) (xy 41.033396 -441.502509) (xy 41.017883 -441.444616)
			(xy 41.01006 -441.385194) (xy 38.596783 -441.385194) (xy 38.589432 -441.402942) (xy 38.559465 -441.454848)
			(xy 38.522978 -441.502398) (xy 38.480598 -441.544778) (xy 38.433048 -441.581265) (xy 38.381142 -441.611232)
			(xy 38.325769 -441.634168) (xy 38.267876 -441.649681) (xy 38.208454 -441.657504) (xy 38.148518 -441.657504)
			(xy 38.089096 -441.649681) (xy 38.031203 -441.634168) (xy 37.97583 -441.611232) (xy 37.923924 -441.581265)
			(xy 37.876374 -441.544778) (xy 37.833994 -441.502398) (xy 37.797507 -441.454848) (xy 37.76754 -441.402942)
			(xy 37.744604 -441.347569) (xy 37.729091 -441.289676) (xy 37.721268 -441.230254) (xy 36.921821 -441.230254)
			(xy 36.946295 -441.236812) (xy 37.001668 -441.259748) (xy 37.053574 -441.289715) (xy 37.101124 -441.326202)
			(xy 37.143504 -441.368582) (xy 37.179991 -441.416132) (xy 37.209958 -441.468038) (xy 37.232894 -441.523411)
			(xy 37.248407 -441.581304) (xy 37.25623 -441.640726) (xy 37.25623 -441.700662) (xy 37.248407 -441.760084)
			(xy 37.232894 -441.817977) (xy 37.209958 -441.87335) (xy 37.179991 -441.925256) (xy 37.143504 -441.972806)
			(xy 37.101124 -442.015186) (xy 37.053574 -442.051673) (xy 37.001668 -442.08164) (xy 36.946295 -442.104576)
			(xy 36.888402 -442.120089) (xy 36.82898 -442.127912) (xy 36.769044 -442.127912) (xy 36.709622 -442.120089)
			(xy 36.651729 -442.104576) (xy 36.596356 -442.08164) (xy 36.54445 -442.051673) (xy 36.4969 -442.015186)
			(xy 36.45452 -441.972806) (xy 36.418033 -441.925256) (xy 36.388066 -441.87335) (xy 36.36513 -441.817977)
			(xy 36.349617 -441.760084) (xy 36.341794 -441.700662) (xy 33.646478 -441.700662) (xy 37.364659 -445.418714)
			(xy 78.673688 -445.418714) (xy 78.673688 -445.358778) (xy 78.681511 -445.299356) (xy 78.697024 -445.241463)
			(xy 78.71996 -445.18609) (xy 78.749927 -445.134184) (xy 78.786414 -445.086634) (xy 78.828794 -445.044254)
			(xy 78.876344 -445.007767) (xy 78.92825 -444.9778) (xy 78.983623 -444.954864) (xy 79.041516 -444.939351)
			(xy 79.100938 -444.931528) (xy 79.130906 -444.931038) (xy 79.160874 -444.931528) (xy 79.220296 -444.939351)
			(xy 79.278189 -444.954864) (xy 79.333562 -444.9778) (xy 79.385468 -445.007767) (xy 79.433018 -445.044254)
			(xy 79.475398 -445.086634) (xy 79.511885 -445.134184) (xy 79.541852 -445.18609) (xy 79.564788 -445.241463)
			(xy 79.580301 -445.299356) (xy 79.588124 -445.358778) (xy 79.588124 -445.410332) (xy 81.148664 -445.410332)
			(xy 81.148664 -445.350396) (xy 81.156487 -445.290974) (xy 81.172 -445.233081) (xy 81.194936 -445.177708)
			(xy 81.224903 -445.125802) (xy 81.26139 -445.078252) (xy 81.30377 -445.035872) (xy 81.35132 -444.999385)
			(xy 81.403226 -444.969418) (xy 81.458599 -444.946482) (xy 81.516492 -444.930969) (xy 81.575914 -444.923146)
			(xy 81.605882 -444.922656) (xy 81.63585 -444.923146) (xy 81.695272 -444.930969) (xy 81.753165 -444.946482)
			(xy 81.808538 -444.969418) (xy 81.860444 -444.999385) (xy 81.907994 -445.035872) (xy 81.930664 -445.058542)
			(xy 83.33408 -445.058542) (xy 83.33408 -444.998606) (xy 83.341903 -444.939184) (xy 83.357416 -444.881291)
			(xy 83.380352 -444.825918) (xy 83.410319 -444.774012) (xy 83.446806 -444.726462) (xy 83.489186 -444.684082)
			(xy 83.536736 -444.647595) (xy 83.588642 -444.617628) (xy 83.644015 -444.594692) (xy 83.701908 -444.579179)
			(xy 83.76133 -444.571356) (xy 83.791298 -444.570866) (xy 83.821266 -444.571356) (xy 83.880688 -444.579179)
			(xy 83.938581 -444.594692) (xy 83.993954 -444.617628) (xy 84.04586 -444.647595) (xy 84.09341 -444.684082)
			(xy 84.13579 -444.726462) (xy 84.172277 -444.774012) (xy 84.202244 -444.825918) (xy 84.22518 -444.881291)
			(xy 84.240693 -444.939184) (xy 84.248516 -444.998606) (xy 84.248516 -445.058542) (xy 84.240693 -445.117964)
			(xy 84.22518 -445.175857) (xy 84.202244 -445.23123) (xy 84.172277 -445.283136) (xy 84.13579 -445.330686)
			(xy 84.105928 -445.360548) (xy 84.818202 -445.360548) (xy 84.818202 -445.300612) (xy 84.826025 -445.24119)
			(xy 84.841538 -445.183297) (xy 84.864474 -445.127924) (xy 84.894441 -445.076018) (xy 84.930928 -445.028468)
			(xy 84.973308 -444.986088) (xy 85.020858 -444.949601) (xy 85.072764 -444.919634) (xy 85.128137 -444.896698)
			(xy 85.18603 -444.881185) (xy 85.245452 -444.873362) (xy 85.27542 -444.872872) (xy 85.305388 -444.873362)
			(xy 85.36481 -444.881185) (xy 85.422703 -444.896698) (xy 85.478076 -444.919634) (xy 85.529982 -444.949601)
			(xy 85.577532 -444.986088) (xy 85.619912 -445.028468) (xy 85.656399 -445.076018) (xy 85.686366 -445.127924)
			(xy 85.709302 -445.183297) (xy 85.724815 -445.24119) (xy 85.732638 -445.300612) (xy 85.732638 -445.360548)
			(xy 85.724815 -445.41997) (xy 85.709302 -445.477863) (xy 85.686366 -445.533236) (xy 85.656399 -445.585142)
			(xy 85.619912 -445.632692) (xy 85.577532 -445.675072) (xy 85.529982 -445.711559) (xy 85.478076 -445.741526)
			(xy 85.422703 -445.764462) (xy 85.36481 -445.779975) (xy 85.305388 -445.787798) (xy 85.245452 -445.787798)
			(xy 85.18603 -445.779975) (xy 85.128137 -445.764462) (xy 85.072764 -445.741526) (xy 85.020858 -445.711559)
			(xy 84.973308 -445.675072) (xy 84.930928 -445.632692) (xy 84.894441 -445.585142) (xy 84.864474 -445.533236)
			(xy 84.841538 -445.477863) (xy 84.826025 -445.41997) (xy 84.818202 -445.360548) (xy 84.105928 -445.360548)
			(xy 84.09341 -445.373066) (xy 84.04586 -445.409553) (xy 83.993954 -445.43952) (xy 83.938581 -445.462456)
			(xy 83.880688 -445.477969) (xy 83.821266 -445.485792) (xy 83.76133 -445.485792) (xy 83.701908 -445.477969)
			(xy 83.644015 -445.462456) (xy 83.588642 -445.43952) (xy 83.536736 -445.409553) (xy 83.489186 -445.373066)
			(xy 83.446806 -445.330686) (xy 83.410319 -445.283136) (xy 83.380352 -445.23123) (xy 83.357416 -445.175857)
			(xy 83.341903 -445.117964) (xy 83.33408 -445.058542) (xy 81.930664 -445.058542) (xy 81.950374 -445.078252)
			(xy 81.986861 -445.125802) (xy 82.016828 -445.177708) (xy 82.039764 -445.233081) (xy 82.055277 -445.290974)
			(xy 82.0631 -445.350396) (xy 82.0631 -445.410332) (xy 82.055277 -445.469754) (xy 82.039764 -445.527647)
			(xy 82.016828 -445.58302) (xy 81.986861 -445.634926) (xy 81.950374 -445.682476) (xy 81.907994 -445.724856)
			(xy 81.860444 -445.761343) (xy 81.808538 -445.79131) (xy 81.753165 -445.814246) (xy 81.695272 -445.829759)
			(xy 81.63585 -445.837582) (xy 81.575914 -445.837582) (xy 81.516492 -445.829759) (xy 81.458599 -445.814246)
			(xy 81.403226 -445.79131) (xy 81.35132 -445.761343) (xy 81.30377 -445.724856) (xy 81.26139 -445.682476)
			(xy 81.224903 -445.634926) (xy 81.194936 -445.58302) (xy 81.172 -445.527647) (xy 81.156487 -445.469754)
			(xy 81.148664 -445.410332) (xy 79.588124 -445.410332) (xy 79.588124 -445.418714) (xy 79.580301 -445.478136)
			(xy 79.564788 -445.536029) (xy 79.541852 -445.591402) (xy 79.511885 -445.643308) (xy 79.475398 -445.690858)
			(xy 79.433018 -445.733238) (xy 79.385468 -445.769725) (xy 79.333562 -445.799692) (xy 79.278189 -445.822628)
			(xy 79.220296 -445.838141) (xy 79.160874 -445.845964) (xy 79.100938 -445.845964) (xy 79.041516 -445.838141)
			(xy 78.983623 -445.822628) (xy 78.92825 -445.799692) (xy 78.876344 -445.769725) (xy 78.828794 -445.733238)
			(xy 78.786414 -445.690858) (xy 78.749927 -445.643308) (xy 78.71996 -445.591402) (xy 78.697024 -445.536029)
			(xy 78.681511 -445.478136) (xy 78.673688 -445.418714) (xy 37.364659 -445.418714) (xy 37.580824 -445.634872)
			(xy 37.580824 -451.381047) (xy 39.818567 -451.381047) (xy 39.824576 -451.265126) (xy 39.838567 -451.149897)
			(xy 39.860475 -451.035907) (xy 39.890195 -450.9237) (xy 39.927585 -450.813811) (xy 39.972468 -450.706764)
			(xy 40.024629 -450.603068) (xy 40.08382 -450.503218) (xy 40.149759 -450.407689) (xy 40.222131 -450.316938)
			(xy 40.300592 -450.231395) (xy 40.384767 -450.151469) (xy 40.474256 -450.077542) (xy 40.568632 -450.009964)
			(xy 40.667446 -449.949058) (xy 40.770226 -449.895115) (xy 40.876483 -449.848391) (xy 40.98571 -449.80911)
			(xy 41.097387 -449.777458) (xy 41.210982 -449.753585) (xy 41.325953 -449.737607) (xy 41.441752 -449.729599)
			(xy 41.49979 -449.729098) (xy 41.557828 -449.729599) (xy 41.673627 -449.737607) (xy 41.788598 -449.753585)
			(xy 41.902193 -449.777458) (xy 42.01387 -449.80911) (xy 42.123097 -449.848391) (xy 42.229354 -449.895115)
			(xy 42.332134 -449.949058) (xy 42.430948 -450.009964) (xy 42.474432 -450.041101) (xy 63.647829 -450.041101)
			(xy 63.653878 -449.965531) (xy 63.667925 -449.891033) (xy 63.689811 -449.81845) (xy 63.719288 -449.748604)
			(xy 63.756023 -449.682287) (xy 63.799598 -449.620251) (xy 63.84952 -449.563198) (xy 63.905224 -449.511774)
			(xy 63.966079 -449.466563) (xy 64.031394 -449.428076) (xy 64.10043 -449.39675) (xy 64.172405 -449.37294)
			(xy 64.246503 -449.356915) (xy 64.321884 -449.348856) (xy 64.35979 -449.348352) (xy 64.397696 -449.348856)
			(xy 64.473077 -449.356915) (xy 64.547175 -449.37294) (xy 64.61915 -449.39675) (xy 64.688186 -449.428076)
			(xy 64.753501 -449.466563) (xy 64.814356 -449.511774) (xy 64.87006 -449.563198) (xy 64.919982 -449.620251)
			(xy 64.963557 -449.682287) (xy 65.000292 -449.748604) (xy 65.029769 -449.81845) (xy 65.051655 -449.891033)
			(xy 65.065702 -449.965531) (xy 65.071751 -450.041101) (xy 66.187829 -450.041101) (xy 66.193878 -449.965531)
			(xy 66.207925 -449.891033) (xy 66.229811 -449.81845) (xy 66.259288 -449.748604) (xy 66.296023 -449.682287)
			(xy 66.339598 -449.620251) (xy 66.38952 -449.563198) (xy 66.445224 -449.511774) (xy 66.506079 -449.466563)
			(xy 66.571394 -449.428076) (xy 66.64043 -449.39675) (xy 66.712405 -449.37294) (xy 66.786503 -449.356915)
			(xy 66.861884 -449.348856) (xy 66.89979 -449.348352) (xy 66.937696 -449.348856) (xy 67.013077 -449.356915)
			(xy 67.087175 -449.37294) (xy 67.15915 -449.39675) (xy 67.228186 -449.428076) (xy 67.293501 -449.466563)
			(xy 67.354356 -449.511774) (xy 67.41006 -449.563198) (xy 67.459982 -449.620251) (xy 67.503557 -449.682287)
			(xy 67.540292 -449.748604) (xy 67.569769 -449.81845) (xy 67.591655 -449.891033) (xy 67.605702 -449.965531)
			(xy 67.611751 -450.041101) (xy 68.727829 -450.041101) (xy 68.733878 -449.965531) (xy 68.747925 -449.891033)
			(xy 68.769811 -449.81845) (xy 68.799288 -449.748604) (xy 68.836023 -449.682287) (xy 68.879598 -449.620251)
			(xy 68.92952 -449.563198) (xy 68.985224 -449.511774) (xy 69.046079 -449.466563) (xy 69.111394 -449.428076)
			(xy 69.18043 -449.39675) (xy 69.252405 -449.37294) (xy 69.326503 -449.356915) (xy 69.401884 -449.348856)
			(xy 69.43979 -449.348352) (xy 69.477696 -449.348856) (xy 69.553077 -449.356915) (xy 69.627175 -449.37294)
			(xy 69.69915 -449.39675) (xy 69.768186 -449.428076) (xy 69.833501 -449.466563) (xy 69.894356 -449.511774)
			(xy 69.95006 -449.563198) (xy 69.999982 -449.620251) (xy 70.043557 -449.682287) (xy 70.080292 -449.748604)
			(xy 70.109769 -449.81845) (xy 70.131655 -449.891033) (xy 70.145702 -449.965531) (xy 70.151751 -450.041101)
			(xy 71.267829 -450.041101) (xy 71.273878 -449.965531) (xy 71.287925 -449.891033) (xy 71.309811 -449.81845)
			(xy 71.339288 -449.748604) (xy 71.376023 -449.682287) (xy 71.419598 -449.620251) (xy 71.46952 -449.563198)
			(xy 71.525224 -449.511774) (xy 71.586079 -449.466563) (xy 71.651394 -449.428076) (xy 71.72043 -449.39675)
			(xy 71.792405 -449.37294) (xy 71.866503 -449.356915) (xy 71.941884 -449.348856) (xy 71.97979 -449.348352)
			(xy 72.017696 -449.348856) (xy 72.093077 -449.356915) (xy 72.167175 -449.37294) (xy 72.23915 -449.39675)
			(xy 72.308186 -449.428076) (xy 72.373501 -449.466563) (xy 72.434356 -449.511774) (xy 72.49006 -449.563198)
			(xy 72.539982 -449.620251) (xy 72.583557 -449.682287) (xy 72.620292 -449.748604) (xy 72.649769 -449.81845)
			(xy 72.671655 -449.891033) (xy 72.685702 -449.965531) (xy 72.691751 -450.041101) (xy 73.807829 -450.041101)
			(xy 73.813878 -449.965531) (xy 73.827925 -449.891033) (xy 73.849811 -449.81845) (xy 73.879288 -449.748604)
			(xy 73.916023 -449.682287) (xy 73.959598 -449.620251) (xy 74.00952 -449.563198) (xy 74.065224 -449.511774)
			(xy 74.126079 -449.466563) (xy 74.191394 -449.428076) (xy 74.26043 -449.39675) (xy 74.332405 -449.37294)
			(xy 74.406503 -449.356915) (xy 74.481884 -449.348856) (xy 74.51979 -449.348352) (xy 74.557696 -449.348856)
			(xy 74.633077 -449.356915) (xy 74.707175 -449.37294) (xy 74.77915 -449.39675) (xy 74.848186 -449.428076)
			(xy 74.913501 -449.466563) (xy 74.974356 -449.511774) (xy 75.03006 -449.563198) (xy 75.079982 -449.620251)
			(xy 75.123557 -449.682287) (xy 75.160292 -449.748604) (xy 75.189769 -449.81845) (xy 75.211655 -449.891033)
			(xy 75.225702 -449.965531) (xy 75.231751 -450.041101) (xy 76.347829 -450.041101) (xy 76.353878 -449.965531)
			(xy 76.367925 -449.891033) (xy 76.389811 -449.81845) (xy 76.419288 -449.748604) (xy 76.456023 -449.682287)
			(xy 76.499598 -449.620251) (xy 76.54952 -449.563198) (xy 76.605224 -449.511774) (xy 76.666079 -449.466563)
			(xy 76.731394 -449.428076) (xy 76.80043 -449.39675) (xy 76.872405 -449.37294) (xy 76.946503 -449.356915)
			(xy 77.021884 -449.348856) (xy 77.05979 -449.348352) (xy 77.097696 -449.348856) (xy 77.173077 -449.356915)
			(xy 77.247175 -449.37294) (xy 77.31915 -449.39675) (xy 77.388186 -449.428076) (xy 77.453501 -449.466563)
			(xy 77.514356 -449.511774) (xy 77.57006 -449.563198) (xy 77.619982 -449.620251) (xy 77.663557 -449.682287)
			(xy 77.700292 -449.748604) (xy 77.729769 -449.81845) (xy 77.751655 -449.891033) (xy 77.765702 -449.965531)
			(xy 77.771751 -450.041101) (xy 78.887829 -450.041101) (xy 78.893878 -449.965531) (xy 78.907925 -449.891033)
			(xy 78.929811 -449.81845) (xy 78.959288 -449.748604) (xy 78.996023 -449.682287) (xy 79.039598 -449.620251)
			(xy 79.08952 -449.563198) (xy 79.145224 -449.511774) (xy 79.206079 -449.466563) (xy 79.271394 -449.428076)
			(xy 79.34043 -449.39675) (xy 79.412405 -449.37294) (xy 79.486503 -449.356915) (xy 79.561884 -449.348856)
			(xy 79.59979 -449.348352) (xy 79.637696 -449.348856) (xy 79.713077 -449.356915) (xy 79.787175 -449.37294)
			(xy 79.85915 -449.39675) (xy 79.928186 -449.428076) (xy 79.993501 -449.466563) (xy 80.054356 -449.511774)
			(xy 80.11006 -449.563198) (xy 80.159982 -449.620251) (xy 80.203557 -449.682287) (xy 80.240292 -449.748604)
			(xy 80.269769 -449.81845) (xy 80.291655 -449.891033) (xy 80.305702 -449.965531) (xy 80.311751 -450.041101)
			(xy 81.427829 -450.041101) (xy 81.433878 -449.965531) (xy 81.447925 -449.891033) (xy 81.469811 -449.81845)
			(xy 81.499288 -449.748604) (xy 81.536023 -449.682287) (xy 81.579598 -449.620251) (xy 81.62952 -449.563198)
			(xy 81.685224 -449.511774) (xy 81.746079 -449.466563) (xy 81.811394 -449.428076) (xy 81.88043 -449.39675)
			(xy 81.952405 -449.37294) (xy 82.026503 -449.356915) (xy 82.101884 -449.348856) (xy 82.13979 -449.348352)
			(xy 82.177696 -449.348856) (xy 82.253077 -449.356915) (xy 82.327175 -449.37294) (xy 82.39915 -449.39675)
			(xy 82.468186 -449.428076) (xy 82.533501 -449.466563) (xy 82.559813 -449.486111) (xy 86.197949 -449.486111)
			(xy 86.203998 -449.410541) (xy 86.218045 -449.336043) (xy 86.239931 -449.26346) (xy 86.269408 -449.193614)
			(xy 86.306143 -449.127297) (xy 86.349718 -449.065261) (xy 86.39964 -449.008208) (xy 86.455344 -448.956784)
			(xy 86.516199 -448.911573) (xy 86.581514 -448.873086) (xy 86.65055 -448.84176) (xy 86.722525 -448.81795)
			(xy 86.796623 -448.801925) (xy 86.872004 -448.793866) (xy 86.90991 -448.793362) (xy 86.947816 -448.793866)
			(xy 87.023197 -448.801925) (xy 87.097295 -448.81795) (xy 87.16927 -448.84176) (xy 87.238306 -448.873086)
			(xy 87.303621 -448.911573) (xy 87.364476 -448.956784) (xy 87.42018 -449.008208) (xy 87.470102 -449.065261)
			(xy 87.513677 -449.127297) (xy 87.550412 -449.193614) (xy 87.579889 -449.26346) (xy 87.601775 -449.336043)
			(xy 87.615822 -449.410541) (xy 87.621871 -449.486111) (xy 88.737949 -449.486111) (xy 88.743998 -449.410541)
			(xy 88.758045 -449.336043) (xy 88.779931 -449.26346) (xy 88.809408 -449.193614) (xy 88.846143 -449.127297)
			(xy 88.889718 -449.065261) (xy 88.93964 -449.008208) (xy 88.995344 -448.956784) (xy 89.056199 -448.911573)
			(xy 89.121514 -448.873086) (xy 89.19055 -448.84176) (xy 89.262525 -448.81795) (xy 89.336623 -448.801925)
			(xy 89.412004 -448.793866) (xy 89.44991 -448.793362) (xy 89.487816 -448.793866) (xy 89.563197 -448.801925)
			(xy 89.637295 -448.81795) (xy 89.70927 -448.84176) (xy 89.778306 -448.873086) (xy 89.843621 -448.911573)
			(xy 89.904476 -448.956784) (xy 89.96018 -449.008208) (xy 90.010102 -449.065261) (xy 90.053677 -449.127297)
			(xy 90.090412 -449.193614) (xy 90.119889 -449.26346) (xy 90.141775 -449.336043) (xy 90.155822 -449.410541)
			(xy 90.161871 -449.486111) (xy 91.277949 -449.486111) (xy 91.283998 -449.410541) (xy 91.298045 -449.336043)
			(xy 91.319931 -449.26346) (xy 91.349408 -449.193614) (xy 91.386143 -449.127297) (xy 91.429718 -449.065261)
			(xy 91.47964 -449.008208) (xy 91.535344 -448.956784) (xy 91.596199 -448.911573) (xy 91.661514 -448.873086)
			(xy 91.73055 -448.84176) (xy 91.802525 -448.81795) (xy 91.876623 -448.801925) (xy 91.952004 -448.793866)
			(xy 91.98991 -448.793362) (xy 92.027816 -448.793866) (xy 92.103197 -448.801925) (xy 92.177295 -448.81795)
			(xy 92.24927 -448.84176) (xy 92.318306 -448.873086) (xy 92.383621 -448.911573) (xy 92.444476 -448.956784)
			(xy 92.50018 -449.008208) (xy 92.550102 -449.065261) (xy 92.593677 -449.127297) (xy 92.630412 -449.193614)
			(xy 92.659889 -449.26346) (xy 92.681775 -449.336043) (xy 92.695822 -449.410541) (xy 92.701871 -449.486111)
			(xy 92.699852 -449.561895) (xy 92.68979 -449.637035) (xy 92.671798 -449.71068) (xy 92.64608 -449.781996)
			(xy 92.612928 -449.850173) (xy 92.572716 -449.914441) (xy 92.525901 -449.97407) (xy 92.473013 -450.028386)
			(xy 92.414651 -450.076772) (xy 92.351476 -450.11868) (xy 92.284205 -450.153636) (xy 92.2136 -450.181243)
			(xy 92.140459 -450.201189) (xy 92.065614 -450.213248) (xy 91.98991 -450.217283) (xy 91.914206 -450.213248)
			(xy 91.839361 -450.201189) (xy 91.76622 -450.181243) (xy 91.695615 -450.153636) (xy 91.628344 -450.11868)
			(xy 91.565169 -450.076772) (xy 91.506807 -450.028386) (xy 91.453919 -449.97407) (xy 91.407104 -449.914441)
			(xy 91.366892 -449.850173) (xy 91.33374 -449.781996) (xy 91.308022 -449.71068) (xy 91.29003 -449.637035)
			(xy 91.279968 -449.561895) (xy 91.277949 -449.486111) (xy 90.161871 -449.486111) (xy 90.159852 -449.561895)
			(xy 90.14979 -449.637035) (xy 90.131798 -449.71068) (xy 90.10608 -449.781996) (xy 90.072928 -449.850173)
			(xy 90.032716 -449.914441) (xy 89.985901 -449.97407) (xy 89.933013 -450.028386) (xy 89.874651 -450.076772)
			(xy 89.811476 -450.11868) (xy 89.744205 -450.153636) (xy 89.6736 -450.181243) (xy 89.600459 -450.201189)
			(xy 89.525614 -450.213248) (xy 89.44991 -450.217283) (xy 89.374206 -450.213248) (xy 89.299361 -450.201189)
			(xy 89.22622 -450.181243) (xy 89.155615 -450.153636) (xy 89.088344 -450.11868) (xy 89.025169 -450.076772)
			(xy 88.966807 -450.028386) (xy 88.913919 -449.97407) (xy 88.867104 -449.914441) (xy 88.826892 -449.850173)
			(xy 88.79374 -449.781996) (xy 88.768022 -449.71068) (xy 88.75003 -449.637035) (xy 88.739968 -449.561895)
			(xy 88.737949 -449.486111) (xy 87.621871 -449.486111) (xy 87.619852 -449.561895) (xy 87.60979 -449.637035)
			(xy 87.591798 -449.71068) (xy 87.56608 -449.781996) (xy 87.532928 -449.850173) (xy 87.492716 -449.914441)
			(xy 87.445901 -449.97407) (xy 87.393013 -450.028386) (xy 87.334651 -450.076772) (xy 87.271476 -450.11868)
			(xy 87.204205 -450.153636) (xy 87.1336 -450.181243) (xy 87.060459 -450.201189) (xy 86.985614 -450.213248)
			(xy 86.90991 -450.217283) (xy 86.834206 -450.213248) (xy 86.759361 -450.201189) (xy 86.68622 -450.181243)
			(xy 86.615615 -450.153636) (xy 86.548344 -450.11868) (xy 86.485169 -450.076772) (xy 86.426807 -450.028386)
			(xy 86.373919 -449.97407) (xy 86.327104 -449.914441) (xy 86.286892 -449.850173) (xy 86.25374 -449.781996)
			(xy 86.228022 -449.71068) (xy 86.21003 -449.637035) (xy 86.199968 -449.561895) (xy 86.197949 -449.486111)
			(xy 82.559813 -449.486111) (xy 82.594356 -449.511774) (xy 82.65006 -449.563198) (xy 82.699982 -449.620251)
			(xy 82.743557 -449.682287) (xy 82.780292 -449.748604) (xy 82.809769 -449.81845) (xy 82.831655 -449.891033)
			(xy 82.845702 -449.965531) (xy 82.851751 -450.041101) (xy 82.849732 -450.116885) (xy 82.83967 -450.192025)
			(xy 82.821678 -450.26567) (xy 82.79596 -450.336986) (xy 82.762808 -450.405163) (xy 82.722596 -450.469431)
			(xy 82.675781 -450.52906) (xy 82.622893 -450.583376) (xy 82.564531 -450.631762) (xy 82.501356 -450.67367)
			(xy 82.434085 -450.708626) (xy 82.36348 -450.736233) (xy 82.290588 -450.756111) (xy 84.927949 -450.756111)
			(xy 84.933998 -450.680541) (xy 84.948045 -450.606043) (xy 84.969931 -450.53346) (xy 84.999408 -450.463614)
			(xy 85.036143 -450.397297) (xy 85.079718 -450.335261) (xy 85.12964 -450.278208) (xy 85.185344 -450.226784)
			(xy 85.246199 -450.181573) (xy 85.311514 -450.143086) (xy 85.38055 -450.11176) (xy 85.452525 -450.08795)
			(xy 85.526623 -450.071925) (xy 85.602004 -450.063866) (xy 85.63991 -450.063362) (xy 85.677816 -450.063866)
			(xy 85.753197 -450.071925) (xy 85.827295 -450.08795) (xy 85.89927 -450.11176) (xy 85.968306 -450.143086)
			(xy 86.033621 -450.181573) (xy 86.094476 -450.226784) (xy 86.15018 -450.278208) (xy 86.200102 -450.335261)
			(xy 86.243677 -450.397297) (xy 86.280412 -450.463614) (xy 86.309889 -450.53346) (xy 86.331775 -450.606043)
			(xy 86.345822 -450.680541) (xy 86.351871 -450.756111) (xy 87.467949 -450.756111) (xy 87.473998 -450.680541)
			(xy 87.488045 -450.606043) (xy 87.509931 -450.53346) (xy 87.539408 -450.463614) (xy 87.576143 -450.397297)
			(xy 87.619718 -450.335261) (xy 87.66964 -450.278208) (xy 87.725344 -450.226784) (xy 87.786199 -450.181573)
			(xy 87.851514 -450.143086) (xy 87.92055 -450.11176) (xy 87.992525 -450.08795) (xy 88.066623 -450.071925)
			(xy 88.142004 -450.063866) (xy 88.17991 -450.063362) (xy 88.217816 -450.063866) (xy 88.293197 -450.071925)
			(xy 88.367295 -450.08795) (xy 88.43927 -450.11176) (xy 88.508306 -450.143086) (xy 88.573621 -450.181573)
			(xy 88.634476 -450.226784) (xy 88.69018 -450.278208) (xy 88.740102 -450.335261) (xy 88.783677 -450.397297)
			(xy 88.820412 -450.463614) (xy 88.849889 -450.53346) (xy 88.871775 -450.606043) (xy 88.885822 -450.680541)
			(xy 88.891871 -450.756111) (xy 90.007949 -450.756111) (xy 90.013998 -450.680541) (xy 90.028045 -450.606043)
			(xy 90.049931 -450.53346) (xy 90.079408 -450.463614) (xy 90.116143 -450.397297) (xy 90.159718 -450.335261)
			(xy 90.20964 -450.278208) (xy 90.265344 -450.226784) (xy 90.326199 -450.181573) (xy 90.391514 -450.143086)
			(xy 90.46055 -450.11176) (xy 90.532525 -450.08795) (xy 90.606623 -450.071925) (xy 90.682004 -450.063866)
			(xy 90.71991 -450.063362) (xy 90.757816 -450.063866) (xy 90.833197 -450.071925) (xy 90.907295 -450.08795)
			(xy 90.97927 -450.11176) (xy 91.048306 -450.143086) (xy 91.113621 -450.181573) (xy 91.174476 -450.226784)
			(xy 91.23018 -450.278208) (xy 91.280102 -450.335261) (xy 91.323677 -450.397297) (xy 91.360412 -450.463614)
			(xy 91.389889 -450.53346) (xy 91.411775 -450.606043) (xy 91.425822 -450.680541) (xy 91.431871 -450.756111)
			(xy 91.429852 -450.831895) (xy 91.41979 -450.907035) (xy 91.401798 -450.98068) (xy 91.37608 -451.051996)
			(xy 91.342928 -451.120173) (xy 91.302716 -451.184441) (xy 91.255901 -451.24407) (xy 91.203013 -451.298386)
			(xy 91.144651 -451.346772) (xy 91.081476 -451.38868) (xy 91.014205 -451.423636) (xy 90.9436 -451.451243)
			(xy 90.870459 -451.471189) (xy 90.795614 -451.483248) (xy 90.71991 -451.487283) (xy 90.644206 -451.483248)
			(xy 90.569361 -451.471189) (xy 90.49622 -451.451243) (xy 90.425615 -451.423636) (xy 90.358344 -451.38868)
			(xy 90.295169 -451.346772) (xy 90.236807 -451.298386) (xy 90.183919 -451.24407) (xy 90.137104 -451.184441)
			(xy 90.096892 -451.120173) (xy 90.06374 -451.051996) (xy 90.038022 -450.98068) (xy 90.02003 -450.907035)
			(xy 90.009968 -450.831895) (xy 90.007949 -450.756111) (xy 88.891871 -450.756111) (xy 88.889852 -450.831895)
			(xy 88.87979 -450.907035) (xy 88.861798 -450.98068) (xy 88.83608 -451.051996) (xy 88.802928 -451.120173)
			(xy 88.762716 -451.184441) (xy 88.715901 -451.24407) (xy 88.663013 -451.298386) (xy 88.604651 -451.346772)
			(xy 88.541476 -451.38868) (xy 88.474205 -451.423636) (xy 88.4036 -451.451243) (xy 88.330459 -451.471189)
			(xy 88.255614 -451.483248) (xy 88.17991 -451.487283) (xy 88.104206 -451.483248) (xy 88.029361 -451.471189)
			(xy 87.95622 -451.451243) (xy 87.885615 -451.423636) (xy 87.818344 -451.38868) (xy 87.755169 -451.346772)
			(xy 87.696807 -451.298386) (xy 87.643919 -451.24407) (xy 87.597104 -451.184441) (xy 87.556892 -451.120173)
			(xy 87.52374 -451.051996) (xy 87.498022 -450.98068) (xy 87.48003 -450.907035) (xy 87.469968 -450.831895)
			(xy 87.467949 -450.756111) (xy 86.351871 -450.756111) (xy 86.349852 -450.831895) (xy 86.33979 -450.907035)
			(xy 86.321798 -450.98068) (xy 86.29608 -451.051996) (xy 86.262928 -451.120173) (xy 86.222716 -451.184441)
			(xy 86.175901 -451.24407) (xy 86.123013 -451.298386) (xy 86.064651 -451.346772) (xy 86.001476 -451.38868)
			(xy 85.934205 -451.423636) (xy 85.8636 -451.451243) (xy 85.790459 -451.471189) (xy 85.715614 -451.483248)
			(xy 85.63991 -451.487283) (xy 85.564206 -451.483248) (xy 85.489361 -451.471189) (xy 85.41622 -451.451243)
			(xy 85.345615 -451.423636) (xy 85.278344 -451.38868) (xy 85.215169 -451.346772) (xy 85.156807 -451.298386)
			(xy 85.103919 -451.24407) (xy 85.057104 -451.184441) (xy 85.016892 -451.120173) (xy 84.98374 -451.051996)
			(xy 84.958022 -450.98068) (xy 84.94003 -450.907035) (xy 84.929968 -450.831895) (xy 84.927949 -450.756111)
			(xy 82.290588 -450.756111) (xy 82.290339 -450.756179) (xy 82.215494 -450.768238) (xy 82.13979 -450.772273)
			(xy 82.064086 -450.768238) (xy 81.989241 -450.756179) (xy 81.9161 -450.736233) (xy 81.845495 -450.708626)
			(xy 81.778224 -450.67367) (xy 81.715049 -450.631762) (xy 81.656687 -450.583376) (xy 81.603799 -450.52906)
			(xy 81.556984 -450.469431) (xy 81.516772 -450.405163) (xy 81.48362 -450.336986) (xy 81.457902 -450.26567)
			(xy 81.43991 -450.192025) (xy 81.429848 -450.116885) (xy 81.427829 -450.041101) (xy 80.311751 -450.041101)
			(xy 80.309732 -450.116885) (xy 80.29967 -450.192025) (xy 80.281678 -450.26567) (xy 80.25596 -450.336986)
			(xy 80.222808 -450.405163) (xy 80.182596 -450.469431) (xy 80.135781 -450.52906) (xy 80.082893 -450.583376)
			(xy 80.024531 -450.631762) (xy 79.961356 -450.67367) (xy 79.894085 -450.708626) (xy 79.82348 -450.736233)
			(xy 79.750339 -450.756179) (xy 79.675494 -450.768238) (xy 79.59979 -450.772273) (xy 79.524086 -450.768238)
			(xy 79.449241 -450.756179) (xy 79.3761 -450.736233) (xy 79.305495 -450.708626) (xy 79.238224 -450.67367)
			(xy 79.175049 -450.631762) (xy 79.116687 -450.583376) (xy 79.063799 -450.52906) (xy 79.016984 -450.469431)
			(xy 78.976772 -450.405163) (xy 78.94362 -450.336986) (xy 78.917902 -450.26567) (xy 78.89991 -450.192025)
			(xy 78.889848 -450.116885) (xy 78.887829 -450.041101) (xy 77.771751 -450.041101) (xy 77.769732 -450.116885)
			(xy 77.75967 -450.192025) (xy 77.741678 -450.26567) (xy 77.71596 -450.336986) (xy 77.682808 -450.405163)
			(xy 77.642596 -450.469431) (xy 77.595781 -450.52906) (xy 77.542893 -450.583376) (xy 77.484531 -450.631762)
			(xy 77.421356 -450.67367) (xy 77.354085 -450.708626) (xy 77.28348 -450.736233) (xy 77.210339 -450.756179)
			(xy 77.135494 -450.768238) (xy 77.05979 -450.772273) (xy 76.984086 -450.768238) (xy 76.909241 -450.756179)
			(xy 76.8361 -450.736233) (xy 76.765495 -450.708626) (xy 76.698224 -450.67367) (xy 76.635049 -450.631762)
			(xy 76.576687 -450.583376) (xy 76.523799 -450.52906) (xy 76.476984 -450.469431) (xy 76.436772 -450.405163)
			(xy 76.40362 -450.336986) (xy 76.377902 -450.26567) (xy 76.35991 -450.192025) (xy 76.349848 -450.116885)
			(xy 76.347829 -450.041101) (xy 75.231751 -450.041101) (xy 75.229732 -450.116885) (xy 75.21967 -450.192025)
			(xy 75.201678 -450.26567) (xy 75.17596 -450.336986) (xy 75.142808 -450.405163) (xy 75.102596 -450.469431)
			(xy 75.055781 -450.52906) (xy 75.002893 -450.583376) (xy 74.944531 -450.631762) (xy 74.881356 -450.67367)
			(xy 74.814085 -450.708626) (xy 74.74348 -450.736233) (xy 74.670339 -450.756179) (xy 74.595494 -450.768238)
			(xy 74.51979 -450.772273) (xy 74.444086 -450.768238) (xy 74.369241 -450.756179) (xy 74.2961 -450.736233)
			(xy 74.225495 -450.708626) (xy 74.158224 -450.67367) (xy 74.095049 -450.631762) (xy 74.036687 -450.583376)
			(xy 73.983799 -450.52906) (xy 73.936984 -450.469431) (xy 73.896772 -450.405163) (xy 73.86362 -450.336986)
			(xy 73.837902 -450.26567) (xy 73.81991 -450.192025) (xy 73.809848 -450.116885) (xy 73.807829 -450.041101)
			(xy 72.691751 -450.041101) (xy 72.689732 -450.116885) (xy 72.67967 -450.192025) (xy 72.661678 -450.26567)
			(xy 72.63596 -450.336986) (xy 72.602808 -450.405163) (xy 72.562596 -450.469431) (xy 72.515781 -450.52906)
			(xy 72.462893 -450.583376) (xy 72.404531 -450.631762) (xy 72.341356 -450.67367) (xy 72.274085 -450.708626)
			(xy 72.20348 -450.736233) (xy 72.130339 -450.756179) (xy 72.055494 -450.768238) (xy 71.97979 -450.772273)
			(xy 71.904086 -450.768238) (xy 71.829241 -450.756179) (xy 71.7561 -450.736233) (xy 71.685495 -450.708626)
			(xy 71.618224 -450.67367) (xy 71.555049 -450.631762) (xy 71.496687 -450.583376) (xy 71.443799 -450.52906)
			(xy 71.396984 -450.469431) (xy 71.356772 -450.405163) (xy 71.32362 -450.336986) (xy 71.297902 -450.26567)
			(xy 71.27991 -450.192025) (xy 71.269848 -450.116885) (xy 71.267829 -450.041101) (xy 70.151751 -450.041101)
			(xy 70.149732 -450.116885) (xy 70.13967 -450.192025) (xy 70.121678 -450.26567) (xy 70.09596 -450.336986)
			(xy 70.062808 -450.405163) (xy 70.022596 -450.469431) (xy 69.975781 -450.52906) (xy 69.922893 -450.583376)
			(xy 69.864531 -450.631762) (xy 69.801356 -450.67367) (xy 69.734085 -450.708626) (xy 69.66348 -450.736233)
			(xy 69.590339 -450.756179) (xy 69.515494 -450.768238) (xy 69.43979 -450.772273) (xy 69.364086 -450.768238)
			(xy 69.289241 -450.756179) (xy 69.2161 -450.736233) (xy 69.145495 -450.708626) (xy 69.078224 -450.67367)
			(xy 69.015049 -450.631762) (xy 68.956687 -450.583376) (xy 68.903799 -450.52906) (xy 68.856984 -450.469431)
			(xy 68.816772 -450.405163) (xy 68.78362 -450.336986) (xy 68.757902 -450.26567) (xy 68.73991 -450.192025)
			(xy 68.729848 -450.116885) (xy 68.727829 -450.041101) (xy 67.611751 -450.041101) (xy 67.609732 -450.116885)
			(xy 67.59967 -450.192025) (xy 67.581678 -450.26567) (xy 67.55596 -450.336986) (xy 67.522808 -450.405163)
			(xy 67.482596 -450.469431) (xy 67.435781 -450.52906) (xy 67.382893 -450.583376) (xy 67.324531 -450.631762)
			(xy 67.261356 -450.67367) (xy 67.194085 -450.708626) (xy 67.12348 -450.736233) (xy 67.050339 -450.756179)
			(xy 66.975494 -450.768238) (xy 66.89979 -450.772273) (xy 66.824086 -450.768238) (xy 66.749241 -450.756179)
			(xy 66.6761 -450.736233) (xy 66.605495 -450.708626) (xy 66.538224 -450.67367) (xy 66.475049 -450.631762)
			(xy 66.416687 -450.583376) (xy 66.363799 -450.52906) (xy 66.316984 -450.469431) (xy 66.276772 -450.405163)
			(xy 66.24362 -450.336986) (xy 66.217902 -450.26567) (xy 66.19991 -450.192025) (xy 66.189848 -450.116885)
			(xy 66.187829 -450.041101) (xy 65.071751 -450.041101) (xy 65.069732 -450.116885) (xy 65.05967 -450.192025)
			(xy 65.041678 -450.26567) (xy 65.01596 -450.336986) (xy 64.982808 -450.405163) (xy 64.942596 -450.469431)
			(xy 64.895781 -450.52906) (xy 64.842893 -450.583376) (xy 64.784531 -450.631762) (xy 64.721356 -450.67367)
			(xy 64.654085 -450.708626) (xy 64.58348 -450.736233) (xy 64.510339 -450.756179) (xy 64.435494 -450.768238)
			(xy 64.35979 -450.772273) (xy 64.284086 -450.768238) (xy 64.209241 -450.756179) (xy 64.1361 -450.736233)
			(xy 64.065495 -450.708626) (xy 63.998224 -450.67367) (xy 63.935049 -450.631762) (xy 63.876687 -450.583376)
			(xy 63.823799 -450.52906) (xy 63.776984 -450.469431) (xy 63.736772 -450.405163) (xy 63.70362 -450.336986)
			(xy 63.677902 -450.26567) (xy 63.65991 -450.192025) (xy 63.649848 -450.116885) (xy 63.647829 -450.041101)
			(xy 42.474432 -450.041101) (xy 42.525324 -450.077542) (xy 42.614813 -450.151469) (xy 42.698988 -450.231395)
			(xy 42.777449 -450.316938) (xy 42.849821 -450.407689) (xy 42.91576 -450.503218) (xy 42.974951 -450.603068)
			(xy 43.027112 -450.706764) (xy 43.071995 -450.813811) (xy 43.109385 -450.9237) (xy 43.139105 -451.035907)
			(xy 43.161013 -451.149897) (xy 43.175004 -451.265126) (xy 43.181013 -451.381047) (xy 43.179009 -451.497105)
			(xy 43.169003 -451.612749) (xy 43.151043 -451.727427) (xy 43.125213 -451.840593) (xy 43.091638 -451.951707)
			(xy 43.06342 -452.026111) (xy 86.197949 -452.026111) (xy 86.203998 -451.950541) (xy 86.218045 -451.876043)
			(xy 86.239931 -451.80346) (xy 86.269408 -451.733614) (xy 86.306143 -451.667297) (xy 86.349718 -451.605261)
			(xy 86.39964 -451.548208) (xy 86.455344 -451.496784) (xy 86.516199 -451.451573) (xy 86.581514 -451.413086)
			(xy 86.65055 -451.38176) (xy 86.722525 -451.35795) (xy 86.796623 -451.341925) (xy 86.872004 -451.333866)
			(xy 86.90991 -451.333362) (xy 86.947816 -451.333866) (xy 87.023197 -451.341925) (xy 87.097295 -451.35795)
			(xy 87.16927 -451.38176) (xy 87.238306 -451.413086) (xy 87.303621 -451.451573) (xy 87.364476 -451.496784)
			(xy 87.42018 -451.548208) (xy 87.470102 -451.605261) (xy 87.513677 -451.667297) (xy 87.550412 -451.733614)
			(xy 87.579889 -451.80346) (xy 87.601775 -451.876043) (xy 87.615822 -451.950541) (xy 87.621871 -452.026111)
			(xy 88.737949 -452.026111) (xy 88.743998 -451.950541) (xy 88.758045 -451.876043) (xy 88.779931 -451.80346)
			(xy 88.809408 -451.733614) (xy 88.846143 -451.667297) (xy 88.889718 -451.605261) (xy 88.93964 -451.548208)
			(xy 88.995344 -451.496784) (xy 89.056199 -451.451573) (xy 89.121514 -451.413086) (xy 89.19055 -451.38176)
			(xy 89.262525 -451.35795) (xy 89.336623 -451.341925) (xy 89.412004 -451.333866) (xy 89.44991 -451.333362)
			(xy 89.487816 -451.333866) (xy 89.563197 -451.341925) (xy 89.637295 -451.35795) (xy 89.70927 -451.38176)
			(xy 89.778306 -451.413086) (xy 89.843621 -451.451573) (xy 89.904476 -451.496784) (xy 89.96018 -451.548208)
			(xy 90.010102 -451.605261) (xy 90.053677 -451.667297) (xy 90.090412 -451.733614) (xy 90.119889 -451.80346)
			(xy 90.141775 -451.876043) (xy 90.155822 -451.950541) (xy 90.161871 -452.026111) (xy 91.277949 -452.026111)
			(xy 91.283998 -451.950541) (xy 91.298045 -451.876043) (xy 91.319931 -451.80346) (xy 91.349408 -451.733614)
			(xy 91.386143 -451.667297) (xy 91.429718 -451.605261) (xy 91.47964 -451.548208) (xy 91.535344 -451.496784)
			(xy 91.596199 -451.451573) (xy 91.661514 -451.413086) (xy 91.73055 -451.38176) (xy 91.802525 -451.35795)
			(xy 91.876623 -451.341925) (xy 91.952004 -451.333866) (xy 91.98991 -451.333362) (xy 92.027816 -451.333866)
			(xy 92.103197 -451.341925) (xy 92.177295 -451.35795) (xy 92.24927 -451.38176) (xy 92.318306 -451.413086)
			(xy 92.383621 -451.451573) (xy 92.444476 -451.496784) (xy 92.50018 -451.548208) (xy 92.550102 -451.605261)
			(xy 92.593677 -451.667297) (xy 92.630412 -451.733614) (xy 92.659889 -451.80346) (xy 92.681775 -451.876043)
			(xy 92.695822 -451.950541) (xy 92.701871 -452.026111) (xy 92.699852 -452.101895) (xy 92.68979 -452.177035)
			(xy 92.671798 -452.25068) (xy 92.64608 -452.321996) (xy 92.612928 -452.390173) (xy 92.572716 -452.454441)
			(xy 92.525901 -452.51407) (xy 92.473013 -452.568386) (xy 92.414651 -452.616772) (xy 92.351476 -452.65868)
			(xy 92.284205 -452.693636) (xy 92.2136 -452.721243) (xy 92.177855 -452.730991) (xy 93.154757 -452.730991)
			(xy 93.160779 -452.614808) (xy 93.174802 -452.499317) (xy 93.19676 -452.385069) (xy 93.226547 -452.272608)
			(xy 93.264022 -452.16247) (xy 93.309007 -452.05518) (xy 93.361286 -451.951249) (xy 93.420611 -451.851173)
			(xy 93.486699 -451.755427) (xy 93.559235 -451.66447) (xy 93.637874 -451.578734) (xy 93.72224 -451.498627)
			(xy 93.811932 -451.424531) (xy 93.906522 -451.356801) (xy 94.00556 -451.295757) (xy 94.108573 -451.241692)
			(xy 94.21507 -451.194862) (xy 94.324545 -451.155491) (xy 94.436475 -451.123767) (xy 94.550327 -451.099841)
			(xy 94.665559 -451.083827) (xy 94.781621 -451.0758) (xy 94.83979 -451.075298) (xy 94.897959 -451.0758)
			(xy 95.014021 -451.083827) (xy 95.129253 -451.099841) (xy 95.243105 -451.123767) (xy 95.355035 -451.155491)
			(xy 95.46451 -451.194862) (xy 95.571007 -451.241692) (xy 95.67402 -451.295757) (xy 95.773058 -451.356801)
			(xy 95.867648 -451.424531) (xy 95.95734 -451.498627) (xy 96.041706 -451.578734) (xy 96.120345 -451.66447)
			(xy 96.192881 -451.755427) (xy 96.258969 -451.851173) (xy 96.318294 -451.951249) (xy 96.370573 -452.05518)
			(xy 96.415558 -452.16247) (xy 96.453033 -452.272608) (xy 96.48282 -452.385069) (xy 96.504778 -452.499317)
			(xy 96.518801 -452.614808) (xy 96.524823 -452.730991) (xy 96.522815 -452.847313) (xy 96.512786 -452.963219)
			(xy 96.494785 -453.078156) (xy 96.468897 -453.191579) (xy 96.435246 -453.302944) (xy 96.393992 -453.411723)
			(xy 96.345331 -453.517397) (xy 96.289495 -453.619461) (xy 96.226752 -453.71743) (xy 96.157398 -453.810837)
			(xy 96.081766 -453.899237) (xy 96.000215 -453.982208) (xy 95.913134 -454.059355) (xy 95.820938 -454.13031)
			(xy 95.724066 -454.194736) (xy 95.622981 -454.252325) (xy 95.518163 -454.302802) (xy 95.410112 -454.345928)
			(xy 95.299344 -454.381497) (xy 95.186385 -454.409339) (xy 95.071775 -454.429321) (xy 94.95606 -454.441348)
			(xy 94.83979 -454.445364) (xy 94.72352 -454.441348) (xy 94.607805 -454.429321) (xy 94.493195 -454.409339)
			(xy 94.380236 -454.381497) (xy 94.269468 -454.345928) (xy 94.161417 -454.302802) (xy 94.056599 -454.252325)
			(xy 93.955514 -454.194736) (xy 93.858642 -454.13031) (xy 93.766446 -454.059355) (xy 93.679365 -453.982208)
			(xy 93.597814 -453.899237) (xy 93.522182 -453.810837) (xy 93.452828 -453.71743) (xy 93.390085 -453.619461)
			(xy 93.334249 -453.517397) (xy 93.285588 -453.411723) (xy 93.244334 -453.302944) (xy 93.210683 -453.191579)
			(xy 93.184795 -453.078156) (xy 93.166794 -452.963219) (xy 93.156765 -452.847313) (xy 93.154757 -452.730991)
			(xy 92.177855 -452.730991) (xy 92.140459 -452.741189) (xy 92.065614 -452.753248) (xy 91.98991 -452.757283)
			(xy 91.914206 -452.753248) (xy 91.839361 -452.741189) (xy 91.76622 -452.721243) (xy 91.695615 -452.693636)
			(xy 91.628344 -452.65868) (xy 91.565169 -452.616772) (xy 91.506807 -452.568386) (xy 91.453919 -452.51407)
			(xy 91.407104 -452.454441) (xy 91.366892 -452.390173) (xy 91.33374 -452.321996) (xy 91.308022 -452.25068)
			(xy 91.29003 -452.177035) (xy 91.279968 -452.101895) (xy 91.277949 -452.026111) (xy 90.161871 -452.026111)
			(xy 90.159852 -452.101895) (xy 90.14979 -452.177035) (xy 90.131798 -452.25068) (xy 90.10608 -452.321996)
			(xy 90.072928 -452.390173) (xy 90.032716 -452.454441) (xy 89.985901 -452.51407) (xy 89.933013 -452.568386)
			(xy 89.874651 -452.616772) (xy 89.811476 -452.65868) (xy 89.744205 -452.693636) (xy 89.6736 -452.721243)
			(xy 89.600459 -452.741189) (xy 89.525614 -452.753248) (xy 89.44991 -452.757283) (xy 89.374206 -452.753248)
			(xy 89.299361 -452.741189) (xy 89.22622 -452.721243) (xy 89.155615 -452.693636) (xy 89.088344 -452.65868)
			(xy 89.025169 -452.616772) (xy 88.966807 -452.568386) (xy 88.913919 -452.51407) (xy 88.867104 -452.454441)
			(xy 88.826892 -452.390173) (xy 88.79374 -452.321996) (xy 88.768022 -452.25068) (xy 88.75003 -452.177035)
			(xy 88.739968 -452.101895) (xy 88.737949 -452.026111) (xy 87.621871 -452.026111) (xy 87.619852 -452.101895)
			(xy 87.60979 -452.177035) (xy 87.591798 -452.25068) (xy 87.56608 -452.321996) (xy 87.532928 -452.390173)
			(xy 87.492716 -452.454441) (xy 87.445901 -452.51407) (xy 87.393013 -452.568386) (xy 87.334651 -452.616772)
			(xy 87.271476 -452.65868) (xy 87.204205 -452.693636) (xy 87.1336 -452.721243) (xy 87.060459 -452.741189)
			(xy 86.985614 -452.753248) (xy 86.90991 -452.757283) (xy 86.834206 -452.753248) (xy 86.759361 -452.741189)
			(xy 86.68622 -452.721243) (xy 86.615615 -452.693636) (xy 86.548344 -452.65868) (xy 86.485169 -452.616772)
			(xy 86.426807 -452.568386) (xy 86.373919 -452.51407) (xy 86.327104 -452.454441) (xy 86.286892 -452.390173)
			(xy 86.25374 -452.321996) (xy 86.228022 -452.25068) (xy 86.21003 -452.177035) (xy 86.199968 -452.101895)
			(xy 86.197949 -452.026111) (xy 43.06342 -452.026111) (xy 43.050477 -452.06024) (xy 43.001926 -452.165674)
			(xy 42.946217 -452.267508) (xy 42.883615 -452.365256) (xy 42.814419 -452.458451) (xy 42.738957 -452.546651)
			(xy 42.65759 -452.629434) (xy 42.570706 -452.706407) (xy 42.525601 -452.741121) (xy 63.647829 -452.741121)
			(xy 63.653878 -452.665551) (xy 63.667925 -452.591053) (xy 63.689811 -452.51847) (xy 63.719288 -452.448624)
			(xy 63.756023 -452.382307) (xy 63.799598 -452.320271) (xy 63.84952 -452.263218) (xy 63.905224 -452.211794)
			(xy 63.966079 -452.166583) (xy 64.031394 -452.128096) (xy 64.10043 -452.09677) (xy 64.172405 -452.07296)
			(xy 64.246503 -452.056935) (xy 64.321884 -452.048876) (xy 64.35979 -452.048372) (xy 64.397696 -452.048876)
			(xy 64.473077 -452.056935) (xy 64.547175 -452.07296) (xy 64.61915 -452.09677) (xy 64.688186 -452.128096)
			(xy 64.753501 -452.166583) (xy 64.814356 -452.211794) (xy 64.87006 -452.263218) (xy 64.919982 -452.320271)
			(xy 64.963557 -452.382307) (xy 65.000292 -452.448624) (xy 65.029769 -452.51847) (xy 65.051655 -452.591053)
			(xy 65.065702 -452.665551) (xy 65.071751 -452.741121) (xy 66.187829 -452.741121) (xy 66.193878 -452.665551)
			(xy 66.207925 -452.591053) (xy 66.229811 -452.51847) (xy 66.259288 -452.448624) (xy 66.296023 -452.382307)
			(xy 66.339598 -452.320271) (xy 66.38952 -452.263218) (xy 66.445224 -452.211794) (xy 66.506079 -452.166583)
			(xy 66.571394 -452.128096) (xy 66.64043 -452.09677) (xy 66.712405 -452.07296) (xy 66.786503 -452.056935)
			(xy 66.861884 -452.048876) (xy 66.89979 -452.048372) (xy 66.937696 -452.048876) (xy 67.013077 -452.056935)
			(xy 67.087175 -452.07296) (xy 67.15915 -452.09677) (xy 67.228186 -452.128096) (xy 67.293501 -452.166583)
			(xy 67.354356 -452.211794) (xy 67.41006 -452.263218) (xy 67.459982 -452.320271) (xy 67.503557 -452.382307)
			(xy 67.540292 -452.448624) (xy 67.569769 -452.51847) (xy 67.591655 -452.591053) (xy 67.605702 -452.665551)
			(xy 67.611751 -452.741121) (xy 68.727829 -452.741121) (xy 68.733878 -452.665551) (xy 68.747925 -452.591053)
			(xy 68.769811 -452.51847) (xy 68.799288 -452.448624) (xy 68.836023 -452.382307) (xy 68.879598 -452.320271)
			(xy 68.92952 -452.263218) (xy 68.985224 -452.211794) (xy 69.046079 -452.166583) (xy 69.111394 -452.128096)
			(xy 69.18043 -452.09677) (xy 69.252405 -452.07296) (xy 69.326503 -452.056935) (xy 69.401884 -452.048876)
			(xy 69.43979 -452.048372) (xy 69.477696 -452.048876) (xy 69.553077 -452.056935) (xy 69.627175 -452.07296)
			(xy 69.69915 -452.09677) (xy 69.768186 -452.128096) (xy 69.833501 -452.166583) (xy 69.894356 -452.211794)
			(xy 69.95006 -452.263218) (xy 69.999982 -452.320271) (xy 70.043557 -452.382307) (xy 70.080292 -452.448624)
			(xy 70.109769 -452.51847) (xy 70.131655 -452.591053) (xy 70.145702 -452.665551) (xy 70.151751 -452.741121)
			(xy 71.267829 -452.741121) (xy 71.273878 -452.665551) (xy 71.287925 -452.591053) (xy 71.309811 -452.51847)
			(xy 71.339288 -452.448624) (xy 71.376023 -452.382307) (xy 71.419598 -452.320271) (xy 71.46952 -452.263218)
			(xy 71.525224 -452.211794) (xy 71.586079 -452.166583) (xy 71.651394 -452.128096) (xy 71.72043 -452.09677)
			(xy 71.792405 -452.07296) (xy 71.866503 -452.056935) (xy 71.941884 -452.048876) (xy 71.97979 -452.048372)
			(xy 72.017696 -452.048876) (xy 72.093077 -452.056935) (xy 72.167175 -452.07296) (xy 72.23915 -452.09677)
			(xy 72.308186 -452.128096) (xy 72.373501 -452.166583) (xy 72.434356 -452.211794) (xy 72.49006 -452.263218)
			(xy 72.539982 -452.320271) (xy 72.583557 -452.382307) (xy 72.620292 -452.448624) (xy 72.649769 -452.51847)
			(xy 72.671655 -452.591053) (xy 72.685702 -452.665551) (xy 72.691751 -452.741121) (xy 73.807829 -452.741121)
			(xy 73.813878 -452.665551) (xy 73.827925 -452.591053) (xy 73.849811 -452.51847) (xy 73.879288 -452.448624)
			(xy 73.916023 -452.382307) (xy 73.959598 -452.320271) (xy 74.00952 -452.263218) (xy 74.065224 -452.211794)
			(xy 74.126079 -452.166583) (xy 74.191394 -452.128096) (xy 74.26043 -452.09677) (xy 74.332405 -452.07296)
			(xy 74.406503 -452.056935) (xy 74.481884 -452.048876) (xy 74.51979 -452.048372) (xy 74.557696 -452.048876)
			(xy 74.633077 -452.056935) (xy 74.707175 -452.07296) (xy 74.77915 -452.09677) (xy 74.848186 -452.128096)
			(xy 74.913501 -452.166583) (xy 74.974356 -452.211794) (xy 75.03006 -452.263218) (xy 75.079982 -452.320271)
			(xy 75.123557 -452.382307) (xy 75.160292 -452.448624) (xy 75.189769 -452.51847) (xy 75.211655 -452.591053)
			(xy 75.225702 -452.665551) (xy 75.231751 -452.741121) (xy 76.347829 -452.741121) (xy 76.353878 -452.665551)
			(xy 76.367925 -452.591053) (xy 76.389811 -452.51847) (xy 76.419288 -452.448624) (xy 76.456023 -452.382307)
			(xy 76.499598 -452.320271) (xy 76.54952 -452.263218) (xy 76.605224 -452.211794) (xy 76.666079 -452.166583)
			(xy 76.731394 -452.128096) (xy 76.80043 -452.09677) (xy 76.872405 -452.07296) (xy 76.946503 -452.056935)
			(xy 77.021884 -452.048876) (xy 77.05979 -452.048372) (xy 77.097696 -452.048876) (xy 77.173077 -452.056935)
			(xy 77.247175 -452.07296) (xy 77.31915 -452.09677) (xy 77.388186 -452.128096) (xy 77.453501 -452.166583)
			(xy 77.514356 -452.211794) (xy 77.57006 -452.263218) (xy 77.619982 -452.320271) (xy 77.663557 -452.382307)
			(xy 77.700292 -452.448624) (xy 77.729769 -452.51847) (xy 77.751655 -452.591053) (xy 77.765702 -452.665551)
			(xy 77.771751 -452.741121) (xy 78.887829 -452.741121) (xy 78.893878 -452.665551) (xy 78.907925 -452.591053)
			(xy 78.929811 -452.51847) (xy 78.959288 -452.448624) (xy 78.996023 -452.382307) (xy 79.039598 -452.320271)
			(xy 79.08952 -452.263218) (xy 79.145224 -452.211794) (xy 79.206079 -452.166583) (xy 79.271394 -452.128096)
			(xy 79.34043 -452.09677) (xy 79.412405 -452.07296) (xy 79.486503 -452.056935) (xy 79.561884 -452.048876)
			(xy 79.59979 -452.048372) (xy 79.637696 -452.048876) (xy 79.713077 -452.056935) (xy 79.787175 -452.07296)
			(xy 79.85915 -452.09677) (xy 79.928186 -452.128096) (xy 79.993501 -452.166583) (xy 80.054356 -452.211794)
			(xy 80.11006 -452.263218) (xy 80.159982 -452.320271) (xy 80.203557 -452.382307) (xy 80.240292 -452.448624)
			(xy 80.269769 -452.51847) (xy 80.291655 -452.591053) (xy 80.305702 -452.665551) (xy 80.311751 -452.741121)
			(xy 81.427829 -452.741121) (xy 81.433878 -452.665551) (xy 81.447925 -452.591053) (xy 81.469811 -452.51847)
			(xy 81.499288 -452.448624) (xy 81.536023 -452.382307) (xy 81.579598 -452.320271) (xy 81.62952 -452.263218)
			(xy 81.685224 -452.211794) (xy 81.746079 -452.166583) (xy 81.811394 -452.128096) (xy 81.88043 -452.09677)
			(xy 81.952405 -452.07296) (xy 82.026503 -452.056935) (xy 82.101884 -452.048876) (xy 82.13979 -452.048372)
			(xy 82.177696 -452.048876) (xy 82.253077 -452.056935) (xy 82.327175 -452.07296) (xy 82.39915 -452.09677)
			(xy 82.468186 -452.128096) (xy 82.533501 -452.166583) (xy 82.594356 -452.211794) (xy 82.65006 -452.263218)
			(xy 82.699982 -452.320271) (xy 82.743557 -452.382307) (xy 82.780292 -452.448624) (xy 82.809769 -452.51847)
			(xy 82.831655 -452.591053) (xy 82.845702 -452.665551) (xy 82.851751 -452.741121) (xy 82.849732 -452.816905)
			(xy 82.83967 -452.892045) (xy 82.821678 -452.96569) (xy 82.79596 -453.037006) (xy 82.762808 -453.105183)
			(xy 82.722596 -453.169451) (xy 82.675781 -453.22908) (xy 82.622893 -453.283396) (xy 82.607556 -453.296111)
			(xy 84.927949 -453.296111) (xy 84.933998 -453.220541) (xy 84.948045 -453.146043) (xy 84.969931 -453.07346)
			(xy 84.999408 -453.003614) (xy 85.036143 -452.937297) (xy 85.079718 -452.875261) (xy 85.12964 -452.818208)
			(xy 85.185344 -452.766784) (xy 85.246199 -452.721573) (xy 85.311514 -452.683086) (xy 85.38055 -452.65176)
			(xy 85.452525 -452.62795) (xy 85.526623 -452.611925) (xy 85.602004 -452.603866) (xy 85.63991 -452.603362)
			(xy 85.677816 -452.603866) (xy 85.753197 -452.611925) (xy 85.827295 -452.62795) (xy 85.89927 -452.65176)
			(xy 85.968306 -452.683086) (xy 86.033621 -452.721573) (xy 86.094476 -452.766784) (xy 86.15018 -452.818208)
			(xy 86.200102 -452.875261) (xy 86.243677 -452.937297) (xy 86.280412 -453.003614) (xy 86.309889 -453.07346)
			(xy 86.331775 -453.146043) (xy 86.345822 -453.220541) (xy 86.351871 -453.296111) (xy 87.467949 -453.296111)
			(xy 87.473998 -453.220541) (xy 87.488045 -453.146043) (xy 87.509931 -453.07346) (xy 87.539408 -453.003614)
			(xy 87.576143 -452.937297) (xy 87.619718 -452.875261) (xy 87.66964 -452.818208) (xy 87.725344 -452.766784)
			(xy 87.786199 -452.721573) (xy 87.851514 -452.683086) (xy 87.92055 -452.65176) (xy 87.992525 -452.62795)
			(xy 88.066623 -452.611925) (xy 88.142004 -452.603866) (xy 88.17991 -452.603362) (xy 88.217816 -452.603866)
			(xy 88.293197 -452.611925) (xy 88.367295 -452.62795) (xy 88.43927 -452.65176) (xy 88.508306 -452.683086)
			(xy 88.573621 -452.721573) (xy 88.634476 -452.766784) (xy 88.69018 -452.818208) (xy 88.740102 -452.875261)
			(xy 88.783677 -452.937297) (xy 88.820412 -453.003614) (xy 88.849889 -453.07346) (xy 88.871775 -453.146043)
			(xy 88.885822 -453.220541) (xy 88.891871 -453.296111) (xy 90.007949 -453.296111) (xy 90.013998 -453.220541)
			(xy 90.028045 -453.146043) (xy 90.049931 -453.07346) (xy 90.079408 -453.003614) (xy 90.116143 -452.937297)
			(xy 90.159718 -452.875261) (xy 90.20964 -452.818208) (xy 90.265344 -452.766784) (xy 90.326199 -452.721573)
			(xy 90.391514 -452.683086) (xy 90.46055 -452.65176) (xy 90.532525 -452.62795) (xy 90.606623 -452.611925)
			(xy 90.682004 -452.603866) (xy 90.71991 -452.603362) (xy 90.757816 -452.603866) (xy 90.833197 -452.611925)
			(xy 90.907295 -452.62795) (xy 90.97927 -452.65176) (xy 91.048306 -452.683086) (xy 91.113621 -452.721573)
			(xy 91.174476 -452.766784) (xy 91.23018 -452.818208) (xy 91.280102 -452.875261) (xy 91.323677 -452.937297)
			(xy 91.360412 -453.003614) (xy 91.389889 -453.07346) (xy 91.411775 -453.146043) (xy 91.425822 -453.220541)
			(xy 91.431871 -453.296111) (xy 91.429852 -453.371895) (xy 91.41979 -453.447035) (xy 91.401798 -453.52068)
			(xy 91.37608 -453.591996) (xy 91.342928 -453.660173) (xy 91.302716 -453.724441) (xy 91.255901 -453.78407)
			(xy 91.203013 -453.838386) (xy 91.144651 -453.886772) (xy 91.081476 -453.92868) (xy 91.014205 -453.963636)
			(xy 90.9436 -453.991243) (xy 90.870459 -454.011189) (xy 90.795614 -454.023248) (xy 90.71991 -454.027283)
			(xy 90.644206 -454.023248) (xy 90.569361 -454.011189) (xy 90.49622 -453.991243) (xy 90.425615 -453.963636)
			(xy 90.358344 -453.92868) (xy 90.295169 -453.886772) (xy 90.236807 -453.838386) (xy 90.183919 -453.78407)
			(xy 90.137104 -453.724441) (xy 90.096892 -453.660173) (xy 90.06374 -453.591996) (xy 90.038022 -453.52068)
			(xy 90.02003 -453.447035) (xy 90.009968 -453.371895) (xy 90.007949 -453.296111) (xy 88.891871 -453.296111)
			(xy 88.889852 -453.371895) (xy 88.87979 -453.447035) (xy 88.861798 -453.52068) (xy 88.83608 -453.591996)
			(xy 88.802928 -453.660173) (xy 88.762716 -453.724441) (xy 88.715901 -453.78407) (xy 88.663013 -453.838386)
			(xy 88.604651 -453.886772) (xy 88.541476 -453.92868) (xy 88.474205 -453.963636) (xy 88.4036 -453.991243)
			(xy 88.330459 -454.011189) (xy 88.255614 -454.023248) (xy 88.17991 -454.027283) (xy 88.104206 -454.023248)
			(xy 88.029361 -454.011189) (xy 87.95622 -453.991243) (xy 87.885615 -453.963636) (xy 87.818344 -453.92868)
			(xy 87.755169 -453.886772) (xy 87.696807 -453.838386) (xy 87.643919 -453.78407) (xy 87.597104 -453.724441)
			(xy 87.556892 -453.660173) (xy 87.52374 -453.591996) (xy 87.498022 -453.52068) (xy 87.48003 -453.447035)
			(xy 87.469968 -453.371895) (xy 87.467949 -453.296111) (xy 86.351871 -453.296111) (xy 86.349852 -453.371895)
			(xy 86.33979 -453.447035) (xy 86.321798 -453.52068) (xy 86.29608 -453.591996) (xy 86.262928 -453.660173)
			(xy 86.222716 -453.724441) (xy 86.175901 -453.78407) (xy 86.123013 -453.838386) (xy 86.064651 -453.886772)
			(xy 86.001476 -453.92868) (xy 85.934205 -453.963636) (xy 85.8636 -453.991243) (xy 85.790459 -454.011189)
			(xy 85.715614 -454.023248) (xy 85.63991 -454.027283) (xy 85.564206 -454.023248) (xy 85.489361 -454.011189)
			(xy 85.41622 -453.991243) (xy 85.345615 -453.963636) (xy 85.278344 -453.92868) (xy 85.215169 -453.886772)
			(xy 85.156807 -453.838386) (xy 85.103919 -453.78407) (xy 85.057104 -453.724441) (xy 85.016892 -453.660173)
			(xy 84.98374 -453.591996) (xy 84.958022 -453.52068) (xy 84.94003 -453.447035) (xy 84.929968 -453.371895)
			(xy 84.927949 -453.296111) (xy 82.607556 -453.296111) (xy 82.564531 -453.331782) (xy 82.501356 -453.37369)
			(xy 82.434085 -453.408646) (xy 82.36348 -453.436253) (xy 82.290339 -453.456199) (xy 82.215494 -453.468258)
			(xy 82.13979 -453.472293) (xy 82.064086 -453.468258) (xy 81.989241 -453.456199) (xy 81.9161 -453.436253)
			(xy 81.845495 -453.408646) (xy 81.778224 -453.37369) (xy 81.715049 -453.331782) (xy 81.656687 -453.283396)
			(xy 81.603799 -453.22908) (xy 81.556984 -453.169451) (xy 81.516772 -453.105183) (xy 81.48362 -453.037006)
			(xy 81.457902 -452.96569) (xy 81.43991 -452.892045) (xy 81.429848 -452.816905) (xy 81.427829 -452.741121)
			(xy 80.311751 -452.741121) (xy 80.309732 -452.816905) (xy 80.29967 -452.892045) (xy 80.281678 -452.96569)
			(xy 80.25596 -453.037006) (xy 80.222808 -453.105183) (xy 80.182596 -453.169451) (xy 80.135781 -453.22908)
			(xy 80.082893 -453.283396) (xy 80.024531 -453.331782) (xy 79.961356 -453.37369) (xy 79.894085 -453.408646)
			(xy 79.82348 -453.436253) (xy 79.750339 -453.456199) (xy 79.675494 -453.468258) (xy 79.59979 -453.472293)
			(xy 79.524086 -453.468258) (xy 79.449241 -453.456199) (xy 79.3761 -453.436253) (xy 79.305495 -453.408646)
			(xy 79.238224 -453.37369) (xy 79.175049 -453.331782) (xy 79.116687 -453.283396) (xy 79.063799 -453.22908)
			(xy 79.016984 -453.169451) (xy 78.976772 -453.105183) (xy 78.94362 -453.037006) (xy 78.917902 -452.96569)
			(xy 78.89991 -452.892045) (xy 78.889848 -452.816905) (xy 78.887829 -452.741121) (xy 77.771751 -452.741121)
			(xy 77.769732 -452.816905) (xy 77.75967 -452.892045) (xy 77.741678 -452.96569) (xy 77.71596 -453.037006)
			(xy 77.682808 -453.105183) (xy 77.642596 -453.169451) (xy 77.595781 -453.22908) (xy 77.542893 -453.283396)
			(xy 77.484531 -453.331782) (xy 77.421356 -453.37369) (xy 77.354085 -453.408646) (xy 77.28348 -453.436253)
			(xy 77.210339 -453.456199) (xy 77.135494 -453.468258) (xy 77.05979 -453.472293) (xy 76.984086 -453.468258)
			(xy 76.909241 -453.456199) (xy 76.8361 -453.436253) (xy 76.765495 -453.408646) (xy 76.698224 -453.37369)
			(xy 76.635049 -453.331782) (xy 76.576687 -453.283396) (xy 76.523799 -453.22908) (xy 76.476984 -453.169451)
			(xy 76.436772 -453.105183) (xy 76.40362 -453.037006) (xy 76.377902 -452.96569) (xy 76.35991 -452.892045)
			(xy 76.349848 -452.816905) (xy 76.347829 -452.741121) (xy 75.231751 -452.741121) (xy 75.229732 -452.816905)
			(xy 75.21967 -452.892045) (xy 75.201678 -452.96569) (xy 75.17596 -453.037006) (xy 75.142808 -453.105183)
			(xy 75.102596 -453.169451) (xy 75.055781 -453.22908) (xy 75.002893 -453.283396) (xy 74.944531 -453.331782)
			(xy 74.881356 -453.37369) (xy 74.814085 -453.408646) (xy 74.74348 -453.436253) (xy 74.670339 -453.456199)
			(xy 74.595494 -453.468258) (xy 74.51979 -453.472293) (xy 74.444086 -453.468258) (xy 74.369241 -453.456199)
			(xy 74.2961 -453.436253) (xy 74.225495 -453.408646) (xy 74.158224 -453.37369) (xy 74.095049 -453.331782)
			(xy 74.036687 -453.283396) (xy 73.983799 -453.22908) (xy 73.936984 -453.169451) (xy 73.896772 -453.105183)
			(xy 73.86362 -453.037006) (xy 73.837902 -452.96569) (xy 73.81991 -452.892045) (xy 73.809848 -452.816905)
			(xy 73.807829 -452.741121) (xy 72.691751 -452.741121) (xy 72.689732 -452.816905) (xy 72.67967 -452.892045)
			(xy 72.661678 -452.96569) (xy 72.63596 -453.037006) (xy 72.602808 -453.105183) (xy 72.562596 -453.169451)
			(xy 72.515781 -453.22908) (xy 72.462893 -453.283396) (xy 72.404531 -453.331782) (xy 72.341356 -453.37369)
			(xy 72.274085 -453.408646) (xy 72.20348 -453.436253) (xy 72.130339 -453.456199) (xy 72.055494 -453.468258)
			(xy 71.97979 -453.472293) (xy 71.904086 -453.468258) (xy 71.829241 -453.456199) (xy 71.7561 -453.436253)
			(xy 71.685495 -453.408646) (xy 71.618224 -453.37369) (xy 71.555049 -453.331782) (xy 71.496687 -453.283396)
			(xy 71.443799 -453.22908) (xy 71.396984 -453.169451) (xy 71.356772 -453.105183) (xy 71.32362 -453.037006)
			(xy 71.297902 -452.96569) (xy 71.27991 -452.892045) (xy 71.269848 -452.816905) (xy 71.267829 -452.741121)
			(xy 70.151751 -452.741121) (xy 70.149732 -452.816905) (xy 70.13967 -452.892045) (xy 70.121678 -452.96569)
			(xy 70.09596 -453.037006) (xy 70.062808 -453.105183) (xy 70.022596 -453.169451) (xy 69.975781 -453.22908)
			(xy 69.922893 -453.283396) (xy 69.864531 -453.331782) (xy 69.801356 -453.37369) (xy 69.734085 -453.408646)
			(xy 69.66348 -453.436253) (xy 69.590339 -453.456199) (xy 69.515494 -453.468258) (xy 69.43979 -453.472293)
			(xy 69.364086 -453.468258) (xy 69.289241 -453.456199) (xy 69.2161 -453.436253) (xy 69.145495 -453.408646)
			(xy 69.078224 -453.37369) (xy 69.015049 -453.331782) (xy 68.956687 -453.283396) (xy 68.903799 -453.22908)
			(xy 68.856984 -453.169451) (xy 68.816772 -453.105183) (xy 68.78362 -453.037006) (xy 68.757902 -452.96569)
			(xy 68.73991 -452.892045) (xy 68.729848 -452.816905) (xy 68.727829 -452.741121) (xy 67.611751 -452.741121)
			(xy 67.609732 -452.816905) (xy 67.59967 -452.892045) (xy 67.581678 -452.96569) (xy 67.55596 -453.037006)
			(xy 67.522808 -453.105183) (xy 67.482596 -453.169451) (xy 67.435781 -453.22908) (xy 67.382893 -453.283396)
			(xy 67.324531 -453.331782) (xy 67.261356 -453.37369) (xy 67.194085 -453.408646) (xy 67.12348 -453.436253)
			(xy 67.050339 -453.456199) (xy 66.975494 -453.468258) (xy 66.89979 -453.472293) (xy 66.824086 -453.468258)
			(xy 66.749241 -453.456199) (xy 66.6761 -453.436253) (xy 66.605495 -453.408646) (xy 66.538224 -453.37369)
			(xy 66.475049 -453.331782) (xy 66.416687 -453.283396) (xy 66.363799 -453.22908) (xy 66.316984 -453.169451)
			(xy 66.276772 -453.105183) (xy 66.24362 -453.037006) (xy 66.217902 -452.96569) (xy 66.19991 -452.892045)
			(xy 66.189848 -452.816905) (xy 66.187829 -452.741121) (xy 65.071751 -452.741121) (xy 65.069732 -452.816905)
			(xy 65.05967 -452.892045) (xy 65.041678 -452.96569) (xy 65.01596 -453.037006) (xy 64.982808 -453.105183)
			(xy 64.942596 -453.169451) (xy 64.895781 -453.22908) (xy 64.842893 -453.283396) (xy 64.784531 -453.331782)
			(xy 64.721356 -453.37369) (xy 64.654085 -453.408646) (xy 64.58348 -453.436253) (xy 64.510339 -453.456199)
			(xy 64.435494 -453.468258) (xy 64.35979 -453.472293) (xy 64.284086 -453.468258) (xy 64.209241 -453.456199)
			(xy 64.1361 -453.436253) (xy 64.065495 -453.408646) (xy 63.998224 -453.37369) (xy 63.935049 -453.331782)
			(xy 63.876687 -453.283396) (xy 63.823799 -453.22908) (xy 63.776984 -453.169451) (xy 63.736772 -453.105183)
			(xy 63.70362 -453.037006) (xy 63.677902 -452.96569) (xy 63.65991 -452.892045) (xy 63.649848 -452.816905)
			(xy 63.647829 -452.741121) (xy 42.525601 -452.741121) (xy 42.478719 -452.777202) (xy 42.382066 -452.841482)
			(xy 42.281209 -452.89894) (xy 42.176629 -452.949304) (xy 42.068822 -452.992332) (xy 41.958305 -453.02782)
			(xy 41.845602 -453.055599) (xy 41.731251 -453.075536) (xy 41.615797 -453.087537) (xy 41.49979 -453.091543)
			(xy 41.383783 -453.087537) (xy 41.268329 -453.075536) (xy 41.153978 -453.055599) (xy 41.041275 -453.02782)
			(xy 40.930758 -452.992332) (xy 40.822951 -452.949304) (xy 40.718371 -452.89894) (xy 40.617514 -452.841482)
			(xy 40.520861 -452.777202) (xy 40.428874 -452.706407) (xy 40.34199 -452.629434) (xy 40.260623 -452.546651)
			(xy 40.185161 -452.458451) (xy 40.115965 -452.365256) (xy 40.053363 -452.267508) (xy 39.997654 -452.165674)
			(xy 39.949103 -452.06024) (xy 39.907942 -451.951707) (xy 39.874367 -451.840593) (xy 39.848537 -451.727427)
			(xy 39.830577 -451.612749) (xy 39.820571 -451.497105) (xy 39.818567 -451.381047) (xy 37.580824 -451.381047)
			(xy 37.580824 -456.176634) (xy 36.676838 -457.08062) (xy 36.467034 -457.08062) (xy 36.405058 -457.119736)
			(xy 36.38931 -457.15301) (xy 36.3703 -457.19193) (xy 36.326134 -457.266449) (xy 36.275302 -457.33659)
			(xy 36.218235 -457.401759) (xy 36.179535 -457.438502) (xy 39.28159 -457.438502) (xy 39.28159 -457.378566)
			(xy 39.289413 -457.319144) (xy 39.304926 -457.261251) (xy 39.327862 -457.205878) (xy 39.357829 -457.153972)
			(xy 39.394316 -457.106422) (xy 39.436696 -457.064042) (xy 39.484246 -457.027555) (xy 39.536152 -456.997588)
			(xy 39.591525 -456.974652) (xy 39.649418 -456.959139) (xy 39.70884 -456.951316) (xy 39.738808 -456.950826)
			(xy 39.768776 -456.951316) (xy 39.828198 -456.959139) (xy 39.886091 -456.974652) (xy 39.941464 -456.997588)
			(xy 39.99337 -457.027555) (xy 40.04092 -457.064042) (xy 40.0833 -457.106422) (xy 40.119787 -457.153972)
			(xy 40.149754 -457.205878) (xy 40.17269 -457.261251) (xy 40.188203 -457.319144) (xy 40.196026 -457.378566)
			(xy 40.196026 -457.438502) (xy 40.188203 -457.497924) (xy 40.17269 -457.555817) (xy 40.149754 -457.61119)
			(xy 40.119787 -457.663096) (xy 40.0833 -457.710646) (xy 40.04092 -457.753026) (xy 39.99337 -457.789513)
			(xy 39.941464 -457.81948) (xy 39.886091 -457.842416) (xy 39.828198 -457.857929) (xy 39.768776 -457.865752)
			(xy 39.70884 -457.865752) (xy 39.649418 -457.857929) (xy 39.591525 -457.842416) (xy 39.536152 -457.81948)
			(xy 39.484246 -457.789513) (xy 39.436696 -457.753026) (xy 39.394316 -457.710646) (xy 39.357829 -457.663096)
			(xy 39.327862 -457.61119) (xy 39.304926 -457.555817) (xy 39.289413 -457.497924) (xy 39.28159 -457.438502)
			(xy 36.179535 -457.438502) (xy 36.155415 -457.461403) (xy 36.087376 -457.515016) (xy 36.014695 -457.562144)
			(xy 35.937987 -457.602388) (xy 35.857903 -457.635407) (xy 35.775122 -457.66092) (xy 35.690345 -457.678711)
			(xy 35.604291 -457.68863) (xy 35.517689 -457.690592) (xy 35.431274 -457.684581) (xy 35.345779 -457.670648)
			(xy 35.261927 -457.648911) (xy 35.180429 -457.619553) (xy 35.101977 -457.582825) (xy 35.027236 -457.539037)
			(xy 34.956839 -457.48856) (xy 34.891382 -457.431823) (xy 34.831421 -457.369306) (xy 34.777465 -457.301539)
			(xy 34.729969 -457.229097) (xy 34.689337 -457.152594) (xy 34.655914 -457.072678) (xy 34.629983 -456.990027)
			(xy 34.611763 -456.905341) (xy 34.601409 -456.819338) (xy 34.599008 -456.732748) (xy 34.604582 -456.646304)
			(xy 34.618083 -456.560739) (xy 34.639396 -456.476778) (xy 34.66834 -456.395133) (xy 34.704671 -456.316496)
			(xy 34.748081 -456.241534) (xy 34.7982 -456.170883) (xy 34.854606 -456.10514) (xy 34.916819 -456.044864)
			(xy 34.984312 -455.990565) (xy 35.056512 -455.942703) (xy 35.132809 -455.901685) (xy 35.212555 -455.867858)
			(xy 35.295074 -455.841509) (xy 35.379667 -455.82286) (xy 35.465616 -455.812071) (xy 35.552193 -455.809233)
			(xy 35.638664 -455.814369) (xy 35.724297 -455.827437) (xy 35.808364 -455.848325) (xy 35.890154 -455.876856)
			(xy 35.968974 -455.912789) (xy 36.044154 -455.955818) (xy 36.115059 -456.00558) (xy 36.181086 -456.061652)
			(xy 36.241676 -456.123559) (xy 36.269422 -456.156822) (xy 36.284735 -456.17484) (xy 36.320822 -456.205387)
			(xy 36.361937 -456.228732) (xy 36.406661 -456.24407) (xy 36.45345 -456.250869) (xy 36.500689 -456.248897)
			(xy 36.546749 -456.238221) (xy 36.590038 -456.21921) (xy 36.629065 -456.192519) (xy 36.646104 -456.176126)
			(xy 36.919408 -455.902822) (xy 36.919408 -445.908684) (xy 28.136596 -437.125618) (xy 28.119955 -437.109684)
			(xy 28.082043 -437.083512) (xy 28.040034 -437.064604) (xy 27.995305 -437.053578) (xy 27.949321 -437.050795)
			(xy 27.903588 -437.056346) (xy 27.859605 -437.07005) (xy 27.818813 -437.091458) (xy 27.782549 -437.119869)
			(xy 27.751999 -437.15435) (xy 27.728165 -437.193774) (xy 27.711828 -437.236848) (xy 27.703524 -437.282162)
			(xy 27.703018 -437.305196) (xy 27.702764 -438.285636) (xy 35.117786 -445.700404) (xy 35.189414 -445.71666)
			(xy 35.223958 -445.704214) (xy 35.265429 -445.689966) (xy 35.350416 -445.668337) (xy 35.437048 -445.654716)
			(xy 35.524571 -445.649221) (xy 35.612226 -445.651899) (xy 35.699251 -445.662727) (xy 35.784889 -445.681611)
			(xy 35.868397 -445.708388) (xy 35.949049 -445.742823) (xy 36.026145 -445.784619) (xy 36.099013 -445.833411)
			(xy 36.167022 -445.888777) (xy 36.22958 -445.950235) (xy 36.286144 -446.01725) (xy 36.336222 -446.089241)
			(xy 36.379379 -446.165583) (xy 36.415241 -446.245611) (xy 36.443495 -446.328631) (xy 36.463896 -446.413921)
			(xy 36.476266 -446.500739) (xy 36.4805 -446.588333) (xy 36.476558 -446.67594) (xy 36.464477 -446.7628)
			(xy 36.44436 -446.848157) (xy 36.416383 -446.93127) (xy 36.380788 -447.011418) (xy 36.337885 -447.087902)
			(xy 36.288047 -447.16006) (xy 36.231707 -447.227264) (xy 36.169354 -447.288929) (xy 36.10153 -447.344521)
			(xy 36.028824 -447.393556) (xy 35.951869 -447.435609) (xy 35.871332 -447.470313) (xy 35.787914 -447.497367)
			(xy 35.702339 -447.516536) (xy 35.61535 -447.527654) (xy 35.527705 -447.530624) (xy 35.440164 -447.525421)
			(xy 35.353487 -447.512088) (xy 35.268429 -447.490743) (xy 35.185727 -447.461571) (xy 35.145726 -447.443606)
			(xy 35.124498 -447.434371) (xy 35.079652 -447.422906) (xy 35.033471 -447.419754) (xy 34.987483 -447.425018)
			(xy 34.943208 -447.438524) (xy 34.902113 -447.459826) (xy 34.865555 -447.488218) (xy 34.834744 -447.522762)
			(xy 34.810699 -447.562316) (xy 34.794215 -447.60557) (xy 34.785838 -447.651094) (xy 34.7853 -447.674238)
			(xy 34.7853 -448.045586) (xy 34.785809 -448.068732) (xy 34.79419 -448.114258) (xy 34.810678 -448.157513)
			(xy 34.834726 -448.197067) (xy 34.865541 -448.231612) (xy 34.902102 -448.260004) (xy 34.9432 -448.281306)
			(xy 34.987477 -448.294813) (xy 35.033468 -448.300077) (xy 35.079651 -448.296925) (xy 35.1245 -448.285461)
			(xy 35.145726 -448.276218) (xy 35.185713 -448.258318) (xy 35.268337 -448.229165) (xy 35.353315 -448.207825)
			(xy 35.439909 -448.194484) (xy 35.527369 -448.189257) (xy 35.614936 -448.192189) (xy 35.70185 -448.203256)
			(xy 35.787358 -448.222361) (xy 35.870718 -448.249338) (xy 35.951206 -448.283954) (xy 36.028124 -448.325908)
			(xy 36.100806 -448.374836) (xy 36.16862 -448.430314) (xy 36.230979 -448.49186) (xy 36.287341 -448.558941)
			(xy 36.337218 -448.630975) (xy 36.380177 -448.707336) (xy 36.415845 -448.787364) (xy 36.443913 -448.870362)
			(xy 36.464138 -448.955612) (xy 36.476343 -449.042374) (xy 36.480424 -449.129895) (xy 36.476344 -449.217416)
			(xy 36.46414 -449.304178) (xy 36.443916 -449.389428) (xy 36.415849 -449.472427) (xy 36.380182 -449.552455)
			(xy 36.337224 -449.628817) (xy 36.287347 -449.700851) (xy 36.230986 -449.767933) (xy 36.168628 -449.82948)
			(xy 36.100814 -449.884958) (xy 36.028133 -449.933887) (xy 35.951215 -449.975842) (xy 35.870727 -450.010458)
			(xy 35.787368 -450.037436) (xy 35.70186 -450.056542) (xy 35.614946 -450.06761) (xy 35.527379 -450.070543)
			(xy 35.439919 -450.065317) (xy 35.353324 -450.051977) (xy 35.268347 -450.030638) (xy 35.185723 -450.001486)
			(xy 35.145726 -449.983606) (xy 35.124498 -449.974371) (xy 35.079652 -449.962906) (xy 35.033471 -449.959754)
			(xy 34.987483 -449.965018) (xy 34.943208 -449.978524) (xy 34.902113 -449.999826) (xy 34.865555 -450.028218)
			(xy 34.834744 -450.062762) (xy 34.810699 -450.102316) (xy 34.794215 -450.14557) (xy 34.785838 -450.191094)
			(xy 34.7853 -450.214238) (xy 34.7853 -450.447918) (xy 35.117786 -450.780404) (xy 35.189414 -450.79666)
			(xy 35.223958 -450.784214) (xy 35.264638 -450.770223) (xy 35.347975 -450.748858) (xy 35.432915 -450.735195)
			(xy 35.518747 -450.729348) (xy 35.604756 -450.731367) (xy 35.69022 -450.741234) (xy 35.774425 -450.758867)
			(xy 35.856667 -450.784119) (xy 35.936259 -450.816778) (xy 36.012535 -450.856571) (xy 36.084856 -450.903166)
			(xy 36.152619 -450.956172) (xy 36.215256 -451.015147) (xy 36.272244 -451.079598) (xy 36.323106 -451.148985)
			(xy 36.367416 -451.222728) (xy 36.404805 -451.300211) (xy 36.434959 -451.380785) (xy 36.457627 -451.463776)
			(xy 36.472619 -451.548492) (xy 36.479809 -451.634223) (xy 36.479137 -451.720252) (xy 36.470609 -451.80586)
			(xy 36.454297 -451.890331) (xy 36.430336 -451.972959) (xy 36.398927 -452.053053) (xy 36.360333 -452.129942)
			(xy 36.314876 -452.202984) (xy 36.262937 -452.271568) (xy 36.20495 -452.335121) (xy 36.1414 -452.393111)
			(xy 36.072818 -452.445053) (xy 35.999778 -452.490513) (xy 35.92289 -452.52911) (xy 35.842798 -452.560523)
			(xy 35.760171 -452.584487) (xy 35.675701 -452.600803) (xy 35.590093 -452.609335) (xy 35.504064 -452.61001)
			(xy 35.418333 -452.602824) (xy 35.333616 -452.587836) (xy 35.250624 -452.565172) (xy 35.170048 -452.535021)
			(xy 35.092564 -452.497636) (xy 35.018819 -452.453328) (xy 34.94943 -452.40247) (xy 34.884977 -452.345485)
			(xy 34.825999 -452.28285) (xy 34.772989 -452.21509) (xy 34.726392 -452.14277) (xy 34.686595 -452.066496)
			(xy 34.653932 -451.986906) (xy 34.628677 -451.904665) (xy 34.61104 -451.82046) (xy 34.60117 -451.734996)
			(xy 34.599147 -451.648988) (xy 34.60499 -451.563155) (xy 34.61865 -451.478215) (xy 34.640011 -451.394877)
			(xy 34.653982 -451.35419) (xy 34.666428 -451.319646) (xy 34.650172 -451.248018) (xy 34.123884 -450.72173)
			(xy 34.123884 -447.316606) (xy 31.223966 -444.416434) (xy 31.207327 -444.400502) (xy 31.169418 -444.374336)
			(xy 31.127413 -444.355431) (xy 31.082688 -444.344408) (xy 31.03671 -444.341628) (xy 30.990983 -444.347181)
			(xy 30.947006 -444.360885) (xy 30.90622 -444.382293) (xy 30.869961 -444.410702) (xy 30.839417 -444.445181)
			(xy 30.815588 -444.484602) (xy 30.799256 -444.527672) (xy 30.790955 -444.572981) (xy 30.790388 -444.596012)
			(xy 30.790388 -445.625728) (xy 30.790991 -445.643632) (xy 30.800939 -445.67803) (xy 30.820068 -445.7083)
			(xy 30.846867 -445.732049) (xy 30.862778 -445.740282) (xy 30.90144 -445.759158) (xy 30.975483 -445.802986)
			(xy 31.045212 -445.853395) (xy 31.110045 -445.909964) (xy 31.169439 -445.972218) (xy 31.222898 -446.039637)
			(xy 31.269975 -446.111659) (xy 31.310276 -446.187679) (xy 31.343463 -446.267063) (xy 31.369261 -446.349147)
			(xy 31.387451 -446.433245) (xy 31.397884 -446.518652) (xy 31.400471 -446.604655) (xy 31.39519 -446.690535)
			(xy 31.382087 -446.775574) (xy 31.36127 -446.85906) (xy 31.332913 -446.940295) (xy 31.297254 -447.018601)
			(xy 31.254591 -447.093321) (xy 31.205281 -447.163832) (xy 31.149736 -447.229543) (xy 31.08842 -447.289905)
			(xy 31.021846 -447.344414) (xy 30.950571 -447.392614) (xy 30.875192 -447.434101) (xy 30.796337 -447.468528)
			(xy 30.714668 -447.495608) (xy 30.630866 -447.515115) (xy 30.545632 -447.526884) (xy 30.45968 -447.530818)
			(xy 30.373728 -447.526884) (xy 30.288494 -447.515115) (xy 30.204692 -447.495608) (xy 30.123023 -447.468528)
			(xy 30.044168 -447.434101) (xy 29.968789 -447.392614) (xy 29.897514 -447.344414) (xy 29.83094 -447.289905)
			(xy 29.769624 -447.229543) (xy 29.714079 -447.163832) (xy 29.664769 -447.093321) (xy 29.622106 -447.018601)
			(xy 29.586447 -446.940295) (xy 29.55809 -446.85906) (xy 29.537273 -446.775574) (xy 29.52417 -446.690535)
			(xy 29.518889 -446.604655) (xy 29.521476 -446.518652) (xy 29.531909 -446.433245) (xy 29.550099 -446.349147)
			(xy 29.575897 -446.267063) (xy 29.609084 -446.187679) (xy 29.649385 -446.111659) (xy 29.696462 -446.039637)
			(xy 29.749921 -445.972218) (xy 29.809315 -445.909964) (xy 29.874148 -445.853395) (xy 29.943877 -445.802986)
			(xy 30.01792 -445.759158) (xy 30.056582 -445.740282) (xy 30.072474 -445.732027) (xy 30.099237 -445.708257)
			(xy 30.118362 -445.677999) (xy 30.128347 -445.643625) (xy 30.128972 -445.625728) (xy 30.128972 -444.124842)
			(xy 28.778708 -442.774324) (xy 28.762066 -442.758362) (xy 28.724143 -442.732139) (xy 28.682111 -442.713186)
			(xy 28.63735 -442.702124) (xy 28.591329 -442.699316) (xy 28.545555 -442.704855) (xy 28.501532 -442.718558)
			(xy 28.460701 -442.739977) (xy 28.424403 -442.768408) (xy 28.393828 -442.80292) (xy 28.369979 -442.84238)
			(xy 28.353638 -442.885494) (xy 28.34534 -442.930848) (xy 28.344876 -442.953902) (xy 28.344876 -449.173362)
			(xy 29.519874 -449.173362) (xy 29.519874 -449.086462) (xy 29.527892 -448.999933) (xy 29.54386 -448.914513)
			(xy 29.567641 -448.830931) (xy 29.599033 -448.749899) (xy 29.637767 -448.67211) (xy 29.683514 -448.598226)
			(xy 29.735883 -448.528879) (xy 29.794427 -448.464659) (xy 29.858647 -448.406115) (xy 29.927994 -448.353746)
			(xy 30.001878 -448.307999) (xy 30.079667 -448.269265) (xy 30.160699 -448.237873) (xy 30.244281 -448.214092)
			(xy 30.329701 -448.198124) (xy 30.41623 -448.190106) (xy 30.45968 -448.189604) (xy 30.50313 -448.190106)
			(xy 30.589659 -448.198124) (xy 30.675079 -448.214092) (xy 30.758661 -448.237873) (xy 30.839693 -448.269265)
			(xy 30.917482 -448.307999) (xy 30.991366 -448.353746) (xy 31.060713 -448.406115) (xy 31.124933 -448.464659)
			(xy 31.183477 -448.528879) (xy 31.235846 -448.598226) (xy 31.281593 -448.67211) (xy 31.320327 -448.749899)
			(xy 31.351719 -448.830931) (xy 31.3755 -448.914513) (xy 31.391468 -448.999933) (xy 31.399486 -449.086462)
			(xy 31.399486 -449.173362) (xy 31.391468 -449.259891) (xy 31.3755 -449.345311) (xy 31.351719 -449.428893)
			(xy 31.320327 -449.509925) (xy 31.281593 -449.587714) (xy 31.235846 -449.661598) (xy 31.183477 -449.730945)
			(xy 31.124933 -449.795165) (xy 31.060713 -449.853709) (xy 30.991366 -449.906078) (xy 30.917482 -449.951825)
			(xy 30.839693 -449.990559) (xy 30.758661 -450.021951) (xy 30.675079 -450.045732) (xy 30.589659 -450.0617)
			(xy 30.50313 -450.069718) (xy 30.41623 -450.069718) (xy 30.329701 -450.0617) (xy 30.244281 -450.045732)
			(xy 30.160699 -450.021951) (xy 30.079667 -449.990559) (xy 30.001878 -449.951825) (xy 29.927994 -449.906078)
			(xy 29.858647 -449.853709) (xy 29.794427 -449.795165) (xy 29.735883 -449.730945) (xy 29.683514 -449.661598)
			(xy 29.637767 -449.587714) (xy 29.599033 -449.509925) (xy 29.567641 -449.428893) (xy 29.54386 -449.345311)
			(xy 29.527892 -449.259891) (xy 29.519874 -449.173362) (xy 28.344876 -449.173362) (xy 28.344876 -451.713362)
			(xy 29.519874 -451.713362) (xy 29.519874 -451.626462) (xy 29.527892 -451.539933) (xy 29.54386 -451.454513)
			(xy 29.567641 -451.370931) (xy 29.599033 -451.289899) (xy 29.637767 -451.21211) (xy 29.683514 -451.138226)
			(xy 29.735883 -451.068879) (xy 29.794427 -451.004659) (xy 29.858647 -450.946115) (xy 29.927994 -450.893746)
			(xy 30.001878 -450.847999) (xy 30.079667 -450.809265) (xy 30.160699 -450.777873) (xy 30.244281 -450.754092)
			(xy 30.329701 -450.738124) (xy 30.41623 -450.730106) (xy 30.45968 -450.729604) (xy 30.50313 -450.730106)
			(xy 30.589659 -450.738124) (xy 30.675079 -450.754092) (xy 30.758661 -450.777873) (xy 30.839693 -450.809265)
			(xy 30.917482 -450.847999) (xy 30.991366 -450.893746) (xy 31.060713 -450.946115) (xy 31.124933 -451.004659)
			(xy 31.183477 -451.068879) (xy 31.235846 -451.138226) (xy 31.281593 -451.21211) (xy 31.320327 -451.289899)
			(xy 31.351719 -451.370931) (xy 31.3755 -451.454513) (xy 31.391468 -451.539933) (xy 31.399486 -451.626462)
			(xy 31.399486 -451.713362) (xy 31.391468 -451.799891) (xy 31.3755 -451.885311) (xy 31.351719 -451.968893)
			(xy 31.320327 -452.049925) (xy 31.281593 -452.127714) (xy 31.235846 -452.201598) (xy 31.183477 -452.270945)
			(xy 31.124933 -452.335165) (xy 31.060713 -452.393709) (xy 30.991366 -452.446078) (xy 30.917482 -452.491825)
			(xy 30.839693 -452.530559) (xy 30.758661 -452.561951) (xy 30.675079 -452.585732) (xy 30.589659 -452.6017)
			(xy 30.50313 -452.609718) (xy 30.41623 -452.609718) (xy 30.329701 -452.6017) (xy 30.244281 -452.585732)
			(xy 30.160699 -452.561951) (xy 30.079667 -452.530559) (xy 30.001878 -452.491825) (xy 29.927994 -452.446078)
			(xy 29.858647 -452.393709) (xy 29.794427 -452.335165) (xy 29.735883 -452.270945) (xy 29.683514 -452.201598)
			(xy 29.637767 -452.127714) (xy 29.599033 -452.049925) (xy 29.567641 -451.968893) (xy 29.54386 -451.885311)
			(xy 29.527892 -451.799891) (xy 29.519874 -451.713362) (xy 28.344876 -451.713362) (xy 28.344876 -454.253362)
			(xy 29.519874 -454.253362) (xy 29.519874 -454.166462) (xy 29.527892 -454.079933) (xy 29.54386 -453.994513)
			(xy 29.567641 -453.910931) (xy 29.599033 -453.829899) (xy 29.637767 -453.75211) (xy 29.683514 -453.678226)
			(xy 29.735883 -453.608879) (xy 29.794427 -453.544659) (xy 29.858647 -453.486115) (xy 29.927994 -453.433746)
			(xy 30.001878 -453.387999) (xy 30.079667 -453.349265) (xy 30.160699 -453.317873) (xy 30.244281 -453.294092)
			(xy 30.329701 -453.278124) (xy 30.41623 -453.270106) (xy 30.45968 -453.269604) (xy 30.50313 -453.270106)
			(xy 30.589659 -453.278124) (xy 30.675079 -453.294092) (xy 30.758661 -453.317873) (xy 30.839693 -453.349265)
			(xy 30.917482 -453.387999) (xy 30.991366 -453.433746) (xy 31.060713 -453.486115) (xy 31.124933 -453.544659)
			(xy 31.183477 -453.608879) (xy 31.235846 -453.678226) (xy 31.281593 -453.75211) (xy 31.320327 -453.829899)
			(xy 31.351719 -453.910931) (xy 31.3755 -453.994513) (xy 31.391468 -454.079933) (xy 31.399486 -454.166462)
			(xy 31.399486 -454.253362) (xy 34.599874 -454.253362) (xy 34.599874 -454.166462) (xy 34.607892 -454.079933)
			(xy 34.62386 -453.994513) (xy 34.647641 -453.910931) (xy 34.679033 -453.829899) (xy 34.717767 -453.75211)
			(xy 34.763514 -453.678226) (xy 34.815883 -453.608879) (xy 34.874427 -453.544659) (xy 34.938647 -453.486115)
			(xy 35.007994 -453.433746) (xy 35.081878 -453.387999) (xy 35.159667 -453.349265) (xy 35.240699 -453.317873)
			(xy 35.324281 -453.294092) (xy 35.409701 -453.278124) (xy 35.49623 -453.270106) (xy 35.53968 -453.269604)
			(xy 35.58313 -453.270106) (xy 35.669659 -453.278124) (xy 35.755079 -453.294092) (xy 35.838661 -453.317873)
			(xy 35.919693 -453.349265) (xy 35.997482 -453.387999) (xy 36.071366 -453.433746) (xy 36.140713 -453.486115)
			(xy 36.204933 -453.544659) (xy 36.263477 -453.608879) (xy 36.315846 -453.678226) (xy 36.361593 -453.75211)
			(xy 36.400327 -453.829899) (xy 36.431719 -453.910931) (xy 36.4555 -453.994513) (xy 36.471468 -454.079933)
			(xy 36.479486 -454.166462) (xy 36.479486 -454.253362) (xy 36.471468 -454.339891) (xy 36.4555 -454.425311)
			(xy 36.431719 -454.508893) (xy 36.400327 -454.589925) (xy 36.361593 -454.667714) (xy 36.315846 -454.741598)
			(xy 36.263477 -454.810945) (xy 36.204933 -454.875165) (xy 36.140713 -454.933709) (xy 36.071366 -454.986078)
			(xy 35.997482 -455.031825) (xy 35.919693 -455.070559) (xy 35.838661 -455.101951) (xy 35.755079 -455.125732)
			(xy 35.669659 -455.1417) (xy 35.58313 -455.149718) (xy 35.49623 -455.149718) (xy 35.409701 -455.1417)
			(xy 35.324281 -455.125732) (xy 35.240699 -455.101951) (xy 35.159667 -455.070559) (xy 35.081878 -455.031825)
			(xy 35.007994 -454.986078) (xy 34.938647 -454.933709) (xy 34.874427 -454.875165) (xy 34.815883 -454.810945)
			(xy 34.763514 -454.741598) (xy 34.717767 -454.667714) (xy 34.679033 -454.589925) (xy 34.647641 -454.508893)
			(xy 34.62386 -454.425311) (xy 34.607892 -454.339891) (xy 34.599874 -454.253362) (xy 31.399486 -454.253362)
			(xy 31.391468 -454.339891) (xy 31.3755 -454.425311) (xy 31.351719 -454.508893) (xy 31.320327 -454.589925)
			(xy 31.281593 -454.667714) (xy 31.235846 -454.741598) (xy 31.183477 -454.810945) (xy 31.124933 -454.875165)
			(xy 31.060713 -454.933709) (xy 30.991366 -454.986078) (xy 30.917482 -455.031825) (xy 30.839693 -455.070559)
			(xy 30.758661 -455.101951) (xy 30.675079 -455.125732) (xy 30.589659 -455.1417) (xy 30.50313 -455.149718)
			(xy 30.41623 -455.149718) (xy 30.329701 -455.1417) (xy 30.244281 -455.125732) (xy 30.160699 -455.101951)
			(xy 30.079667 -455.070559) (xy 30.001878 -455.031825) (xy 29.927994 -454.986078) (xy 29.858647 -454.933709)
			(xy 29.794427 -454.875165) (xy 29.735883 -454.810945) (xy 29.683514 -454.741598) (xy 29.637767 -454.667714)
			(xy 29.599033 -454.589925) (xy 29.567641 -454.508893) (xy 29.54386 -454.425311) (xy 29.527892 -454.339891)
			(xy 29.519874 -454.253362) (xy 28.344876 -454.253362) (xy 28.344876 -455.192638) (xy 27.647392 -455.890376)
			(xy 27.63774 -455.917808) (xy 27.628934 -455.941912) (xy 27.605771 -455.987705) (xy 27.576692 -456.029989)
			(xy 27.542219 -456.068003) (xy 27.502971 -456.101066) (xy 27.48153 -456.115166) (xy 27.46256 -456.127772)
			(xy 27.429037 -456.158598) (xy 27.401546 -456.194906) (xy 27.38097 -456.235535) (xy 27.367967 -456.279181)
			(xy 27.362955 -456.324446) (xy 27.366094 -456.369879) (xy 27.377283 -456.414025) (xy 27.396164 -456.455469)
			(xy 27.422131 -456.492882) (xy 27.437842 -456.509374) (xy 27.600656 -456.672188) (xy 28.30957 -456.672188)
			(xy 28.430744 -456.793362) (xy 29.519874 -456.793362) (xy 29.519874 -456.706462) (xy 29.527892 -456.619933)
			(xy 29.54386 -456.534513) (xy 29.567641 -456.450931) (xy 29.599033 -456.369899) (xy 29.637767 -456.29211)
			(xy 29.683514 -456.218226) (xy 29.735883 -456.148879) (xy 29.794427 -456.084659) (xy 29.858647 -456.026115)
			(xy 29.927994 -455.973746) (xy 30.001878 -455.927999) (xy 30.079667 -455.889265) (xy 30.160699 -455.857873)
			(xy 30.244281 -455.834092) (xy 30.329701 -455.818124) (xy 30.41623 -455.810106) (xy 30.45968 -455.809604)
			(xy 30.50313 -455.810106) (xy 30.589659 -455.818124) (xy 30.675079 -455.834092) (xy 30.758661 -455.857873)
			(xy 30.839693 -455.889265) (xy 30.917482 -455.927999) (xy 30.991366 -455.973746) (xy 31.060713 -456.026115)
			(xy 31.124933 -456.084659) (xy 31.183477 -456.148879) (xy 31.235846 -456.218226) (xy 31.281593 -456.29211)
			(xy 31.320327 -456.369899) (xy 31.351719 -456.450931) (xy 31.3755 -456.534513) (xy 31.391468 -456.619933)
			(xy 31.399486 -456.706462) (xy 31.399486 -456.793362) (xy 31.391468 -456.879891) (xy 31.3755 -456.965311)
			(xy 31.351719 -457.048893) (xy 31.320327 -457.129925) (xy 31.281593 -457.207714) (xy 31.235846 -457.281598)
			(xy 31.183477 -457.350945) (xy 31.124933 -457.415165) (xy 31.060713 -457.473709) (xy 30.991366 -457.526078)
			(xy 30.917482 -457.571825) (xy 30.839693 -457.610559) (xy 30.758661 -457.641951) (xy 30.675079 -457.665732)
			(xy 30.589659 -457.6817) (xy 30.50313 -457.689718) (xy 30.41623 -457.689718) (xy 30.329701 -457.6817)
			(xy 30.244281 -457.665732) (xy 30.160699 -457.641951) (xy 30.079667 -457.610559) (xy 30.001878 -457.571825)
			(xy 29.927994 -457.526078) (xy 29.858647 -457.473709) (xy 29.794427 -457.415165) (xy 29.735883 -457.350945)
			(xy 29.683514 -457.281598) (xy 29.637767 -457.207714) (xy 29.599033 -457.129925) (xy 29.567641 -457.048893)
			(xy 29.54386 -456.965311) (xy 29.527892 -456.879891) (xy 29.519874 -456.793362) (xy 28.430744 -456.793362)
			(xy 30.037786 -458.400404) (xy 30.109414 -458.41666) (xy 30.143958 -458.404214) (xy 30.184638 -458.390223)
			(xy 30.267975 -458.368858) (xy 30.352915 -458.355195) (xy 30.438747 -458.349348) (xy 30.524756 -458.351367)
			(xy 30.61022 -458.361234) (xy 30.694425 -458.378867) (xy 30.776667 -458.404119) (xy 30.856259 -458.436778)
			(xy 30.932535 -458.476571) (xy 31.004856 -458.523166) (xy 31.072619 -458.576172) (xy 31.135256 -458.635147)
			(xy 31.192244 -458.699598) (xy 31.243106 -458.768985) (xy 31.287416 -458.842728) (xy 31.324805 -458.920211)
			(xy 31.354959 -459.000785) (xy 31.377627 -459.083776) (xy 31.392619 -459.168492) (xy 31.399809 -459.254223)
			(xy 31.399191 -459.333362) (xy 34.599874 -459.333362) (xy 34.599874 -459.246462) (xy 34.607892 -459.159933)
			(xy 34.62386 -459.074513) (xy 34.647641 -458.990931) (xy 34.679033 -458.909899) (xy 34.717767 -458.83211)
			(xy 34.763514 -458.758226) (xy 34.815883 -458.688879) (xy 34.874427 -458.624659) (xy 34.938647 -458.566115)
			(xy 35.007994 -458.513746) (xy 35.081878 -458.467999) (xy 35.159667 -458.429265) (xy 35.240699 -458.397873)
			(xy 35.324281 -458.374092) (xy 35.409701 -458.358124) (xy 35.49623 -458.350106) (xy 35.53968 -458.349604)
			(xy 35.58313 -458.350106) (xy 35.669659 -458.358124) (xy 35.755079 -458.374092) (xy 35.838661 -458.397873)
			(xy 35.919693 -458.429265) (xy 35.997482 -458.467999) (xy 36.071366 -458.513746) (xy 36.128938 -458.557223)
			(xy 62.983864 -458.557223) (xy 62.983864 -458.485901) (xy 62.99185 -458.415027) (xy 63.00772 -458.345492)
			(xy 63.031277 -458.278172) (xy 63.062222 -458.213913) (xy 63.100168 -458.153522) (xy 63.144637 -458.09776)
			(xy 63.19507 -458.047327) (xy 63.250832 -458.002858) (xy 63.311223 -457.964912) (xy 63.375482 -457.933967)
			(xy 63.442802 -457.91041) (xy 63.512337 -457.89454) (xy 63.583211 -457.886554) (xy 63.618872 -457.886054)
			(xy 63.654533 -457.886554) (xy 63.725407 -457.89454) (xy 63.794942 -457.91041) (xy 63.862262 -457.933967)
			(xy 63.926521 -457.964912) (xy 63.986912 -458.002858) (xy 64.042674 -458.047327) (xy 64.093107 -458.09776)
			(xy 64.137576 -458.153522) (xy 64.175522 -458.213913) (xy 64.206467 -458.278172) (xy 64.230024 -458.345492)
			(xy 64.245894 -458.415027) (xy 64.25388 -458.485901) (xy 64.25388 -458.557223) (xy 65.059298 -458.557223)
			(xy 65.059298 -458.485901) (xy 65.067284 -458.415027) (xy 65.083154 -458.345492) (xy 65.106711 -458.278172)
			(xy 65.137656 -458.213913) (xy 65.175602 -458.153522) (xy 65.220071 -458.09776) (xy 65.270504 -458.047327)
			(xy 65.326266 -458.002858) (xy 65.386657 -457.964912) (xy 65.450916 -457.933967) (xy 65.518236 -457.91041)
			(xy 65.587771 -457.89454) (xy 65.658645 -457.886554) (xy 65.694306 -457.886054) (xy 65.729967 -457.886554)
			(xy 65.800841 -457.89454) (xy 65.870376 -457.91041) (xy 65.937696 -457.933967) (xy 66.001955 -457.964912)
			(xy 66.062346 -458.002858) (xy 66.118108 -458.047327) (xy 66.168541 -458.09776) (xy 66.21301 -458.153522)
			(xy 66.250956 -458.213913) (xy 66.281901 -458.278172) (xy 66.305458 -458.345492) (xy 66.321328 -458.415027)
			(xy 66.329314 -458.485901) (xy 66.329314 -458.557223) (xy 66.329228 -458.557985) (xy 67.283576 -458.557985)
			(xy 67.283576 -458.486663) (xy 67.291562 -458.415789) (xy 67.307432 -458.346254) (xy 67.330989 -458.278934)
			(xy 67.361934 -458.214675) (xy 67.39988 -458.154284) (xy 67.444349 -458.098522) (xy 67.494782 -458.048089)
			(xy 67.550544 -458.00362) (xy 67.610935 -457.965674) (xy 67.675194 -457.934729) (xy 67.742514 -457.911172)
			(xy 67.812049 -457.895302) (xy 67.882923 -457.887316) (xy 67.918584 -457.886816) (xy 67.954245 -457.887316)
			(xy 68.025119 -457.895302) (xy 68.094654 -457.911172) (xy 68.161974 -457.934729) (xy 68.226233 -457.965674)
			(xy 68.286624 -458.00362) (xy 68.342386 -458.048089) (xy 68.392819 -458.098522) (xy 68.437288 -458.154284)
			(xy 68.475234 -458.214675) (xy 68.506179 -458.278934) (xy 68.529736 -458.346254) (xy 68.545606 -458.415789)
			(xy 68.553592 -458.486663) (xy 68.553592 -458.557985) (xy 68.545606 -458.628859) (xy 68.529736 -458.698394)
			(xy 68.506179 -458.765714) (xy 68.475234 -458.829973) (xy 68.437288 -458.890364) (xy 68.392819 -458.946126)
			(xy 68.342386 -458.996559) (xy 68.286624 -459.041028) (xy 68.226233 -459.078974) (xy 68.161974 -459.109919)
			(xy 68.094654 -459.133476) (xy 68.025119 -459.149346) (xy 67.954245 -459.157332) (xy 67.882923 -459.157332)
			(xy 67.812049 -459.149346) (xy 67.742514 -459.133476) (xy 67.675194 -459.109919) (xy 67.610935 -459.078974)
			(xy 67.550544 -459.041028) (xy 67.494782 -458.996559) (xy 67.444349 -458.946126) (xy 67.39988 -458.890364)
			(xy 67.361934 -458.829973) (xy 67.330989 -458.765714) (xy 67.307432 -458.698394) (xy 67.291562 -458.628859)
			(xy 67.283576 -458.557985) (xy 66.329228 -458.557985) (xy 66.321328 -458.628097) (xy 66.305458 -458.697632)
			(xy 66.281901 -458.764952) (xy 66.250956 -458.829211) (xy 66.21301 -458.889602) (xy 66.168541 -458.945364)
			(xy 66.118108 -458.995797) (xy 66.062346 -459.040266) (xy 66.001955 -459.078212) (xy 65.937696 -459.109157)
			(xy 65.870376 -459.132714) (xy 65.800841 -459.148584) (xy 65.729967 -459.15657) (xy 65.658645 -459.15657)
			(xy 65.587771 -459.148584) (xy 65.518236 -459.132714) (xy 65.450916 -459.109157) (xy 65.386657 -459.078212)
			(xy 65.326266 -459.040266) (xy 65.270504 -458.995797) (xy 65.220071 -458.945364) (xy 65.175602 -458.889602)
			(xy 65.137656 -458.829211) (xy 65.106711 -458.764952) (xy 65.083154 -458.697632) (xy 65.067284 -458.628097)
			(xy 65.059298 -458.557223) (xy 64.25388 -458.557223) (xy 64.245894 -458.628097) (xy 64.230024 -458.697632)
			(xy 64.206467 -458.764952) (xy 64.175522 -458.829211) (xy 64.137576 -458.889602) (xy 64.093107 -458.945364)
			(xy 64.042674 -458.995797) (xy 63.986912 -459.040266) (xy 63.926521 -459.078212) (xy 63.862262 -459.109157)
			(xy 63.794942 -459.132714) (xy 63.725407 -459.148584) (xy 63.654533 -459.15657) (xy 63.583211 -459.15657)
			(xy 63.512337 -459.148584) (xy 63.442802 -459.132714) (xy 63.375482 -459.109157) (xy 63.311223 -459.078212)
			(xy 63.250832 -459.040266) (xy 63.19507 -458.995797) (xy 63.144637 -458.945364) (xy 63.100168 -458.889602)
			(xy 63.062222 -458.829211) (xy 63.031277 -458.764952) (xy 63.00772 -458.697632) (xy 62.99185 -458.628097)
			(xy 62.983864 -458.557223) (xy 36.128938 -458.557223) (xy 36.140713 -458.566115) (xy 36.204933 -458.624659)
			(xy 36.263477 -458.688879) (xy 36.315846 -458.758226) (xy 36.361593 -458.83211) (xy 36.400327 -458.909899)
			(xy 36.431719 -458.990931) (xy 36.4555 -459.074513) (xy 36.471468 -459.159933) (xy 36.479486 -459.246462)
			(xy 36.479486 -459.333362) (xy 36.471468 -459.419891) (xy 36.4555 -459.505311) (xy 36.431719 -459.588893)
			(xy 36.400327 -459.669925) (xy 36.361593 -459.747714) (xy 36.315846 -459.821598) (xy 36.263477 -459.890945)
			(xy 36.204933 -459.955165) (xy 36.140713 -460.013709) (xy 36.071366 -460.066078) (xy 35.997482 -460.111825)
			(xy 35.919693 -460.150559) (xy 35.838661 -460.181951) (xy 35.755079 -460.205732) (xy 35.669659 -460.2217)
			(xy 35.58313 -460.229718) (xy 35.49623 -460.229718) (xy 35.409701 -460.2217) (xy 35.324281 -460.205732)
			(xy 35.240699 -460.181951) (xy 35.159667 -460.150559) (xy 35.081878 -460.111825) (xy 35.007994 -460.066078)
			(xy 34.938647 -460.013709) (xy 34.874427 -459.955165) (xy 34.815883 -459.890945) (xy 34.763514 -459.821598)
			(xy 34.717767 -459.747714) (xy 34.679033 -459.669925) (xy 34.647641 -459.588893) (xy 34.62386 -459.505311)
			(xy 34.607892 -459.419891) (xy 34.599874 -459.333362) (xy 31.399191 -459.333362) (xy 31.399137 -459.340252)
			(xy 31.390609 -459.42586) (xy 31.374297 -459.510331) (xy 31.350336 -459.592959) (xy 31.318927 -459.673053)
			(xy 31.280333 -459.749942) (xy 31.234876 -459.822984) (xy 31.182937 -459.891568) (xy 31.12495 -459.955121)
			(xy 31.0614 -460.013111) (xy 30.992818 -460.065053) (xy 30.919778 -460.110513) (xy 30.84289 -460.14911)
			(xy 30.762798 -460.180523) (xy 30.680171 -460.204487) (xy 30.595701 -460.220803) (xy 30.510093 -460.229335)
			(xy 30.424064 -460.23001) (xy 30.338333 -460.222824) (xy 30.253616 -460.207836) (xy 30.170624 -460.185172)
			(xy 30.090048 -460.155021) (xy 30.012564 -460.117636) (xy 29.938819 -460.073328) (xy 29.86943 -460.02247)
			(xy 29.804977 -459.965485) (xy 29.745999 -459.90285) (xy 29.692989 -459.83509) (xy 29.646392 -459.76277)
			(xy 29.606595 -459.686496) (xy 29.573932 -459.606906) (xy 29.548677 -459.524665) (xy 29.53104 -459.44046)
			(xy 29.52117 -459.354996) (xy 29.519147 -459.268988) (xy 29.52499 -459.183155) (xy 29.53865 -459.098215)
			(xy 29.560011 -459.014877) (xy 29.573982 -458.97419) (xy 29.586428 -458.939646) (xy 29.570172 -458.868018)
			(xy 28.035758 -457.333604) (xy 27.820874 -457.333604) (xy 27.797687 -457.334121) (xy 27.752084 -457.342539)
			(xy 27.708765 -457.359091) (xy 27.669168 -457.383228) (xy 27.634607 -457.414148) (xy 27.606229 -457.450826)
			(xy 27.584977 -457.492043) (xy 27.571556 -457.536432) (xy 27.566411 -457.58252) (xy 27.569713 -457.628776)
			(xy 27.575002 -457.651358) (xy 27.582081 -457.680486) (xy 27.589445 -457.739977) (xy 27.58898 -457.79992)
			(xy 27.580694 -457.859289) (xy 27.564728 -457.917068) (xy 27.541356 -457.972269) (xy 27.510978 -458.023946)
			(xy 27.474114 -458.071215) (xy 27.431394 -458.113268) (xy 27.383551 -458.149384) (xy 27.331402 -458.178945)
			(xy 27.27584 -458.201445) (xy 27.217817 -458.2165) (xy 27.158325 -458.223851) (xy 27.098382 -458.223373)
			(xy 27.039015 -458.215074) (xy 26.981239 -458.199095) (xy 26.926043 -458.175712) (xy 26.874372 -458.145323)
			(xy 26.827111 -458.108448) (xy 26.785068 -458.06572) (xy 26.748962 -458.017868) (xy 26.719412 -457.965713)
			(xy 26.696924 -457.910147) (xy 26.681882 -457.85212) (xy 26.674543 -457.792626) (xy 26.675034 -457.732683)
			(xy 26.683346 -457.673318) (xy 26.699337 -457.615545) (xy 26.722733 -457.560355) (xy 26.753133 -457.508691)
			(xy 26.790018 -457.461437) (xy 26.832755 -457.419403) (xy 26.880614 -457.383308) (xy 26.906474 -457.368148)
			(xy 26.926564 -457.356153) (xy 26.96236 -457.326031) (xy 26.992037 -457.289864) (xy 27.014592 -457.248876)
			(xy 27.029262 -457.204452) (xy 27.035553 -457.158093) (xy 27.03325 -457.111365) (xy 27.022433 -457.065849)
			(xy 27.003466 -457.023082) (xy 26.976991 -456.98451) (xy 26.96083 -456.96759) (xy 26.007568 -456.014074)
			(xy 26.007568 -443.103508) (xy 25.943052 -443.038992) (xy 25.926411 -443.023064) (xy 25.888501 -442.996904)
			(xy 25.846497 -442.978005) (xy 25.801774 -442.966986) (xy 25.755798 -442.964208) (xy 25.710074 -442.969762)
			(xy 25.666099 -442.983467) (xy 25.625315 -443.004872) (xy 25.589057 -443.033278) (xy 25.558513 -443.067753)
			(xy 25.534682 -443.107169) (xy 25.518345 -443.150235) (xy 25.510038 -443.19554) (xy 25.509474 -443.21857)
			(xy 25.50922 -445.201548) (xy 24.599392 -446.111376) (xy 24.599392 -459.69174) (xy 25.171715 -460.26402)
			(xy 27.258263 -460.26402) (xy 27.264363 -460.208583) (xy 27.278469 -460.154626) (xy 27.300281 -460.103297)
			(xy 27.329335 -460.055691) (xy 27.36501 -460.012823) (xy 27.406547 -459.975606) (xy 27.45306 -459.944833)
			(xy 27.503557 -459.921161) (xy 27.556964 -459.905093) (xy 27.61214 -459.896973) (xy 27.640026 -459.896464)
			(xy 27.667912 -459.896973) (xy 27.723088 -459.905093) (xy 27.776495 -459.921161) (xy 27.826992 -459.944833)
			(xy 27.873505 -459.975606) (xy 27.915042 -460.012823) (xy 27.950717 -460.055691) (xy 27.979771 -460.103297)
			(xy 28.001583 -460.154626) (xy 28.015689 -460.208583) (xy 28.021789 -460.26402) (xy 28.019966 -460.313887)
			(xy 62.983864 -460.313887) (xy 62.983864 -460.242565) (xy 62.99185 -460.171691) (xy 63.00772 -460.102156)
			(xy 63.031277 -460.034836) (xy 63.062222 -459.970577) (xy 63.100168 -459.910186) (xy 63.144637 -459.854424)
			(xy 63.19507 -459.803991) (xy 63.250832 -459.759522) (xy 63.311223 -459.721576) (xy 63.375482 -459.690631)
			(xy 63.442802 -459.667074) (xy 63.512337 -459.651204) (xy 63.583211 -459.643218) (xy 63.618872 -459.642718)
			(xy 63.654533 -459.643218) (xy 63.725407 -459.651204) (xy 63.794942 -459.667074) (xy 63.862262 -459.690631)
			(xy 63.926521 -459.721576) (xy 63.986912 -459.759522) (xy 64.042674 -459.803991) (xy 64.093107 -459.854424)
			(xy 64.137576 -459.910186) (xy 64.175522 -459.970577) (xy 64.206467 -460.034836) (xy 64.230024 -460.102156)
			(xy 64.245894 -460.171691) (xy 64.25388 -460.242565) (xy 64.25388 -460.313887) (xy 65.059298 -460.313887)
			(xy 65.059298 -460.242565) (xy 65.067284 -460.171691) (xy 65.083154 -460.102156) (xy 65.106711 -460.034836)
			(xy 65.137656 -459.970577) (xy 65.175602 -459.910186) (xy 65.220071 -459.854424) (xy 65.270504 -459.803991)
			(xy 65.326266 -459.759522) (xy 65.386657 -459.721576) (xy 65.450916 -459.690631) (xy 65.518236 -459.667074)
			(xy 65.587771 -459.651204) (xy 65.658645 -459.643218) (xy 65.694306 -459.642718) (xy 65.729967 -459.643218)
			(xy 65.800841 -459.651204) (xy 65.870376 -459.667074) (xy 65.937696 -459.690631) (xy 66.001955 -459.721576)
			(xy 66.062346 -459.759522) (xy 66.118108 -459.803991) (xy 66.168541 -459.854424) (xy 66.21301 -459.910186)
			(xy 66.250956 -459.970577) (xy 66.281901 -460.034836) (xy 66.305458 -460.102156) (xy 66.321328 -460.171691)
			(xy 66.329314 -460.242565) (xy 66.329314 -460.313887) (xy 66.329228 -460.314649) (xy 67.283576 -460.314649)
			(xy 67.283576 -460.243327) (xy 67.291562 -460.172453) (xy 67.307432 -460.102918) (xy 67.330989 -460.035598)
			(xy 67.361934 -459.971339) (xy 67.39988 -459.910948) (xy 67.444349 -459.855186) (xy 67.494782 -459.804753)
			(xy 67.550544 -459.760284) (xy 67.610935 -459.722338) (xy 67.675194 -459.691393) (xy 67.742514 -459.667836)
			(xy 67.812049 -459.651966) (xy 67.882923 -459.64398) (xy 67.918584 -459.64348) (xy 67.954245 -459.64398)
			(xy 68.025119 -459.651966) (xy 68.094654 -459.667836) (xy 68.161974 -459.691393) (xy 68.226233 -459.722338)
			(xy 68.286624 -459.760284) (xy 68.342386 -459.804753) (xy 68.392819 -459.855186) (xy 68.437288 -459.910948)
			(xy 68.475234 -459.971339) (xy 68.506179 -460.035598) (xy 68.529736 -460.102918) (xy 68.545606 -460.172453)
			(xy 68.553592 -460.243327) (xy 68.553592 -460.314649) (xy 68.545606 -460.385523) (xy 68.529736 -460.455058)
			(xy 68.506179 -460.522378) (xy 68.475234 -460.586637) (xy 68.437288 -460.647028) (xy 68.392819 -460.70279)
			(xy 68.342386 -460.753223) (xy 68.286624 -460.797692) (xy 68.226233 -460.835638) (xy 68.161974 -460.866583)
			(xy 68.094654 -460.89014) (xy 68.025119 -460.90601) (xy 67.954245 -460.913996) (xy 67.882923 -460.913996)
			(xy 67.812049 -460.90601) (xy 67.742514 -460.89014) (xy 67.675194 -460.866583) (xy 67.610935 -460.835638)
			(xy 67.550544 -460.797692) (xy 67.494782 -460.753223) (xy 67.444349 -460.70279) (xy 67.39988 -460.647028)
			(xy 67.361934 -460.586637) (xy 67.330989 -460.522378) (xy 67.307432 -460.455058) (xy 67.291562 -460.385523)
			(xy 67.283576 -460.314649) (xy 66.329228 -460.314649) (xy 66.321328 -460.384761) (xy 66.305458 -460.454296)
			(xy 66.281901 -460.521616) (xy 66.250956 -460.585875) (xy 66.21301 -460.646266) (xy 66.168541 -460.702028)
			(xy 66.118108 -460.752461) (xy 66.062346 -460.79693) (xy 66.001955 -460.834876) (xy 65.937696 -460.865821)
			(xy 65.870376 -460.889378) (xy 65.800841 -460.905248) (xy 65.729967 -460.913234) (xy 65.658645 -460.913234)
			(xy 65.587771 -460.905248) (xy 65.518236 -460.889378) (xy 65.450916 -460.865821) (xy 65.386657 -460.834876)
			(xy 65.326266 -460.79693) (xy 65.270504 -460.752461) (xy 65.220071 -460.702028) (xy 65.175602 -460.646266)
			(xy 65.137656 -460.585875) (xy 65.106711 -460.521616) (xy 65.083154 -460.454296) (xy 65.067284 -460.384761)
			(xy 65.059298 -460.313887) (xy 64.25388 -460.313887) (xy 64.245894 -460.384761) (xy 64.230024 -460.454296)
			(xy 64.206467 -460.521616) (xy 64.175522 -460.585875) (xy 64.137576 -460.646266) (xy 64.093107 -460.702028)
			(xy 64.042674 -460.752461) (xy 63.986912 -460.79693) (xy 63.926521 -460.834876) (xy 63.862262 -460.865821)
			(xy 63.794942 -460.889378) (xy 63.725407 -460.905248) (xy 63.654533 -460.913234) (xy 63.583211 -460.913234)
			(xy 63.512337 -460.905248) (xy 63.442802 -460.889378) (xy 63.375482 -460.865821) (xy 63.311223 -460.834876)
			(xy 63.250832 -460.79693) (xy 63.19507 -460.752461) (xy 63.144637 -460.702028) (xy 63.100168 -460.646266)
			(xy 63.062222 -460.585875) (xy 63.031277 -460.521616) (xy 63.00772 -460.454296) (xy 62.99185 -460.384761)
			(xy 62.983864 -460.313887) (xy 28.019966 -460.313887) (xy 28.019752 -460.319754) (xy 28.009622 -460.374597)
			(xy 27.991615 -460.427381) (xy 27.966114 -460.476981) (xy 27.933663 -460.522339) (xy 27.894954 -460.562488)
			(xy 27.850811 -460.596574) (xy 27.802176 -460.62387) (xy 27.750085 -460.643793) (xy 27.695648 -460.655919)
			(xy 27.640026 -460.65999) (xy 27.584404 -460.655919) (xy 27.529967 -460.643793) (xy 27.477876 -460.62387)
			(xy 27.429241 -460.596574) (xy 27.385098 -460.562488) (xy 27.346389 -460.522339) (xy 27.313938 -460.476981)
			(xy 27.288437 -460.427381) (xy 27.27043 -460.374597) (xy 27.2603 -460.319754) (xy 27.258263 -460.26402)
			(xy 25.171715 -460.26402) (xy 26.781178 -461.873362) (xy 29.519874 -461.873362) (xy 29.519874 -461.786462)
			(xy 29.527892 -461.699933) (xy 29.54386 -461.614513) (xy 29.567641 -461.530931) (xy 29.599033 -461.449899)
			(xy 29.637767 -461.37211) (xy 29.683514 -461.298226) (xy 29.735883 -461.228879) (xy 29.794427 -461.164659)
			(xy 29.858647 -461.106115) (xy 29.927994 -461.053746) (xy 30.001878 -461.007999) (xy 30.079667 -460.969265)
			(xy 30.160699 -460.937873) (xy 30.244281 -460.914092) (xy 30.329701 -460.898124) (xy 30.41623 -460.890106)
			(xy 30.45968 -460.889604) (xy 30.50313 -460.890106) (xy 30.589659 -460.898124) (xy 30.675079 -460.914092)
			(xy 30.758661 -460.937873) (xy 30.839693 -460.969265) (xy 30.917482 -461.007999) (xy 30.991366 -461.053746)
			(xy 31.060713 -461.106115) (xy 31.124933 -461.164659) (xy 31.183477 -461.228879) (xy 31.235846 -461.298226)
			(xy 31.281593 -461.37211) (xy 31.320327 -461.449899) (xy 31.351719 -461.530931) (xy 31.3755 -461.614513)
			(xy 31.391468 -461.699933) (xy 31.399486 -461.786462) (xy 31.399486 -461.873362) (xy 34.599874 -461.873362)
			(xy 34.599874 -461.786462) (xy 34.607892 -461.699933) (xy 34.62386 -461.614513) (xy 34.647641 -461.530931)
			(xy 34.679033 -461.449899) (xy 34.717767 -461.37211) (xy 34.763514 -461.298226) (xy 34.815883 -461.228879)
			(xy 34.874427 -461.164659) (xy 34.938647 -461.106115) (xy 35.007994 -461.053746) (xy 35.081878 -461.007999)
			(xy 35.159667 -460.969265) (xy 35.240699 -460.937873) (xy 35.324281 -460.914092) (xy 35.409701 -460.898124)
			(xy 35.49623 -460.890106) (xy 35.53968 -460.889604) (xy 35.58313 -460.890106) (xy 35.669659 -460.898124)
			(xy 35.755079 -460.914092) (xy 35.838661 -460.937873) (xy 35.919693 -460.969265) (xy 35.997482 -461.007999)
			(xy 36.071366 -461.053746) (xy 36.140713 -461.106115) (xy 36.204933 -461.164659) (xy 36.263477 -461.228879)
			(xy 36.315846 -461.298226) (xy 36.361593 -461.37211) (xy 36.400327 -461.449899) (xy 36.431719 -461.530931)
			(xy 36.4555 -461.614513) (xy 36.471468 -461.699933) (xy 36.479486 -461.786462) (xy 36.479486 -461.873362)
			(xy 36.471468 -461.959891) (xy 36.4555 -462.045311) (xy 36.4455 -462.080457) (xy 62.983864 -462.080457)
			(xy 62.983864 -462.009135) (xy 62.99185 -461.938261) (xy 63.00772 -461.868726) (xy 63.031277 -461.801406)
			(xy 63.062222 -461.737147) (xy 63.100168 -461.676756) (xy 63.144637 -461.620994) (xy 63.19507 -461.570561)
			(xy 63.250832 -461.526092) (xy 63.311223 -461.488146) (xy 63.375482 -461.457201) (xy 63.442802 -461.433644)
			(xy 63.512337 -461.417774) (xy 63.583211 -461.409788) (xy 63.618872 -461.409288) (xy 63.654533 -461.409788)
			(xy 63.725407 -461.417774) (xy 63.794942 -461.433644) (xy 63.862262 -461.457201) (xy 63.926521 -461.488146)
			(xy 63.986912 -461.526092) (xy 64.042674 -461.570561) (xy 64.093107 -461.620994) (xy 64.137576 -461.676756)
			(xy 64.175522 -461.737147) (xy 64.206467 -461.801406) (xy 64.230024 -461.868726) (xy 64.245894 -461.938261)
			(xy 64.25388 -462.009135) (xy 64.25388 -462.080457) (xy 65.059298 -462.080457) (xy 65.059298 -462.009135)
			(xy 65.067284 -461.938261) (xy 65.083154 -461.868726) (xy 65.106711 -461.801406) (xy 65.137656 -461.737147)
			(xy 65.175602 -461.676756) (xy 65.220071 -461.620994) (xy 65.270504 -461.570561) (xy 65.326266 -461.526092)
			(xy 65.386657 -461.488146) (xy 65.450916 -461.457201) (xy 65.518236 -461.433644) (xy 65.587771 -461.417774)
			(xy 65.658645 -461.409788) (xy 65.694306 -461.409288) (xy 65.729967 -461.409788) (xy 65.800841 -461.417774)
			(xy 65.870376 -461.433644) (xy 65.937696 -461.457201) (xy 66.001955 -461.488146) (xy 66.062346 -461.526092)
			(xy 66.118108 -461.570561) (xy 66.168541 -461.620994) (xy 66.21301 -461.676756) (xy 66.250956 -461.737147)
			(xy 66.281901 -461.801406) (xy 66.305458 -461.868726) (xy 66.321328 -461.938261) (xy 66.329314 -462.009135)
			(xy 66.329314 -462.080457) (xy 66.329228 -462.081219) (xy 67.283576 -462.081219) (xy 67.283576 -462.009897)
			(xy 67.291562 -461.939023) (xy 67.307432 -461.869488) (xy 67.330989 -461.802168) (xy 67.361934 -461.737909)
			(xy 67.39988 -461.677518) (xy 67.444349 -461.621756) (xy 67.494782 -461.571323) (xy 67.550544 -461.526854)
			(xy 67.610935 -461.488908) (xy 67.675194 -461.457963) (xy 67.742514 -461.434406) (xy 67.812049 -461.418536)
			(xy 67.882923 -461.41055) (xy 67.918584 -461.41005) (xy 67.954245 -461.41055) (xy 68.025119 -461.418536)
			(xy 68.094654 -461.434406) (xy 68.161974 -461.457963) (xy 68.226233 -461.488908) (xy 68.286624 -461.526854)
			(xy 68.342386 -461.571323) (xy 68.392819 -461.621756) (xy 68.437288 -461.677518) (xy 68.475234 -461.737909)
			(xy 68.506179 -461.802168) (xy 68.529736 -461.869488) (xy 68.545606 -461.939023) (xy 68.553592 -462.009897)
			(xy 68.553592 -462.081219) (xy 68.545606 -462.152093) (xy 68.529736 -462.221628) (xy 68.506179 -462.288948)
			(xy 68.475234 -462.353207) (xy 68.437288 -462.413598) (xy 68.392819 -462.46936) (xy 68.342386 -462.519793)
			(xy 68.286624 -462.564262) (xy 68.226233 -462.602208) (xy 68.161974 -462.633153) (xy 68.094654 -462.65671)
			(xy 68.025119 -462.67258) (xy 67.954245 -462.680566) (xy 67.882923 -462.680566) (xy 67.812049 -462.67258)
			(xy 67.742514 -462.65671) (xy 67.675194 -462.633153) (xy 67.610935 -462.602208) (xy 67.550544 -462.564262)
			(xy 67.494782 -462.519793) (xy 67.444349 -462.46936) (xy 67.39988 -462.413598) (xy 67.361934 -462.353207)
			(xy 67.330989 -462.288948) (xy 67.307432 -462.221628) (xy 67.291562 -462.152093) (xy 67.283576 -462.081219)
			(xy 66.329228 -462.081219) (xy 66.321328 -462.151331) (xy 66.305458 -462.220866) (xy 66.281901 -462.288186)
			(xy 66.250956 -462.352445) (xy 66.21301 -462.412836) (xy 66.168541 -462.468598) (xy 66.118108 -462.519031)
			(xy 66.062346 -462.5635) (xy 66.001955 -462.601446) (xy 65.937696 -462.632391) (xy 65.870376 -462.655948)
			(xy 65.800841 -462.671818) (xy 65.729967 -462.679804) (xy 65.658645 -462.679804) (xy 65.587771 -462.671818)
			(xy 65.518236 -462.655948) (xy 65.450916 -462.632391) (xy 65.386657 -462.601446) (xy 65.326266 -462.5635)
			(xy 65.270504 -462.519031) (xy 65.220071 -462.468598) (xy 65.175602 -462.412836) (xy 65.137656 -462.352445)
			(xy 65.106711 -462.288186) (xy 65.083154 -462.220866) (xy 65.067284 -462.151331) (xy 65.059298 -462.080457)
			(xy 64.25388 -462.080457) (xy 64.245894 -462.151331) (xy 64.230024 -462.220866) (xy 64.206467 -462.288186)
			(xy 64.175522 -462.352445) (xy 64.137576 -462.412836) (xy 64.093107 -462.468598) (xy 64.042674 -462.519031)
			(xy 63.986912 -462.5635) (xy 63.926521 -462.601446) (xy 63.862262 -462.632391) (xy 63.794942 -462.655948)
			(xy 63.725407 -462.671818) (xy 63.654533 -462.679804) (xy 63.583211 -462.679804) (xy 63.512337 -462.671818)
			(xy 63.442802 -462.655948) (xy 63.375482 -462.632391) (xy 63.311223 -462.601446) (xy 63.250832 -462.5635)
			(xy 63.19507 -462.519031) (xy 63.144637 -462.468598) (xy 63.100168 -462.412836) (xy 63.062222 -462.352445)
			(xy 63.031277 -462.288186) (xy 63.00772 -462.220866) (xy 62.99185 -462.151331) (xy 62.983864 -462.080457)
			(xy 36.4455 -462.080457) (xy 36.431719 -462.128893) (xy 36.400327 -462.209925) (xy 36.36847 -462.273904)
			(xy 51.322732 -462.273904) (xy 52.974748 -462.273904) (xy 52.974748 -463.895287) (xy 62.938144 -463.895287)
			(xy 62.938144 -463.823965) (xy 62.94613 -463.753091) (xy 62.962 -463.683556) (xy 62.985557 -463.616236)
			(xy 63.016502 -463.551977) (xy 63.054448 -463.491586) (xy 63.098917 -463.435824) (xy 63.14935 -463.385391)
			(xy 63.205112 -463.340922) (xy 63.265503 -463.302976) (xy 63.329762 -463.272031) (xy 63.397082 -463.248474)
			(xy 63.466617 -463.232604) (xy 63.537491 -463.224618) (xy 63.573152 -463.224118) (xy 63.608813 -463.224618)
			(xy 63.679687 -463.232604) (xy 63.749222 -463.248474) (xy 63.816542 -463.272031) (xy 63.880801 -463.302976)
			(xy 63.941192 -463.340922) (xy 63.996954 -463.385391) (xy 64.047387 -463.435824) (xy 64.091856 -463.491586)
			(xy 64.129802 -463.551977) (xy 64.160747 -463.616236) (xy 64.184304 -463.683556) (xy 64.200174 -463.753091)
			(xy 64.20816 -463.823965) (xy 64.20816 -463.895287) (xy 65.013578 -463.895287) (xy 65.013578 -463.823965)
			(xy 65.021564 -463.753091) (xy 65.037434 -463.683556) (xy 65.060991 -463.616236) (xy 65.091936 -463.551977)
			(xy 65.129882 -463.491586) (xy 65.174351 -463.435824) (xy 65.224784 -463.385391) (xy 65.280546 -463.340922)
			(xy 65.340937 -463.302976) (xy 65.405196 -463.272031) (xy 65.472516 -463.248474) (xy 65.542051 -463.232604)
			(xy 65.612925 -463.224618) (xy 65.648586 -463.224118) (xy 65.684247 -463.224618) (xy 65.755121 -463.232604)
			(xy 65.824656 -463.248474) (xy 65.891976 -463.272031) (xy 65.956235 -463.302976) (xy 66.016626 -463.340922)
			(xy 66.072388 -463.385391) (xy 66.122821 -463.435824) (xy 66.16729 -463.491586) (xy 66.205236 -463.551977)
			(xy 66.236181 -463.616236) (xy 66.259738 -463.683556) (xy 66.275608 -463.753091) (xy 66.283594 -463.823965)
			(xy 66.283594 -463.895287) (xy 66.283508 -463.896049) (xy 67.19239 -463.896049) (xy 67.19239 -463.824727)
			(xy 67.200376 -463.753853) (xy 67.216246 -463.684318) (xy 67.239803 -463.616998) (xy 67.270748 -463.552739)
			(xy 67.308694 -463.492348) (xy 67.353163 -463.436586) (xy 67.403596 -463.386153) (xy 67.459358 -463.341684)
			(xy 67.519749 -463.303738) (xy 67.584008 -463.272793) (xy 67.651328 -463.249236) (xy 67.720863 -463.233366)
			(xy 67.791737 -463.22538) (xy 67.827398 -463.22488) (xy 67.863059 -463.22538) (xy 67.933933 -463.233366)
			(xy 68.003468 -463.249236) (xy 68.070788 -463.272793) (xy 68.135047 -463.303738) (xy 68.195438 -463.341684)
			(xy 68.2512 -463.386153) (xy 68.301633 -463.436586) (xy 68.346102 -463.492348) (xy 68.384048 -463.552739)
			(xy 68.414993 -463.616998) (xy 68.43855 -463.684318) (xy 68.45442 -463.753853) (xy 68.462406 -463.824727)
			(xy 68.462406 -463.896049) (xy 68.45442 -463.966923) (xy 68.43855 -464.036458) (xy 68.414993 -464.103778)
			(xy 68.384048 -464.168037) (xy 68.346102 -464.228428) (xy 68.301633 -464.28419) (xy 68.2512 -464.334623)
			(xy 68.195438 -464.379092) (xy 68.135047 -464.417038) (xy 68.070788 -464.447983) (xy 68.003468 -464.47154)
			(xy 67.933933 -464.48741) (xy 67.863059 -464.495396) (xy 67.791737 -464.495396) (xy 67.720863 -464.48741)
			(xy 67.651328 -464.47154) (xy 67.584008 -464.447983) (xy 67.519749 -464.417038) (xy 67.459358 -464.379092)
			(xy 67.403596 -464.334623) (xy 67.353163 -464.28419) (xy 67.308694 -464.228428) (xy 67.270748 -464.168037)
			(xy 67.239803 -464.103778) (xy 67.216246 -464.036458) (xy 67.200376 -463.966923) (xy 67.19239 -463.896049)
			(xy 66.283508 -463.896049) (xy 66.275608 -463.966161) (xy 66.259738 -464.035696) (xy 66.236181 -464.103016)
			(xy 66.205236 -464.167275) (xy 66.16729 -464.227666) (xy 66.122821 -464.283428) (xy 66.072388 -464.333861)
			(xy 66.016626 -464.37833) (xy 65.956235 -464.416276) (xy 65.891976 -464.447221) (xy 65.824656 -464.470778)
			(xy 65.755121 -464.486648) (xy 65.684247 -464.494634) (xy 65.612925 -464.494634) (xy 65.542051 -464.486648)
			(xy 65.472516 -464.470778) (xy 65.405196 -464.447221) (xy 65.340937 -464.416276) (xy 65.280546 -464.37833)
			(xy 65.224784 -464.333861) (xy 65.174351 -464.283428) (xy 65.129882 -464.227666) (xy 65.091936 -464.167275)
			(xy 65.060991 -464.103016) (xy 65.037434 -464.035696) (xy 65.021564 -463.966161) (xy 65.013578 -463.895287)
			(xy 64.20816 -463.895287) (xy 64.200174 -463.966161) (xy 64.184304 -464.035696) (xy 64.160747 -464.103016)
			(xy 64.129802 -464.167275) (xy 64.091856 -464.227666) (xy 64.047387 -464.283428) (xy 63.996954 -464.333861)
			(xy 63.941192 -464.37833) (xy 63.880801 -464.416276) (xy 63.816542 -464.447221) (xy 63.749222 -464.470778)
			(xy 63.679687 -464.486648) (xy 63.608813 -464.494634) (xy 63.537491 -464.494634) (xy 63.466617 -464.486648)
			(xy 63.397082 -464.470778) (xy 63.329762 -464.447221) (xy 63.265503 -464.416276) (xy 63.205112 -464.37833)
			(xy 63.14935 -464.333861) (xy 63.098917 -464.283428) (xy 63.054448 -464.227666) (xy 63.016502 -464.167275)
			(xy 62.985557 -464.103016) (xy 62.962 -464.035696) (xy 62.94613 -463.966161) (xy 62.938144 -463.895287)
			(xy 52.974748 -463.895287) (xy 52.974748 -463.925412) (xy 51.322732 -463.925412) (xy 51.322732 -462.273904)
			(xy 36.36847 -462.273904) (xy 36.361593 -462.287714) (xy 36.315846 -462.361598) (xy 36.263477 -462.430945)
			(xy 36.204933 -462.495165) (xy 36.140713 -462.553709) (xy 36.071366 -462.606078) (xy 35.997482 -462.651825)
			(xy 35.919693 -462.690559) (xy 35.838661 -462.721951) (xy 35.755079 -462.745732) (xy 35.669659 -462.7617)
			(xy 35.58313 -462.769718) (xy 35.49623 -462.769718) (xy 35.409701 -462.7617) (xy 35.324281 -462.745732)
			(xy 35.240699 -462.721951) (xy 35.159667 -462.690559) (xy 35.081878 -462.651825) (xy 35.007994 -462.606078)
			(xy 34.938647 -462.553709) (xy 34.874427 -462.495165) (xy 34.815883 -462.430945) (xy 34.763514 -462.361598)
			(xy 34.717767 -462.287714) (xy 34.679033 -462.209925) (xy 34.647641 -462.128893) (xy 34.62386 -462.045311)
			(xy 34.607892 -461.959891) (xy 34.599874 -461.873362) (xy 31.399486 -461.873362) (xy 31.391468 -461.959891)
			(xy 31.3755 -462.045311) (xy 31.351719 -462.128893) (xy 31.320327 -462.209925) (xy 31.281593 -462.287714)
			(xy 31.235846 -462.361598) (xy 31.183477 -462.430945) (xy 31.124933 -462.495165) (xy 31.060713 -462.553709)
			(xy 30.991366 -462.606078) (xy 30.917482 -462.651825) (xy 30.839693 -462.690559) (xy 30.758661 -462.721951)
			(xy 30.675079 -462.745732) (xy 30.589659 -462.7617) (xy 30.50313 -462.769718) (xy 30.41623 -462.769718)
			(xy 30.329701 -462.7617) (xy 30.244281 -462.745732) (xy 30.160699 -462.721951) (xy 30.079667 -462.690559)
			(xy 30.001878 -462.651825) (xy 29.927994 -462.606078) (xy 29.858647 -462.553709) (xy 29.794427 -462.495165)
			(xy 29.735883 -462.430945) (xy 29.683514 -462.361598) (xy 29.637767 -462.287714) (xy 29.599033 -462.209925)
			(xy 29.567641 -462.128893) (xy 29.54386 -462.045311) (xy 29.527892 -461.959891) (xy 29.519874 -461.873362)
			(xy 26.781178 -461.873362) (xy 27.981656 -463.07375) (xy 28.003658 -463.096483) (xy 28.042171 -463.146675)
			(xy 28.073804 -463.201464) (xy 28.098015 -463.259914) (xy 28.114389 -463.321023) (xy 28.122647 -463.383747)
			(xy 28.122647 -463.447013) (xy 28.114389 -463.509737) (xy 28.098015 -463.570846) (xy 28.073804 -463.629296)
			(xy 28.042171 -463.684085) (xy 28.003658 -463.734277) (xy 27.958923 -463.779012) (xy 27.908731 -463.817525)
			(xy 27.853942 -463.849158) (xy 27.795492 -463.873369) (xy 27.734383 -463.889743) (xy 27.671659 -463.898001)
			(xy 27.608393 -463.898001) (xy 27.545669 -463.889743) (xy 27.48456 -463.873369) (xy 27.42611 -463.849158)
			(xy 27.371321 -463.817525) (xy 27.321129 -463.779012) (xy 27.298396 -463.75701) (xy 24.11476 -460.57312)
			(xy 24.102628 -460.561679) (xy 24.073761 -460.545002) (xy 24.041561 -460.536371) (xy 24.008224 -460.536373)
			(xy 23.976024 -460.545008) (xy 23.94716 -460.561688) (xy 23.9236 -460.585275) (xy 23.906953 -460.614158)
			(xy 23.898354 -460.646367) (xy 23.897844 -460.663036) (xy 23.897844 -460.781146) (xy 28.350464 -465.233512)
			(xy 29.432758 -465.233512) (xy 29.455067 -465.23305) (xy 29.499001 -465.225266) (xy 29.5409 -465.209929)
			(xy 29.579477 -465.187512) (xy 29.613547 -465.158703) (xy 29.642063 -465.124387) (xy 29.664149 -465.085618)
			(xy 29.679125 -465.043589) (xy 29.686531 -464.99959) (xy 29.686141 -464.954974) (xy 29.677966 -464.911112)
			(xy 29.662257 -464.869351) (xy 29.651198 -464.849972) (xy 29.629625 -464.812692) (xy 29.592606 -464.734916)
			(xy 29.562856 -464.654079) (xy 29.540624 -464.570861) (xy 29.526096 -464.485957) (xy 29.519396 -464.400081)
			(xy 29.520578 -464.313952) (xy 29.529632 -464.228292) (xy 29.546484 -464.143819) (xy 29.570991 -464.061242)
			(xy 29.602949 -463.981252) (xy 29.642089 -463.90452) (xy 29.688083 -463.831691) (xy 29.740545 -463.763373)
			(xy 29.799036 -463.70014) (xy 29.863066 -463.642522) (xy 29.932097 -463.591002) (xy 30.005551 -463.546011)
			(xy 30.082813 -463.507928) (xy 30.163233 -463.477071) (xy 30.246139 -463.4537) (xy 30.330835 -463.438009)
			(xy 30.416611 -463.43013) (xy 30.502749 -463.43013) (xy 30.588525 -463.438009) (xy 30.673221 -463.4537)
			(xy 30.756127 -463.477071) (xy 30.836547 -463.507928) (xy 30.913809 -463.546011) (xy 30.987263 -463.591002)
			(xy 31.056294 -463.642522) (xy 31.120324 -463.70014) (xy 31.178815 -463.763373) (xy 31.231277 -463.831691)
			(xy 31.277271 -463.90452) (xy 31.316411 -463.981252) (xy 31.348369 -464.061242) (xy 31.372876 -464.143819)
			(xy 31.389728 -464.228292) (xy 31.398782 -464.313952) (xy 31.399964 -464.400081) (xy 31.393264 -464.485957)
			(xy 31.378736 -464.570861) (xy 31.356504 -464.654079) (xy 31.326754 -464.734916) (xy 31.289735 -464.812692)
			(xy 31.268162 -464.849972) (xy 31.257188 -464.869392) (xy 31.241487 -464.91114) (xy 31.233316 -464.954987)
			(xy 31.232927 -464.999588) (xy 31.240331 -465.043572) (xy 31.255302 -465.085587) (xy 31.277378 -465.124343)
			(xy 31.305882 -465.158649) (xy 31.339938 -465.187451) (xy 31.3785 -465.209865) (xy 31.420383 -465.225201)
			(xy 31.464301 -465.232988) (xy 31.486602 -465.233512) (xy 34.512758 -465.233512) (xy 34.535067 -465.23305)
			(xy 34.579001 -465.225266) (xy 34.6209 -465.209929) (xy 34.659477 -465.187512) (xy 34.693547 -465.158703)
			(xy 34.722063 -465.124387) (xy 34.744149 -465.085618) (xy 34.759125 -465.043589) (xy 34.766531 -464.99959)
			(xy 34.766141 -464.954974) (xy 34.757966 -464.911112) (xy 34.742257 -464.869351) (xy 34.731198 -464.849972)
			(xy 34.709625 -464.812692) (xy 34.672606 -464.734916) (xy 34.642856 -464.654079) (xy 34.620624 -464.570861)
			(xy 34.606096 -464.485957) (xy 34.599396 -464.400081) (xy 34.600578 -464.313952) (xy 34.609632 -464.228292)
			(xy 34.626484 -464.143819) (xy 34.650991 -464.061242) (xy 34.682949 -463.981252) (xy 34.722089 -463.90452)
			(xy 34.768083 -463.831691) (xy 34.820545 -463.763373) (xy 34.879036 -463.70014) (xy 34.943066 -463.642522)
			(xy 35.012097 -463.591002) (xy 35.085551 -463.546011) (xy 35.162813 -463.507928) (xy 35.243233 -463.477071)
			(xy 35.326139 -463.4537) (xy 35.410835 -463.438009) (xy 35.496611 -463.43013) (xy 35.582749 -463.43013)
			(xy 35.668525 -463.438009) (xy 35.753221 -463.4537) (xy 35.836127 -463.477071) (xy 35.916547 -463.507928)
			(xy 35.993809 -463.546011) (xy 36.013621 -463.558146) (xy 40.023287 -463.558146) (xy 40.029387 -463.502709)
			(xy 40.043493 -463.448752) (xy 40.065305 -463.397423) (xy 40.094359 -463.349817) (xy 40.130034 -463.306949)
			(xy 40.171571 -463.269732) (xy 40.218084 -463.238959) (xy 40.268581 -463.215287) (xy 40.321988 -463.199219)
			(xy 40.377164 -463.191099) (xy 40.40505 -463.19059) (xy 40.432936 -463.191099) (xy 40.488112 -463.199219)
			(xy 40.541519 -463.215287) (xy 40.592016 -463.238959) (xy 40.638529 -463.269732) (xy 40.680066 -463.306949)
			(xy 40.715741 -463.349817) (xy 40.744795 -463.397423) (xy 40.766607 -463.448752) (xy 40.780713 -463.502709)
			(xy 40.786813 -463.558146) (xy 40.784776 -463.61388) (xy 40.774646 -463.668723) (xy 40.756639 -463.721507)
			(xy 40.731138 -463.771107) (xy 40.698687 -463.816465) (xy 40.659978 -463.856614) (xy 40.615835 -463.8907)
			(xy 40.5672 -463.917996) (xy 40.515109 -463.937919) (xy 40.460672 -463.950045) (xy 40.40505 -463.954116)
			(xy 40.349428 -463.950045) (xy 40.294991 -463.937919) (xy 40.2429 -463.917996) (xy 40.194265 -463.8907)
			(xy 40.150122 -463.856614) (xy 40.111413 -463.816465) (xy 40.078962 -463.771107) (xy 40.053461 -463.721507)
			(xy 40.035454 -463.668723) (xy 40.025324 -463.61388) (xy 40.023287 -463.558146) (xy 36.013621 -463.558146)
			(xy 36.067263 -463.591002) (xy 36.136294 -463.642522) (xy 36.200324 -463.70014) (xy 36.258815 -463.763373)
			(xy 36.311277 -463.831691) (xy 36.357271 -463.90452) (xy 36.396411 -463.981252) (xy 36.428369 -464.061242)
			(xy 36.452876 -464.143819) (xy 36.469728 -464.228292) (xy 36.478782 -464.313952) (xy 36.479964 -464.400081)
			(xy 36.473264 -464.485957) (xy 36.458736 -464.570861) (xy 36.436504 -464.654079) (xy 36.406754 -464.734916)
			(xy 36.369735 -464.812692) (xy 36.348162 -464.849972) (xy 36.337188 -464.869392) (xy 36.321487 -464.91114)
			(xy 36.313316 -464.954987) (xy 36.312927 -464.999588) (xy 36.320331 -465.043572) (xy 36.335302 -465.085587)
			(xy 36.357378 -465.124343) (xy 36.385882 -465.158649) (xy 36.419938 -465.187451) (xy 36.4585 -465.209865)
			(xy 36.500383 -465.225201) (xy 36.544301 -465.232988) (xy 36.566602 -465.233512) (xy 37.280596 -465.233512)
			(xy 37.826696 -464.687412) (xy 40.594788 -464.687412) (xy 40.628824 -464.688682) (xy 40.644946 -464.689335)
			(xy 40.67666 -464.683444) (xy 40.705883 -464.669786) (xy 40.730743 -464.649233) (xy 40.749653 -464.6231)
			(xy 40.761401 -464.593059) (xy 40.765237 -464.561031) (xy 40.760915 -464.529065) (xy 40.755316 -464.51393)
			(xy 40.745264 -464.48813) (xy 40.731871 -464.434404) (xy 40.726385 -464.379307) (xy 40.72892 -464.323996)
			(xy 40.739424 -464.269631) (xy 40.757676 -464.217356) (xy 40.783292 -464.168269) (xy 40.815735 -464.123399)
			(xy 40.854323 -464.08369) (xy 40.898245 -464.049976) (xy 40.946579 -464.022965) (xy 40.99831 -464.003224)
			(xy 41.052351 -463.991168) (xy 41.107567 -463.987049) (xy 41.162799 -463.990956) (xy 41.216886 -464.002805)
			(xy 41.268692 -464.022347) (xy 41.31713 -464.049173) (xy 41.361181 -464.082718) (xy 41.39992 -464.122279)
			(xy 41.432535 -464.167023) (xy 41.458339 -464.216012) (xy 41.476791 -464.268217) (xy 41.487504 -464.322541)
			(xy 41.490251 -464.377842) (xy 41.484976 -464.43296) (xy 41.47179 -464.486736) (xy 41.450969 -464.538042)
			(xy 41.437845 -464.560411) (xy 86.399122 -464.560411) (xy 86.401115 -464.360283) (xy 86.411112 -464.160394)
			(xy 86.429099 -463.961066) (xy 86.455047 -463.762617) (xy 86.488914 -463.565365) (xy 86.530646 -463.369626)
			(xy 86.580175 -463.175713) (xy 86.637424 -462.983938) (xy 86.702299 -462.794606) (xy 86.774698 -462.608022)
			(xy 86.854504 -462.424483) (xy 86.941589 -462.244285) (xy 87.035814 -462.067715) (xy 87.137028 -461.895056)
			(xy 87.245069 -461.726586) (xy 87.359764 -461.562572) (xy 87.48093 -461.403279) (xy 87.608371 -461.248962)
			(xy 87.741885 -461.099866) (xy 87.881257 -460.956232) (xy 88.026264 -460.81829) (xy 88.176675 -460.686259)
			(xy 88.332247 -460.560352) (xy 88.492732 -460.44077) (xy 88.657873 -460.327705) (xy 88.827405 -460.221337)
			(xy 89.001058 -460.121838) (xy 89.178552 -460.029366) (xy 89.359604 -459.94407) (xy 89.543924 -459.866086)
			(xy 89.731216 -459.795538) (xy 89.921181 -459.732541) (xy 90.113514 -459.677195) (xy 90.307908 -459.629588)
			(xy 90.504051 -459.589797) (xy 90.701628 -459.557885) (xy 90.900325 -459.533904) (xy 91.099821 -459.517891)
			(xy 91.299799 -459.509874) (xy 91.399868 -459.509368) (xy 91.499937 -459.509864) (xy 91.699915 -459.517861)
			(xy 91.899414 -459.533853) (xy 92.098112 -459.557814) (xy 92.295693 -459.589706) (xy 92.49184 -459.629477)
			(xy 92.686239 -459.677064) (xy 92.878578 -459.732391) (xy 93.068549 -459.795369) (xy 93.255848 -459.865897)
			(xy 93.440176 -459.943863) (xy 93.621237 -460.029141) (xy 93.79874 -460.121594) (xy 93.972403 -460.221076)
			(xy 94.141946 -460.327426) (xy 94.307099 -460.440475) (xy 94.467596 -460.56004) (xy 94.623181 -460.685932)
			(xy 94.773605 -460.817947) (xy 94.918626 -460.955875) (xy 95.058012 -461.099495) (xy 95.191541 -461.248576)
			(xy 95.318999 -461.402881) (xy 95.44018 -461.562162) (xy 95.554892 -461.726163) (xy 95.66295 -461.894623)
			(xy 95.764182 -462.067272) (xy 95.858425 -462.243832) (xy 95.945528 -462.424022) (xy 96.025353 -462.607552)
			(xy 96.09777 -462.794129) (xy 96.162665 -462.983454) (xy 96.219933 -463.175224) (xy 96.269483 -463.369131)
			(xy 96.311234 -463.564866) (xy 96.345121 -463.762115) (xy 96.371089 -463.960561) (xy 96.389096 -464.159888)
			(xy 96.399114 -464.359775) (xy 96.401127 -464.559903) (xy 96.395131 -464.759951) (xy 96.381135 -464.9596)
			(xy 96.359164 -465.158528) (xy 96.32925 -465.356418) (xy 96.291443 -465.552953) (xy 96.245804 -465.747818)
			(xy 96.192404 -465.940701) (xy 96.13133 -466.131293) (xy 96.062679 -466.319288) (xy 95.986561 -466.504387)
			(xy 95.903099 -466.686292) (xy 95.812426 -466.864711) (xy 95.714687 -467.039361) (xy 95.610038 -467.20996)
			(xy 95.498648 -467.376235) (xy 95.380694 -467.53792) (xy 95.256365 -467.694757) (xy 95.125862 -467.846494)
			(xy 94.989391 -467.992888) (xy 94.847173 -468.133704) (xy 94.699435 -468.268718) (xy 94.546413 -468.397713)
			(xy 94.388353 -468.520482) (xy 94.225507 -468.636829) (xy 94.058137 -468.746567) (xy 93.88651 -468.849521)
			(xy 93.710902 -468.945526) (xy 93.531592 -469.034428) (xy 93.34887 -469.116084) (xy 93.163027 -469.190365)
			(xy 92.97436 -469.257151) (xy 92.783173 -469.316334) (xy 92.589771 -469.367821) (xy 92.394464 -469.411529)
			(xy 92.197564 -469.447388) (xy 91.999387 -469.47534) (xy 91.800251 -469.49534) (xy 91.600474 -469.507358)
			(xy 91.400376 -469.511372) (xy 91.200278 -469.507378) (xy 91.000499 -469.495381) (xy 90.801361 -469.475401)
			(xy 90.603182 -469.447469) (xy 90.406278 -469.41163) (xy 90.210967 -469.367942) (xy 90.017559 -469.316475)
			(xy 89.826366 -469.257311) (xy 89.637693 -469.190544) (xy 89.451842 -469.116282) (xy 89.269111 -469.034644)
			(xy 89.089793 -468.945761) (xy 88.914175 -468.849774) (xy 88.742537 -468.746837) (xy 88.575156 -468.637116)
			(xy 88.412298 -468.520785) (xy 88.254226 -468.398032) (xy 88.101191 -468.269053) (xy 87.953439 -468.134055)
			(xy 87.811206 -467.993252) (xy 87.674721 -467.846872) (xy 87.544202 -467.695149) (xy 87.419858 -467.538325)
			(xy 87.301888 -467.376651) (xy 87.19048 -467.210387) (xy 87.085814 -467.039799) (xy 86.988057 -466.86516)
			(xy 86.897366 -466.686749) (xy 86.813885 -466.504853) (xy 86.737749 -466.319762) (xy 86.669079 -466.131773)
			(xy 86.607986 -465.941188) (xy 86.554566 -465.74831) (xy 86.508906 -465.55345) (xy 86.47108 -465.356919)
			(xy 86.441146 -465.159032) (xy 86.419154 -464.960106) (xy 86.405139 -464.760459) (xy 86.399122 -464.560411)
			(xy 41.437845 -464.560411) (xy 41.42295 -464.585799) (xy 41.388323 -464.629005) (xy 41.347814 -464.666752)
			(xy 41.302274 -464.698246) (xy 41.25266 -464.722828) (xy 41.226486 -464.731862) (xy 41.206112 -464.738972)
			(xy 41.167925 -464.759058) (xy 41.133674 -464.7853) (xy 41.104343 -464.816945) (xy 41.080772 -464.853086)
			(xy 41.063638 -464.892685) (xy 41.053431 -464.934609) (xy 41.050445 -464.977653) (xy 41.054765 -465.020584)
			(xy 41.060116 -465.041488) (xy 41.06814 -465.072242) (xy 41.07698 -465.135185) (xy 41.077486 -465.198743)
			(xy 41.069648 -465.261818) (xy 41.053602 -465.323319) (xy 41.029626 -465.382183) (xy 40.998134 -465.437393)
			(xy 40.959671 -465.487994) (xy 40.914901 -465.533111) (xy 40.864599 -465.571964) (xy 40.809634 -465.603881)
			(xy 40.750956 -465.628311) (xy 40.689581 -465.644831) (xy 40.635689 -465.651951) (xy 62.938144 -465.651951)
			(xy 62.938144 -465.580629) (xy 62.94613 -465.509755) (xy 62.962 -465.44022) (xy 62.985557 -465.3729)
			(xy 63.016502 -465.308641) (xy 63.054448 -465.24825) (xy 63.098917 -465.192488) (xy 63.14935 -465.142055)
			(xy 63.205112 -465.097586) (xy 63.265503 -465.05964) (xy 63.329762 -465.028695) (xy 63.397082 -465.005138)
			(xy 63.466617 -464.989268) (xy 63.537491 -464.981282) (xy 63.573152 -464.980782) (xy 63.608813 -464.981282)
			(xy 63.679687 -464.989268) (xy 63.749222 -465.005138) (xy 63.816542 -465.028695) (xy 63.880801 -465.05964)
			(xy 63.941192 -465.097586) (xy 63.996954 -465.142055) (xy 64.047387 -465.192488) (xy 64.091856 -465.24825)
			(xy 64.129802 -465.308641) (xy 64.160747 -465.3729) (xy 64.184304 -465.44022) (xy 64.200174 -465.509755)
			(xy 64.20816 -465.580629) (xy 64.20816 -465.651951) (xy 65.013578 -465.651951) (xy 65.013578 -465.580629)
			(xy 65.021564 -465.509755) (xy 65.037434 -465.44022) (xy 65.060991 -465.3729) (xy 65.091936 -465.308641)
			(xy 65.129882 -465.24825) (xy 65.174351 -465.192488) (xy 65.224784 -465.142055) (xy 65.280546 -465.097586)
			(xy 65.340937 -465.05964) (xy 65.405196 -465.028695) (xy 65.472516 -465.005138) (xy 65.542051 -464.989268)
			(xy 65.612925 -464.981282) (xy 65.648586 -464.980782) (xy 65.684247 -464.981282) (xy 65.755121 -464.989268)
			(xy 65.824656 -465.005138) (xy 65.891976 -465.028695) (xy 65.956235 -465.05964) (xy 66.016626 -465.097586)
			(xy 66.072388 -465.142055) (xy 66.122821 -465.192488) (xy 66.16729 -465.24825) (xy 66.205236 -465.308641)
			(xy 66.236181 -465.3729) (xy 66.259738 -465.44022) (xy 66.275608 -465.509755) (xy 66.283594 -465.580629)
			(xy 66.283594 -465.651951) (xy 66.283508 -465.652713) (xy 67.19239 -465.652713) (xy 67.19239 -465.581391)
			(xy 67.200376 -465.510517) (xy 67.216246 -465.440982) (xy 67.239803 -465.373662) (xy 67.270748 -465.309403)
			(xy 67.308694 -465.249012) (xy 67.353163 -465.19325) (xy 67.403596 -465.142817) (xy 67.459358 -465.098348)
			(xy 67.519749 -465.060402) (xy 67.584008 -465.029457) (xy 67.651328 -465.0059) (xy 67.720863 -464.99003)
			(xy 67.791737 -464.982044) (xy 67.827398 -464.981544) (xy 67.863059 -464.982044) (xy 67.933933 -464.99003)
			(xy 68.003468 -465.0059) (xy 68.070788 -465.029457) (xy 68.135047 -465.060402) (xy 68.195438 -465.098348)
			(xy 68.2512 -465.142817) (xy 68.301633 -465.19325) (xy 68.346102 -465.249012) (xy 68.384048 -465.309403)
			(xy 68.414993 -465.373662) (xy 68.43855 -465.440982) (xy 68.45442 -465.510517) (xy 68.462406 -465.581391)
			(xy 68.462406 -465.652713) (xy 68.45442 -465.723587) (xy 68.43855 -465.793122) (xy 68.414993 -465.860442)
			(xy 68.384048 -465.924701) (xy 68.346102 -465.985092) (xy 68.301633 -466.040854) (xy 68.2512 -466.091287)
			(xy 68.195438 -466.135756) (xy 68.135047 -466.173702) (xy 68.070788 -466.204647) (xy 68.003468 -466.228204)
			(xy 67.933933 -466.244074) (xy 67.863059 -466.25206) (xy 67.791737 -466.25206) (xy 67.720863 -466.244074)
			(xy 67.651328 -466.228204) (xy 67.584008 -466.204647) (xy 67.519749 -466.173702) (xy 67.459358 -466.135756)
			(xy 67.403596 -466.091287) (xy 67.353163 -466.040854) (xy 67.308694 -465.985092) (xy 67.270748 -465.924701)
			(xy 67.239803 -465.860442) (xy 67.216246 -465.793122) (xy 67.200376 -465.723587) (xy 67.19239 -465.652713)
			(xy 66.283508 -465.652713) (xy 66.275608 -465.722825) (xy 66.259738 -465.79236) (xy 66.236181 -465.85968)
			(xy 66.205236 -465.923939) (xy 66.16729 -465.98433) (xy 66.122821 -466.040092) (xy 66.072388 -466.090525)
			(xy 66.016626 -466.134994) (xy 65.956235 -466.17294) (xy 65.891976 -466.203885) (xy 65.824656 -466.227442)
			(xy 65.755121 -466.243312) (xy 65.684247 -466.251298) (xy 65.612925 -466.251298) (xy 65.542051 -466.243312)
			(xy 65.472516 -466.227442) (xy 65.405196 -466.203885) (xy 65.340937 -466.17294) (xy 65.280546 -466.134994)
			(xy 65.224784 -466.090525) (xy 65.174351 -466.040092) (xy 65.129882 -465.98433) (xy 65.091936 -465.923939)
			(xy 65.060991 -465.85968) (xy 65.037434 -465.79236) (xy 65.021564 -465.722825) (xy 65.013578 -465.651951)
			(xy 64.20816 -465.651951) (xy 64.200174 -465.722825) (xy 64.184304 -465.79236) (xy 64.160747 -465.85968)
			(xy 64.129802 -465.923939) (xy 64.091856 -465.98433) (xy 64.047387 -466.040092) (xy 63.996954 -466.090525)
			(xy 63.941192 -466.134994) (xy 63.880801 -466.17294) (xy 63.816542 -466.203885) (xy 63.749222 -466.227442)
			(xy 63.679687 -466.243312) (xy 63.608813 -466.251298) (xy 63.537491 -466.251298) (xy 63.466617 -466.243312)
			(xy 63.397082 -466.227442) (xy 63.329762 -466.203885) (xy 63.265503 -466.17294) (xy 63.205112 -466.134994)
			(xy 63.14935 -466.090525) (xy 63.098917 -466.040092) (xy 63.054448 -465.98433) (xy 63.016502 -465.923939)
			(xy 62.985557 -465.85968) (xy 62.962 -465.79236) (xy 62.94613 -465.722825) (xy 62.938144 -465.651951)
			(xy 40.635689 -465.651951) (xy 40.626568 -465.653156) (xy 40.594788 -465.653628) (xy 38.227 -465.653628)
			(xy 37.6809 -466.199728) (xy 27.95016 -466.199728) (xy 22.932136 -461.18145) (xy 22.932136 -445.420242)
			(xy 23.841964 -444.510414) (xy 23.84171 -408.887168) (xy 23.841215 -408.864127) (xy 23.832919 -408.818798)
			(xy 23.816587 -408.775707) (xy 23.792754 -408.736267) (xy 23.7622 -408.70177) (xy 23.725928 -408.673346)
			(xy 23.685126 -408.651928) (xy 23.641131 -408.638217) (xy 23.595385 -408.632662) (xy 23.549387 -408.635446)
			(xy 23.504645 -408.646477) (xy 23.462624 -408.665393) (xy 23.424703 -408.691576) (xy 23.408132 -408.70759)
			(xy 13.946632 -418.169344) (xy 13.946632 -447.059304) (xy 12.487148 -448.518788) (xy 12.476791 -448.529804)
			(xy 12.461099 -448.555639) (xy 12.451913 -448.584437) (xy 12.449748 -448.614587) (xy 12.454725 -448.644402)
			(xy 12.460224 -448.658488) (xy 12.478286 -448.701847) (xy 12.507842 -448.791012) (xy 12.529725 -448.882363)
			(xy 12.543778 -448.975241) (xy 12.549898 -449.068977) (xy 12.548041 -449.162895) (xy 12.538222 -449.256316)
			(xy 12.52051 -449.348567) (xy 12.495034 -449.438982) (xy 12.461978 -449.526909) (xy 12.421579 -449.611713)
			(xy 12.374129 -449.692784) (xy 12.319971 -449.769536) (xy 12.259496 -449.841415) (xy 12.193139 -449.907903)
			(xy 12.121379 -449.96852) (xy 12.044734 -450.022829) (xy 11.963757 -450.070438) (xy 11.879032 -450.111004)
			(xy 11.79117 -450.144233) (xy 11.700805 -450.169887) (xy 11.608589 -450.18778) (xy 11.515188 -450.197784)
			(xy 11.421274 -450.199825) (xy 11.327526 -450.193889) (xy 11.23462 -450.18002) (xy 11.143226 -450.158317)
			(xy 11.054004 -450.128936) (xy 10.967596 -450.09209) (xy 10.884627 -450.048044) (xy 10.805694 -449.997117)
			(xy 10.731368 -449.939675) (xy 10.662185 -449.876133) (xy 10.598643 -449.806949) (xy 10.541202 -449.732623)
			(xy 10.490274 -449.653691) (xy 10.446229 -449.570722) (xy 10.409383 -449.484314) (xy 10.380003 -449.395091)
			(xy 10.3583 -449.303697) (xy 10.34443 -449.210791) (xy 10.338495 -449.117043) (xy 10.340536 -449.02313)
			(xy 10.35054 -448.929728) (xy 10.368433 -448.837512) (xy 10.394088 -448.747148) (xy 10.427317 -448.659286)
			(xy 10.467883 -448.574561) (xy 10.515493 -448.493584) (xy 10.569802 -448.416939) (xy 10.630419 -448.345179)
			(xy 10.696907 -448.278822) (xy 10.768786 -448.218347) (xy 10.845538 -448.164189) (xy 10.926609 -448.11674)
			(xy 11.011414 -448.076341) (xy 11.099341 -448.043285) (xy 11.189756 -448.017809) (xy 11.282007 -448.000098)
			(xy 11.375428 -447.990279) (xy 11.469345 -447.988422) (xy 11.563081 -447.994543) (xy 11.65596 -448.008595)
			(xy 11.747311 -448.030479) (xy 11.836476 -448.060035) (xy 11.879834 -448.078098) (xy 11.915648 -448.093592)
			(xy 11.992102 -448.07886) (xy 13.285216 -446.785492) (xy 13.285216 -445.804036) (xy 13.284719 -445.780997)
			(xy 13.276418 -445.735672) (xy 13.260083 -445.692586) (xy 13.236249 -445.65315) (xy 13.205696 -445.618657)
			(xy 13.169426 -445.590237) (xy 13.128626 -445.568821) (xy 13.084634 -445.555111) (xy 13.038892 -445.549556)
			(xy 12.992897 -445.552338) (xy 12.948158 -445.563366) (xy 12.906139 -445.582278) (xy 12.868218 -445.608455)
			(xy 12.851638 -445.624458) (xy 9.051544 -449.424552) (xy 7.049516 -449.424552) (xy 6.985 -449.46824)
			(xy 6.970522 -449.504562) (xy 6.952881 -449.547404) (xy 6.911396 -449.630256) (xy 6.863121 -449.709344)
			(xy 6.808395 -449.784114) (xy 6.747603 -449.854041) (xy 6.68117 -449.918633) (xy 6.609563 -449.977437)
			(xy 6.533285 -450.030041) (xy 6.452872 -450.076075) (xy 6.368887 -450.115217) (xy 6.281921 -450.147191)
			(xy 6.192583 -450.171772) (xy 6.101501 -450.188789) (xy 6.009315 -450.198122) (xy 5.91667 -450.199706)
			(xy 5.824219 -450.193528) (xy 5.732609 -450.179634) (xy 5.642483 -450.158119) (xy 5.554475 -450.129136)
			(xy 5.469202 -450.092888) (xy 5.387262 -450.049628) (xy 5.309231 -449.999662) (xy 5.235657 -449.943338)
			(xy 5.167055 -449.881054) (xy 5.103909 -449.813246) (xy 5.07492 -449.777104) (xy 5.06066 -449.759747)
			(xy 5.02712 -449.729871) (xy 4.98885 -449.706356) (xy 4.947041 -449.689936) (xy 4.902998 -449.681121)
			(xy 4.85809 -449.680187) (xy 4.813718 -449.687162) (xy 4.771263 -449.701828) (xy 4.732048 -449.72373)
			(xy 4.697294 -449.752185) (xy 4.668083 -449.786307) (xy 4.645326 -449.825032) (xy 4.629731 -449.867156)
			(xy 4.621785 -449.911364) (xy 4.621276 -449.933822) (xy 4.621276 -453.293988) (xy 10.338318 -453.293988)
			(xy 10.342302 -453.200201) (xy 10.354225 -453.107089) (xy 10.374002 -453.015324) (xy 10.40149 -452.925567)
			(xy 10.43649 -452.838464) (xy 10.478752 -452.754643) (xy 10.52797 -452.674708) (xy 10.583789 -452.599235)
			(xy 10.645808 -452.528768) (xy 10.71358 -452.463815) (xy 10.786615 -452.404842) (xy 10.864389 -452.352276)
			(xy 10.946341 -452.306495) (xy 11.03188 -452.267829) (xy 11.120389 -452.236557) (xy 11.211232 -452.212903)
			(xy 11.303754 -452.197039) (xy 11.397288 -452.189078) (xy 11.444224 -452.18858) (xy 11.49116 -452.189078)
			(xy 11.584694 -452.197039) (xy 11.677216 -452.212903) (xy 11.768059 -452.236557) (xy 11.856568 -452.267829)
			(xy 11.942107 -452.306495) (xy 12.024059 -452.352276) (xy 12.101833 -452.404842) (xy 12.174868 -452.463815)
			(xy 12.24264 -452.528768) (xy 12.304659 -452.599235) (xy 12.360478 -452.674708) (xy 12.409696 -452.754643)
			(xy 12.451958 -452.838464) (xy 12.486958 -452.925567) (xy 12.514446 -453.015324) (xy 12.534223 -453.107089)
			(xy 12.546146 -453.200201) (xy 12.550131 -453.293988) (xy 12.546146 -453.387775) (xy 12.534223 -453.480887)
			(xy 12.514446 -453.572652) (xy 12.486958 -453.662409) (xy 12.451958 -453.749512) (xy 12.409696 -453.833333)
			(xy 12.360478 -453.913268) (xy 12.304659 -453.988741) (xy 12.24264 -454.059208) (xy 12.174868 -454.124161)
			(xy 12.101833 -454.183134) (xy 12.024059 -454.2357) (xy 11.942107 -454.281481) (xy 11.856568 -454.320147)
			(xy 11.768059 -454.351419) (xy 11.677216 -454.375073) (xy 11.584694 -454.390937) (xy 11.49116 -454.398898)
			(xy 11.397288 -454.398898) (xy 11.303754 -454.390937) (xy 11.211232 -454.375073) (xy 11.120389 -454.351419)
			(xy 11.03188 -454.320147) (xy 10.946341 -454.281481) (xy 10.864389 -454.2357) (xy 10.786615 -454.183134)
			(xy 10.71358 -454.124161) (xy 10.645808 -454.059208) (xy 10.583789 -453.988741) (xy 10.52797 -453.913268)
			(xy 10.478752 -453.833333) (xy 10.43649 -453.749512) (xy 10.40149 -453.662409) (xy 10.374002 -453.572652)
			(xy 10.354225 -453.480887) (xy 10.342302 -453.387775) (xy 10.338318 -453.293988) (xy 4.621276 -453.293988)
			(xy 4.621276 -457.494132) (xy 10.338318 -457.494132) (xy 10.342302 -457.400345) (xy 10.354225 -457.307233)
			(xy 10.374002 -457.215468) (xy 10.40149 -457.125711) (xy 10.43649 -457.038608) (xy 10.478752 -456.954787)
			(xy 10.52797 -456.874852) (xy 10.583789 -456.799379) (xy 10.645808 -456.728912) (xy 10.71358 -456.663959)
			(xy 10.786615 -456.604986) (xy 10.864389 -456.55242) (xy 10.946341 -456.506639) (xy 11.03188 -456.467973)
			(xy 11.120389 -456.436701) (xy 11.211232 -456.413047) (xy 11.303754 -456.397183) (xy 11.397288 -456.389222)
			(xy 11.444224 -456.388724) (xy 11.49116 -456.389222) (xy 11.584694 -456.397183) (xy 11.677216 -456.413047)
			(xy 11.768059 -456.436701) (xy 11.856568 -456.467973) (xy 11.942107 -456.506639) (xy 12.024059 -456.55242)
			(xy 12.101833 -456.604986) (xy 12.174868 -456.663959) (xy 12.24264 -456.728912) (xy 12.304659 -456.799379)
			(xy 12.360478 -456.874852) (xy 12.409696 -456.954787) (xy 12.451958 -457.038608) (xy 12.486958 -457.125711)
			(xy 12.514446 -457.215468) (xy 12.534223 -457.307233) (xy 12.546146 -457.400345) (xy 12.550131 -457.494132)
			(xy 12.546146 -457.587919) (xy 12.534223 -457.681031) (xy 12.514446 -457.772796) (xy 12.486958 -457.862553)
			(xy 12.451958 -457.949656) (xy 12.409696 -458.033477) (xy 12.360478 -458.113412) (xy 12.304659 -458.188885)
			(xy 12.24264 -458.259352) (xy 12.174868 -458.324305) (xy 12.101833 -458.383278) (xy 12.024059 -458.435844)
			(xy 11.942107 -458.481625) (xy 11.856568 -458.520291) (xy 11.768059 -458.551563) (xy 11.677216 -458.575217)
			(xy 11.584694 -458.591081) (xy 11.49116 -458.599042) (xy 11.397288 -458.599042) (xy 11.303754 -458.591081)
			(xy 11.211232 -458.575217) (xy 11.120389 -458.551563) (xy 11.03188 -458.520291) (xy 10.946341 -458.481625)
			(xy 10.864389 -458.435844) (xy 10.786615 -458.383278) (xy 10.71358 -458.324305) (xy 10.645808 -458.259352)
			(xy 10.583789 -458.188885) (xy 10.52797 -458.113412) (xy 10.478752 -458.033477) (xy 10.43649 -457.949656)
			(xy 10.40149 -457.862553) (xy 10.374002 -457.772796) (xy 10.354225 -457.681031) (xy 10.342302 -457.587919)
			(xy 10.338318 -457.494132) (xy 4.621276 -457.494132) (xy 4.621276 -459.903576) (xy 5.368798 -460.651098)
			(xy 5.379812 -460.661458) (xy 5.405646 -460.677155) (xy 5.434446 -460.686343) (xy 5.464597 -460.688506)
			(xy 5.494413 -460.683524) (xy 5.508498 -460.678022) (xy 5.551747 -460.660015) (xy 5.640671 -460.630514)
			(xy 5.731773 -460.608646) (xy 5.8244 -460.594568) (xy 5.917886 -460.588381) (xy 6.01156 -460.59013)
			(xy 6.104749 -460.599802) (xy 6.196786 -460.617327) (xy 6.287008 -460.64258) (xy 6.37477 -460.67538)
			(xy 6.45944 -460.715491) (xy 6.54041 -460.762625) (xy 6.6171 -460.816444) (xy 6.68896 -460.876561)
			(xy 6.755472 -460.942545) (xy 6.816161 -461.013923) (xy 6.87059 -461.090181) (xy 6.918368 -461.170773)
			(xy 6.959153 -461.255121) (xy 6.992651 -461.342618) (xy 7.018623 -461.432636) (xy 7.036882 -461.52453)
			(xy 7.047297 -461.617639) (xy 7.049793 -461.711296) (xy 7.044352 -461.804828) (xy 7.031013 -461.897564)
			(xy 7.009872 -461.988838) (xy 6.981081 -462.077995) (xy 6.944847 -462.164395) (xy 6.901429 -462.247417)
			(xy 6.851139 -462.326466) (xy 6.823202 -462.364074) (xy 6.810363 -462.381618) (xy 6.790242 -462.420152)
			(xy 6.776972 -462.461548) (xy 6.770942 -462.504599) (xy 6.772326 -462.548048) (xy 6.781084 -462.590628)
			(xy 6.796962 -462.631096) (xy 6.819494 -462.668271) (xy 6.848025 -462.701069) (xy 6.881722 -462.728533)
			(xy 6.919601 -462.749862) (xy 6.960558 -462.764432) (xy 7.003396 -462.77182) (xy 7.025132 -462.772252)
			(xy 9.898634 -462.772252) (xy 10.338816 -462.331816) (xy 10.338816 -460.588868) (xy 12.549632 -460.588868)
			(xy 12.549632 -462.799176) (xy 10.80643 -462.799176) (xy 10.172446 -463.43316) (xy 4.030218 -463.43316)
			(xy 2.308352 -461.711294) (xy 2.308352 -448.153028) (xy 4.00812 -446.453006) (xy 4.00812 -422.701212)
			(xy 11.302746 -415.406586) (xy 11.318676 -415.389943) (xy 11.34484 -415.352028) (xy 11.363742 -415.310018)
			(xy 11.374763 -415.26529) (xy 11.377543 -415.219307) (xy 11.37199 -415.173577) (xy 11.358287 -415.129596)
			(xy 11.336882 -415.088805) (xy 11.308476 -415.05254) (xy 11.273999 -415.021988) (xy 11.23458 -414.998149)
			(xy 11.191511 -414.981805) (xy 11.146201 -414.973491) (xy 11.123168 -414.973008) (xy 9.54151 -414.973008)
			(xy 9.242806 -414.674304) (xy 1.359154 -414.674304) (xy 0.509016 -415.524442) (xy 0.509016 -467.418521)
			(xy 62.938144 -467.418521) (xy 62.938144 -467.347199) (xy 62.94613 -467.276325) (xy 62.962 -467.20679)
			(xy 62.985557 -467.13947) (xy 63.016502 -467.075211) (xy 63.054448 -467.01482) (xy 63.098917 -466.959058)
			(xy 63.14935 -466.908625) (xy 63.205112 -466.864156) (xy 63.265503 -466.82621) (xy 63.329762 -466.795265)
			(xy 63.397082 -466.771708) (xy 63.466617 -466.755838) (xy 63.537491 -466.747852) (xy 63.573152 -466.747352)
			(xy 63.608813 -466.747852) (xy 63.679687 -466.755838) (xy 63.749222 -466.771708) (xy 63.816542 -466.795265)
			(xy 63.880801 -466.82621) (xy 63.941192 -466.864156) (xy 63.996954 -466.908625) (xy 64.047387 -466.959058)
			(xy 64.091856 -467.01482) (xy 64.129802 -467.075211) (xy 64.160747 -467.13947) (xy 64.184304 -467.20679)
			(xy 64.200174 -467.276325) (xy 64.20816 -467.347199) (xy 64.20816 -467.418521) (xy 65.013578 -467.418521)
			(xy 65.013578 -467.347199) (xy 65.021564 -467.276325) (xy 65.037434 -467.20679) (xy 65.060991 -467.13947)
			(xy 65.091936 -467.075211) (xy 65.129882 -467.01482) (xy 65.174351 -466.959058) (xy 65.224784 -466.908625)
			(xy 65.280546 -466.864156) (xy 65.340937 -466.82621) (xy 65.405196 -466.795265) (xy 65.472516 -466.771708)
			(xy 65.542051 -466.755838) (xy 65.612925 -466.747852) (xy 65.648586 -466.747352) (xy 65.684247 -466.747852)
			(xy 65.755121 -466.755838) (xy 65.824656 -466.771708) (xy 65.891976 -466.795265) (xy 65.956235 -466.82621)
			(xy 66.016626 -466.864156) (xy 66.072388 -466.908625) (xy 66.122821 -466.959058) (xy 66.16729 -467.01482)
			(xy 66.205236 -467.075211) (xy 66.236181 -467.13947) (xy 66.259738 -467.20679) (xy 66.275608 -467.276325)
			(xy 66.283594 -467.347199) (xy 66.283594 -467.418521) (xy 66.283508 -467.419283) (xy 67.19239 -467.419283)
			(xy 67.19239 -467.347961) (xy 67.200376 -467.277087) (xy 67.216246 -467.207552) (xy 67.239803 -467.140232)
			(xy 67.270748 -467.075973) (xy 67.308694 -467.015582) (xy 67.353163 -466.95982) (xy 67.403596 -466.909387)
			(xy 67.459358 -466.864918) (xy 67.519749 -466.826972) (xy 67.584008 -466.796027) (xy 67.651328 -466.77247)
			(xy 67.720863 -466.7566) (xy 67.791737 -466.748614) (xy 67.827398 -466.748114) (xy 67.863059 -466.748614)
			(xy 67.933933 -466.7566) (xy 68.003468 -466.77247) (xy 68.070788 -466.796027) (xy 68.135047 -466.826972)
			(xy 68.195438 -466.864918) (xy 68.2512 -466.909387) (xy 68.301633 -466.95982) (xy 68.346102 -467.015582)
			(xy 68.384048 -467.075973) (xy 68.414993 -467.140232) (xy 68.43855 -467.207552) (xy 68.45442 -467.277087)
			(xy 68.462406 -467.347961) (xy 68.462406 -467.419283) (xy 68.45442 -467.490157) (xy 68.43855 -467.559692)
			(xy 68.414993 -467.627012) (xy 68.384048 -467.691271) (xy 68.346102 -467.751662) (xy 68.301633 -467.807424)
			(xy 68.2512 -467.857857) (xy 68.195438 -467.902326) (xy 68.135047 -467.940272) (xy 68.070788 -467.971217)
			(xy 68.003468 -467.994774) (xy 67.933933 -468.010644) (xy 67.863059 -468.01863) (xy 67.791737 -468.01863)
			(xy 67.720863 -468.010644) (xy 67.651328 -467.994774) (xy 67.584008 -467.971217) (xy 67.519749 -467.940272)
			(xy 67.459358 -467.902326) (xy 67.403596 -467.857857) (xy 67.353163 -467.807424) (xy 67.308694 -467.751662)
			(xy 67.270748 -467.691271) (xy 67.239803 -467.627012) (xy 67.216246 -467.559692) (xy 67.200376 -467.490157)
			(xy 67.19239 -467.419283) (xy 66.283508 -467.419283) (xy 66.275608 -467.489395) (xy 66.259738 -467.55893)
			(xy 66.236181 -467.62625) (xy 66.205236 -467.690509) (xy 66.16729 -467.7509) (xy 66.122821 -467.806662)
			(xy 66.072388 -467.857095) (xy 66.016626 -467.901564) (xy 65.956235 -467.93951) (xy 65.891976 -467.970455)
			(xy 65.824656 -467.994012) (xy 65.755121 -468.009882) (xy 65.684247 -468.017868) (xy 65.612925 -468.017868)
			(xy 65.542051 -468.009882) (xy 65.472516 -467.994012) (xy 65.405196 -467.970455) (xy 65.340937 -467.93951)
			(xy 65.280546 -467.901564) (xy 65.224784 -467.857095) (xy 65.174351 -467.806662) (xy 65.129882 -467.7509)
			(xy 65.091936 -467.690509) (xy 65.060991 -467.62625) (xy 65.037434 -467.55893) (xy 65.021564 -467.489395)
			(xy 65.013578 -467.418521) (xy 64.20816 -467.418521) (xy 64.200174 -467.489395) (xy 64.184304 -467.55893)
			(xy 64.160747 -467.62625) (xy 64.129802 -467.690509) (xy 64.091856 -467.7509) (xy 64.047387 -467.806662)
			(xy 63.996954 -467.857095) (xy 63.941192 -467.901564) (xy 63.880801 -467.93951) (xy 63.816542 -467.970455)
			(xy 63.749222 -467.994012) (xy 63.679687 -468.009882) (xy 63.608813 -468.017868) (xy 63.537491 -468.017868)
			(xy 63.466617 -468.009882) (xy 63.397082 -467.994012) (xy 63.329762 -467.970455) (xy 63.265503 -467.93951)
			(xy 63.205112 -467.901564) (xy 63.14935 -467.857095) (xy 63.098917 -467.806662) (xy 63.054448 -467.7509)
			(xy 63.016502 -467.690509) (xy 62.985557 -467.62625) (xy 62.962 -467.55893) (xy 62.94613 -467.489395)
			(xy 62.938144 -467.418521) (xy 0.509016 -467.418521) (xy 0.509016 -473.700094) (xy 11.599164 -473.700094)
			(xy 11.599658 -473.600658) (xy 11.607565 -473.401944) (xy 11.623365 -473.203701) (xy 11.647034 -473.006243)
			(xy 11.678535 -472.809883) (xy 11.717818 -472.614929) (xy 11.76482 -472.421692) (xy 11.819467 -472.230476)
			(xy 11.881674 -472.041584) (xy 11.95134 -471.855315) (xy 12.028358 -471.671962) (xy 12.112603 -471.491816)
			(xy 12.203944 -471.315162) (xy 12.302236 -471.142279) (xy 12.407324 -470.973441) (xy 12.519041 -470.808913)
			(xy 12.637211 -470.648958) (xy 12.761646 -470.493827) (xy 12.892151 -470.343765) (xy 13.028518 -470.199011)
			(xy 13.170532 -470.059793) (xy 13.317969 -469.92633) (xy 13.470596 -469.798835) (xy 13.62817 -469.677509)
			(xy 13.790444 -469.562543) (xy 13.957159 -469.454119) (xy 14.128054 -469.352409) (xy 14.302857 -469.257574)
			(xy 14.481292 -469.169763) (xy 14.663077 -469.089115) (xy 14.847925 -469.015759) (xy 15.035543 -468.949809)
			(xy 15.225635 -468.891371) (xy 15.417899 -468.840536) (xy 15.612033 -468.797385) (xy 15.807728 -468.761987)
			(xy 16.004677 -468.734396) (xy 16.202566 -468.714657) (xy 16.401084 -468.702801) (xy 16.599916 -468.698848)
			(xy 16.798748 -468.702801) (xy 16.997266 -468.714657) (xy 17.195155 -468.734396) (xy 17.392104 -468.761987)
			(xy 17.587799 -468.797385) (xy 17.781933 -468.840536) (xy 17.974197 -468.891371) (xy 18.164289 -468.949809)
			(xy 18.351907 -469.015759) (xy 18.536755 -469.089115) (xy 18.71854 -469.169763) (xy 18.896975 -469.257574)
			(xy 19.071778 -469.352409) (xy 19.242673 -469.454119) (xy 19.409388 -469.562543) (xy 19.571662 -469.677509)
			(xy 19.729236 -469.798835) (xy 19.881863 -469.92633) (xy 20.0293 -470.059793) (xy 20.171314 -470.199011)
			(xy 20.307681 -470.343765) (xy 20.438186 -470.493827) (xy 20.562621 -470.648958) (xy 20.680791 -470.808913)
			(xy 20.792508 -470.973441) (xy 20.897596 -471.142279) (xy 20.995888 -471.315162) (xy 21.087229 -471.491816)
			(xy 21.171474 -471.671962) (xy 21.248492 -471.855315) (xy 21.318158 -472.041584) (xy 21.347816 -472.13164)
			(xy 70.723742 -472.13164) (xy 70.723742 -472.071704) (xy 70.731565 -472.012282) (xy 70.747078 -471.954389)
			(xy 70.770014 -471.899016) (xy 70.799981 -471.84711) (xy 70.836468 -471.79956) (xy 70.878848 -471.75718)
			(xy 70.926398 -471.720693) (xy 70.978304 -471.690726) (xy 71.033677 -471.66779) (xy 71.09157 -471.652277)
			(xy 71.150992 -471.644454) (xy 71.18096 -471.643964) (xy 71.210928 -471.644454) (xy 71.27035 -471.652277)
			(xy 71.328243 -471.66779) (xy 71.383616 -471.690726) (xy 71.435522 -471.720693) (xy 71.483072 -471.75718)
			(xy 71.525452 -471.79956) (xy 71.561939 -471.84711) (xy 71.591906 -471.899016) (xy 71.614842 -471.954389)
			(xy 71.630355 -472.012282) (xy 71.638178 -472.071704) (xy 71.638178 -472.13164) (xy 71.630355 -472.191062)
			(xy 71.614842 -472.248955) (xy 71.591906 -472.304328) (xy 71.561939 -472.356234) (xy 71.525452 -472.403784)
			(xy 71.483072 -472.446164) (xy 71.435522 -472.482651) (xy 71.383616 -472.512618) (xy 71.328243 -472.535554)
			(xy 71.27035 -472.551067) (xy 71.210928 -472.55889) (xy 71.150992 -472.55889) (xy 71.09157 -472.551067)
			(xy 71.033677 -472.535554) (xy 70.978304 -472.512618) (xy 70.926398 -472.482651) (xy 70.878848 -472.446164)
			(xy 70.836468 -472.403784) (xy 70.799981 -472.356234) (xy 70.770014 -472.304328) (xy 70.747078 -472.248955)
			(xy 70.731565 -472.191062) (xy 70.723742 -472.13164) (xy 21.347816 -472.13164) (xy 21.380365 -472.230476)
			(xy 21.435012 -472.421692) (xy 21.482014 -472.614929) (xy 21.521297 -472.809883) (xy 21.552798 -473.006243)
			(xy 21.576467 -473.203701) (xy 21.592267 -473.401944) (xy 21.600174 -473.600658) (xy 21.600317 -473.629478)
			(xy 70.656686 -473.629478) (xy 70.656686 -473.569542) (xy 70.664509 -473.51012) (xy 70.680022 -473.452227)
			(xy 70.702958 -473.396854) (xy 70.732925 -473.344948) (xy 70.769412 -473.297398) (xy 70.811792 -473.255018)
			(xy 70.859342 -473.218531) (xy 70.911248 -473.188564) (xy 70.966621 -473.165628) (xy 71.024514 -473.150115)
			(xy 71.083936 -473.142292) (xy 71.113904 -473.141802) (xy 71.143872 -473.142292) (xy 71.203294 -473.150115)
			(xy 71.261187 -473.165628) (xy 71.31656 -473.188564) (xy 71.368466 -473.218531) (xy 71.416016 -473.255018)
			(xy 71.458396 -473.297398) (xy 71.494883 -473.344948) (xy 71.52485 -473.396854) (xy 71.547786 -473.452227)
			(xy 71.563299 -473.51012) (xy 71.571122 -473.569542) (xy 71.571122 -473.585558) (xy 73.942193 -473.585558)
			(xy 73.948293 -473.530121) (xy 73.962399 -473.476164) (xy 73.984211 -473.424835) (xy 74.013265 -473.377229)
			(xy 74.04894 -473.334361) (xy 74.090477 -473.297144) (xy 74.13699 -473.266371) (xy 74.187487 -473.242699)
			(xy 74.240894 -473.226631) (xy 74.29607 -473.218511) (xy 74.323956 -473.218002) (xy 74.351842 -473.218511)
			(xy 74.407018 -473.226631) (xy 74.460425 -473.242699) (xy 74.510922 -473.266371) (xy 74.557435 -473.297144)
			(xy 74.598972 -473.334361) (xy 74.634647 -473.377229) (xy 74.663701 -473.424835) (xy 74.685513 -473.476164)
			(xy 74.699619 -473.530121) (xy 74.705719 -473.585558) (xy 74.703682 -473.641292) (xy 74.693552 -473.696135)
			(xy 74.675545 -473.748919) (xy 74.650044 -473.798519) (xy 74.617593 -473.843877) (xy 74.578884 -473.884026)
			(xy 74.534741 -473.918112) (xy 74.486106 -473.945408) (xy 74.434015 -473.965331) (xy 74.379578 -473.977457)
			(xy 74.323956 -473.981528) (xy 74.268334 -473.977457) (xy 74.213897 -473.965331) (xy 74.161806 -473.945408)
			(xy 74.113171 -473.918112) (xy 74.069028 -473.884026) (xy 74.030319 -473.843877) (xy 73.997868 -473.798519)
			(xy 73.972367 -473.748919) (xy 73.95436 -473.696135) (xy 73.94423 -473.641292) (xy 73.942193 -473.585558)
			(xy 71.571122 -473.585558) (xy 71.571122 -473.629478) (xy 71.563299 -473.6889) (xy 71.547786 -473.746793)
			(xy 71.52485 -473.802166) (xy 71.494883 -473.854072) (xy 71.458396 -473.901622) (xy 71.416016 -473.944002)
			(xy 71.368466 -473.980489) (xy 71.31656 -474.010456) (xy 71.261187 -474.033392) (xy 71.203294 -474.048905)
			(xy 71.143872 -474.056728) (xy 71.083936 -474.056728) (xy 71.024514 -474.048905) (xy 70.966621 -474.033392)
			(xy 70.911248 -474.010456) (xy 70.859342 -473.980489) (xy 70.811792 -473.944002) (xy 70.769412 -473.901622)
			(xy 70.732925 -473.854072) (xy 70.702958 -473.802166) (xy 70.680022 -473.746793) (xy 70.664509 -473.6889)
			(xy 70.656686 -473.629478) (xy 21.600317 -473.629478) (xy 21.600668 -473.700094) (xy 21.600174 -473.79953)
			(xy 21.592267 -473.998244) (xy 21.576467 -474.196487) (xy 21.552798 -474.393945) (xy 21.521297 -474.590305)
			(xy 21.482014 -474.785259) (xy 21.435012 -474.978496) (xy 21.380365 -475.169712) (xy 21.318158 -475.358604)
			(xy 21.248492 -475.544873) (xy 21.171474 -475.728226) (xy 21.087229 -475.908372) (xy 20.995888 -476.085026)
			(xy 20.897596 -476.257909) (xy 20.792508 -476.426747) (xy 20.680791 -476.591275) (xy 20.562621 -476.75123)
			(xy 20.438186 -476.906361) (xy 20.307681 -477.056423) (xy 20.171314 -477.201177) (xy 20.0293 -477.340395)
			(xy 19.881863 -477.473858) (xy 19.729236 -477.601353) (xy 19.571662 -477.722679) (xy 19.409388 -477.837645)
			(xy 19.242673 -477.946069) (xy 19.071778 -478.047779) (xy 18.896975 -478.142614) (xy 18.71854 -478.230425)
			(xy 18.536755 -478.311073) (xy 18.351907 -478.384429) (xy 18.164289 -478.450379) (xy 17.974197 -478.508817)
			(xy 17.781933 -478.559652) (xy 17.587799 -478.602803) (xy 17.392104 -478.638201) (xy 17.195155 -478.665792)
			(xy 16.997266 -478.685531) (xy 16.798748 -478.697387) (xy 16.599916 -478.701341) (xy 16.401084 -478.697387)
			(xy 16.202566 -478.685531) (xy 16.004677 -478.665792) (xy 15.807728 -478.638201) (xy 15.612033 -478.602803)
			(xy 15.417899 -478.559652) (xy 15.225635 -478.508817) (xy 15.035543 -478.450379) (xy 14.847925 -478.384429)
			(xy 14.663077 -478.311073) (xy 14.481292 -478.230425) (xy 14.302857 -478.142614) (xy 14.128054 -478.047779)
			(xy 13.957159 -477.946069) (xy 13.790444 -477.837645) (xy 13.62817 -477.722679) (xy 13.470596 -477.601353)
			(xy 13.317969 -477.473858) (xy 13.170532 -477.340395) (xy 13.028518 -477.201177) (xy 12.892151 -477.056423)
			(xy 12.761646 -476.906361) (xy 12.637211 -476.75123) (xy 12.519041 -476.591275) (xy 12.407324 -476.426747)
			(xy 12.302236 -476.257909) (xy 12.203944 -476.085026) (xy 12.112603 -475.908372) (xy 12.028358 -475.728226)
			(xy 11.95134 -475.544873) (xy 11.881674 -475.358604) (xy 11.819467 -475.169712) (xy 11.76482 -474.978496)
			(xy 11.717818 -474.785259) (xy 11.678535 -474.590305) (xy 11.647034 -474.393945) (xy 11.623365 -474.196487)
			(xy 11.607565 -473.998244) (xy 11.599658 -473.79953) (xy 11.599164 -473.700094) (xy 0.509016 -473.700094)
			(xy 0.509016 -478.799906) (xy 74.39914 -478.799906) (xy 74.39914 -477.799908) (xy 74.399635 -477.715487)
			(xy 74.407549 -477.546829) (xy 74.423359 -477.378729) (xy 74.447032 -477.211554) (xy 74.478514 -477.045672)
			(xy 74.517737 -476.881448) (xy 74.564615 -476.719244) (xy 74.619044 -476.559414) (xy 74.680904 -476.402312)
			(xy 74.750061 -476.248282) (xy 74.826361 -476.097663) (xy 74.909637 -475.950785) (xy 74.999706 -475.807973)
			(xy 75.09637 -475.669539) (xy 75.199416 -475.535788) (xy 75.308619 -475.407014) (xy 75.423737 -475.2835)
			(xy 75.544518 -475.165518) (xy 75.670697 -475.053327) (xy 75.801995 -474.947173) (xy 75.938125 -474.847291)
			(xy 76.078787 -474.753898) (xy 76.223672 -474.667202) (xy 76.372461 -474.587392) (xy 76.524828 -474.514644)
			(xy 76.680437 -474.449117) (xy 76.838946 -474.390957) (xy 77.000007 -474.340289) (xy 77.163266 -474.297227)
			(xy 77.328364 -474.261865) (xy 77.494938 -474.23428) (xy 77.662622 -474.214533) (xy 77.831048 -474.202667)
			(xy 77.999844 -474.198709) (xy 78.16864 -474.202667) (xy 78.337066 -474.214533) (xy 78.50475 -474.23428)
			(xy 78.671324 -474.261865) (xy 78.836422 -474.297227) (xy 78.999681 -474.340289) (xy 79.160742 -474.390957)
			(xy 79.319251 -474.449117) (xy 79.47486 -474.514644) (xy 79.627227 -474.587392) (xy 79.776016 -474.667202)
			(xy 79.920901 -474.753898) (xy 80.061563 -474.847291) (xy 80.197693 -474.947173) (xy 80.328991 -475.053327)
			(xy 80.45517 -475.165518) (xy 80.575951 -475.2835) (xy 80.691069 -475.407014) (xy 80.800272 -475.535788)
			(xy 80.903318 -475.669539) (xy 80.999982 -475.807973) (xy 81.090051 -475.950785) (xy 81.173327 -476.097663)
			(xy 81.249627 -476.248282) (xy 81.318784 -476.402312) (xy 81.380644 -476.559414) (xy 81.435073 -476.719244)
			(xy 81.481951 -476.881448) (xy 81.521174 -477.045672) (xy 81.552656 -477.211554) (xy 81.576329 -477.378729)
			(xy 81.592139 -477.546829) (xy 81.600053 -477.715487) (xy 81.600548 -477.799908) (xy 81.600548 -478.799906)
			(xy 81.600053 -478.884327) (xy 81.592139 -479.052985) (xy 81.576329 -479.221085) (xy 81.552656 -479.38826)
			(xy 81.521174 -479.554142) (xy 81.481951 -479.718366) (xy 81.435073 -479.88057) (xy 81.380644 -480.0404)
			(xy 81.318784 -480.197502) (xy 81.249627 -480.351532) (xy 81.173327 -480.502151) (xy 81.090051 -480.649029)
			(xy 80.999982 -480.791841) (xy 80.903318 -480.930275) (xy 80.800272 -481.064026) (xy 80.691069 -481.1928)
			(xy 80.575951 -481.316314) (xy 80.45517 -481.434296) (xy 80.328991 -481.546487) (xy 80.197693 -481.652641)
			(xy 80.061563 -481.752523) (xy 79.920901 -481.845916) (xy 79.776016 -481.932612) (xy 79.627227 -482.012422)
			(xy 79.47486 -482.08517) (xy 79.319251 -482.150697) (xy 79.160742 -482.208857) (xy 78.999681 -482.259525)
			(xy 78.836422 -482.302587) (xy 78.671324 -482.337949) (xy 78.50475 -482.365534) (xy 78.337066 -482.385281)
			(xy 78.16864 -482.397147) (xy 77.999844 -482.401105) (xy 77.831048 -482.397147) (xy 77.662622 -482.385281)
			(xy 77.494938 -482.365534) (xy 77.328364 -482.337949) (xy 77.163266 -482.302587) (xy 77.000007 -482.259525)
			(xy 76.838946 -482.208857) (xy 76.680437 -482.150697) (xy 76.524828 -482.08517) (xy 76.372461 -482.012422)
			(xy 76.223672 -481.932612) (xy 76.078787 -481.845916) (xy 75.938125 -481.752523) (xy 75.801995 -481.652641)
			(xy 75.670697 -481.546487) (xy 75.544518 -481.434296) (xy 75.423737 -481.316314) (xy 75.308619 -481.1928)
			(xy 75.199416 -481.064026) (xy 75.09637 -480.930275) (xy 74.999706 -480.791841) (xy 74.909637 -480.649029)
			(xy 74.826361 -480.502151) (xy 74.750061 -480.351532) (xy 74.680904 -480.197502) (xy 74.619044 -480.0404)
			(xy 74.564615 -479.88057) (xy 74.517737 -479.718366) (xy 74.478514 -479.554142) (xy 74.447032 -479.38826)
			(xy 74.423359 -479.221085) (xy 74.407549 -479.052985) (xy 74.399635 -478.884327) (xy 74.39914 -478.799906)
			(xy 0.509016 -478.799906) (xy 0.509016 -481.880672) (xy 51.007772 -481.880672) (xy 52.65928 -481.880672)
			(xy 52.65928 -483.532688) (xy 51.007772 -483.532688) (xy 51.007772 -481.880672) (xy 0.509016 -481.880672)
			(xy 0.509016 -485.234589) (xy 73.724508 -485.234589) (xy 73.724508 -485.163267) (xy 73.732494 -485.092393)
			(xy 73.748364 -485.022858) (xy 73.771921 -484.955538) (xy 73.802866 -484.891279) (xy 73.840812 -484.830888)
			(xy 73.885281 -484.775126) (xy 73.935714 -484.724693) (xy 73.991476 -484.680224) (xy 74.051867 -484.642278)
			(xy 74.116126 -484.611333) (xy 74.183446 -484.587776) (xy 74.252981 -484.571906) (xy 74.323855 -484.56392)
			(xy 74.359516 -484.56342) (xy 74.395177 -484.56392) (xy 74.466051 -484.571906) (xy 74.535586 -484.587776)
			(xy 74.602906 -484.611333) (xy 74.667165 -484.642278) (xy 74.727556 -484.680224) (xy 74.783318 -484.724693)
			(xy 74.833751 -484.775126) (xy 74.87822 -484.830888) (xy 74.916166 -484.891279) (xy 74.947111 -484.955538)
			(xy 74.970668 -485.022858) (xy 74.986538 -485.092393) (xy 74.994524 -485.163267) (xy 74.994524 -485.234589)
			(xy 75.653638 -485.234589) (xy 75.653638 -485.163267) (xy 75.661624 -485.092393) (xy 75.677494 -485.022858)
			(xy 75.701051 -484.955538) (xy 75.731996 -484.891279) (xy 75.769942 -484.830888) (xy 75.814411 -484.775126)
			(xy 75.864844 -484.724693) (xy 75.920606 -484.680224) (xy 75.980997 -484.642278) (xy 76.045256 -484.611333)
			(xy 76.112576 -484.587776) (xy 76.182111 -484.571906) (xy 76.252985 -484.56392) (xy 76.288646 -484.56342)
			(xy 76.324307 -484.56392) (xy 76.395181 -484.571906) (xy 76.464716 -484.587776) (xy 76.532036 -484.611333)
			(xy 76.596295 -484.642278) (xy 76.656686 -484.680224) (xy 76.712448 -484.724693) (xy 76.762881 -484.775126)
			(xy 76.80735 -484.830888) (xy 76.845296 -484.891279) (xy 76.876241 -484.955538) (xy 76.899798 -485.022858)
			(xy 76.915668 -485.092393) (xy 76.923654 -485.163267) (xy 76.923654 -485.234589) (xy 76.918502 -485.280309)
			(xy 77.397602 -485.280309) (xy 77.397602 -485.208987) (xy 77.405588 -485.138113) (xy 77.421458 -485.068578)
			(xy 77.445015 -485.001258) (xy 77.47596 -484.936999) (xy 77.513906 -484.876608) (xy 77.558375 -484.820846)
			(xy 77.608808 -484.770413) (xy 77.66457 -484.725944) (xy 77.724961 -484.687998) (xy 77.78922 -484.657053)
			(xy 77.85654 -484.633496) (xy 77.926075 -484.617626) (xy 77.996949 -484.60964) (xy 78.03261 -484.60914)
			(xy 78.068271 -484.60964) (xy 78.139145 -484.617626) (xy 78.20868 -484.633496) (xy 78.276 -484.657053)
			(xy 78.340259 -484.687998) (xy 78.40065 -484.725944) (xy 78.456412 -484.770413) (xy 78.506845 -484.820846)
			(xy 78.551314 -484.876608) (xy 78.58926 -484.936999) (xy 78.620205 -485.001258) (xy 78.643762 -485.068578)
			(xy 78.659632 -485.138113) (xy 78.667618 -485.208987) (xy 78.667618 -485.280309) (xy 79.326732 -485.280309)
			(xy 79.326732 -485.208987) (xy 79.334718 -485.138113) (xy 79.350588 -485.068578) (xy 79.374145 -485.001258)
			(xy 79.40509 -484.936999) (xy 79.443036 -484.876608) (xy 79.487505 -484.820846) (xy 79.537938 -484.770413)
			(xy 79.5937 -484.725944) (xy 79.654091 -484.687998) (xy 79.71835 -484.657053) (xy 79.78567 -484.633496)
			(xy 79.855205 -484.617626) (xy 79.926079 -484.60964) (xy 79.96174 -484.60914) (xy 79.997401 -484.60964)
			(xy 80.068275 -484.617626) (xy 80.13781 -484.633496) (xy 80.20513 -484.657053) (xy 80.269389 -484.687998)
			(xy 80.32978 -484.725944) (xy 80.385542 -484.770413) (xy 80.435975 -484.820846) (xy 80.480444 -484.876608)
			(xy 80.51839 -484.936999) (xy 80.549335 -485.001258) (xy 80.572892 -485.068578) (xy 80.588762 -485.138113)
			(xy 80.596748 -485.208987) (xy 80.596748 -485.280309) (xy 80.588762 -485.351183) (xy 80.572892 -485.420718)
			(xy 80.560822 -485.45521) (xy 87.02089 -485.45521) (xy 87.02089 -485.395274) (xy 87.028713 -485.335852)
			(xy 87.044226 -485.277959) (xy 87.067162 -485.222586) (xy 87.097129 -485.17068) (xy 87.133616 -485.12313)
			(xy 87.175996 -485.08075) (xy 87.223546 -485.044263) (xy 87.275452 -485.014296) (xy 87.330825 -484.99136)
			(xy 87.388718 -484.975847) (xy 87.44814 -484.968024) (xy 87.478108 -484.967534) (xy 87.508076 -484.968024)
			(xy 87.567498 -484.975847) (xy 87.625391 -484.99136) (xy 87.680764 -485.014296) (xy 87.73267 -485.044263)
			(xy 87.78022 -485.08075) (xy 87.8226 -485.12313) (xy 87.859087 -485.17068) (xy 87.889054 -485.222586)
			(xy 87.91199 -485.277959) (xy 87.927503 -485.335852) (xy 87.935326 -485.395274) (xy 87.935326 -485.45521)
			(xy 87.927503 -485.514632) (xy 87.91199 -485.572525) (xy 87.889054 -485.627898) (xy 87.859087 -485.679804)
			(xy 87.8226 -485.727354) (xy 87.78022 -485.769734) (xy 87.73267 -485.806221) (xy 87.680764 -485.836188)
			(xy 87.625391 -485.859124) (xy 87.567498 -485.874637) (xy 87.508076 -485.88246) (xy 87.44814 -485.88246)
			(xy 87.388718 -485.874637) (xy 87.330825 -485.859124) (xy 87.275452 -485.836188) (xy 87.223546 -485.806221)
			(xy 87.175996 -485.769734) (xy 87.133616 -485.727354) (xy 87.097129 -485.679804) (xy 87.067162 -485.627898)
			(xy 87.044226 -485.572525) (xy 87.028713 -485.514632) (xy 87.02089 -485.45521) (xy 80.560822 -485.45521)
			(xy 80.549335 -485.488038) (xy 80.51839 -485.552297) (xy 80.480444 -485.612688) (xy 80.435975 -485.66845)
			(xy 80.385542 -485.718883) (xy 80.32978 -485.763352) (xy 80.269389 -485.801298) (xy 80.20513 -485.832243)
			(xy 80.13781 -485.8558) (xy 80.068275 -485.87167) (xy 79.997401 -485.879656) (xy 79.926079 -485.879656)
			(xy 79.855205 -485.87167) (xy 79.78567 -485.8558) (xy 79.71835 -485.832243) (xy 79.654091 -485.801298)
			(xy 79.5937 -485.763352) (xy 79.537938 -485.718883) (xy 79.487505 -485.66845) (xy 79.443036 -485.612688)
			(xy 79.40509 -485.552297) (xy 79.374145 -485.488038) (xy 79.350588 -485.420718) (xy 79.334718 -485.351183)
			(xy 79.326732 -485.280309) (xy 78.667618 -485.280309) (xy 78.659632 -485.351183) (xy 78.643762 -485.420718)
			(xy 78.620205 -485.488038) (xy 78.58926 -485.552297) (xy 78.551314 -485.612688) (xy 78.506845 -485.66845)
			(xy 78.456412 -485.718883) (xy 78.40065 -485.763352) (xy 78.340259 -485.801298) (xy 78.276 -485.832243)
			(xy 78.20868 -485.8558) (xy 78.139145 -485.87167) (xy 78.068271 -485.879656) (xy 77.996949 -485.879656)
			(xy 77.926075 -485.87167) (xy 77.85654 -485.8558) (xy 77.78922 -485.832243) (xy 77.724961 -485.801298)
			(xy 77.66457 -485.763352) (xy 77.608808 -485.718883) (xy 77.558375 -485.66845) (xy 77.513906 -485.612688)
			(xy 77.47596 -485.552297) (xy 77.445015 -485.488038) (xy 77.421458 -485.420718) (xy 77.405588 -485.351183)
			(xy 77.397602 -485.280309) (xy 76.918502 -485.280309) (xy 76.915668 -485.305463) (xy 76.899798 -485.374998)
			(xy 76.876241 -485.442318) (xy 76.845296 -485.506577) (xy 76.80735 -485.566968) (xy 76.762881 -485.62273)
			(xy 76.712448 -485.673163) (xy 76.656686 -485.717632) (xy 76.596295 -485.755578) (xy 76.532036 -485.786523)
			(xy 76.464716 -485.81008) (xy 76.395181 -485.82595) (xy 76.324307 -485.833936) (xy 76.252985 -485.833936)
			(xy 76.182111 -485.82595) (xy 76.112576 -485.81008) (xy 76.045256 -485.786523) (xy 75.980997 -485.755578)
			(xy 75.920606 -485.717632) (xy 75.864844 -485.673163) (xy 75.814411 -485.62273) (xy 75.769942 -485.566968)
			(xy 75.731996 -485.506577) (xy 75.701051 -485.442318) (xy 75.677494 -485.374998) (xy 75.661624 -485.305463)
			(xy 75.653638 -485.234589) (xy 74.994524 -485.234589) (xy 74.986538 -485.305463) (xy 74.970668 -485.374998)
			(xy 74.947111 -485.442318) (xy 74.916166 -485.506577) (xy 74.87822 -485.566968) (xy 74.833751 -485.62273)
			(xy 74.783318 -485.673163) (xy 74.727556 -485.717632) (xy 74.667165 -485.755578) (xy 74.602906 -485.786523)
			(xy 74.535586 -485.81008) (xy 74.466051 -485.82595) (xy 74.395177 -485.833936) (xy 74.323855 -485.833936)
			(xy 74.252981 -485.82595) (xy 74.183446 -485.81008) (xy 74.116126 -485.786523) (xy 74.051867 -485.755578)
			(xy 73.991476 -485.717632) (xy 73.935714 -485.673163) (xy 73.885281 -485.62273) (xy 73.840812 -485.566968)
			(xy 73.802866 -485.506577) (xy 73.771921 -485.442318) (xy 73.748364 -485.374998) (xy 73.732494 -485.305463)
			(xy 73.724508 -485.234589) (xy 0.509016 -485.234589) (xy 0.509016 -488.294325) (xy 1.150876 -488.294325)
			(xy 1.152892 -488.164712) (xy 1.162962 -488.035476) (xy 1.181047 -487.907115) (xy 1.207077 -487.780127)
			(xy 1.240952 -487.655003) (xy 1.28254 -487.532227) (xy 1.331681 -487.412274) (xy 1.388184 -487.295609)
			(xy 1.451831 -487.182681) (xy 1.522375 -487.073929) (xy 1.599544 -486.969773) (xy 1.683039 -486.870616)
			(xy 1.772537 -486.776842) (xy 1.867692 -486.688813) (xy 1.968135 -486.60687) (xy 2.073478 -486.531331)
			(xy 2.183314 -486.462486) (xy 2.297218 -486.400603) (xy 2.414748 -486.345922) (xy 2.535451 -486.298652)
			(xy 2.658859 -486.258979) (xy 2.784495 -486.227054) (xy 2.911872 -486.203002) (xy 3.040498 -486.186915)
			(xy 3.169876 -486.178856) (xy 3.23469 -486.178352) (xy 3.299504 -486.178856) (xy 3.428882 -486.186915)
			(xy 3.557508 -486.203002) (xy 3.684885 -486.227054) (xy 3.810521 -486.258979) (xy 3.933929 -486.298652)
			(xy 4.054632 -486.345922) (xy 4.172162 -486.400603) (xy 4.286066 -486.462486) (xy 4.395902 -486.531331)
			(xy 4.501245 -486.60687) (xy 4.601688 -486.688813) (xy 4.696843 -486.776842) (xy 4.786341 -486.870616)
			(xy 4.869836 -486.969773) (xy 4.947005 -487.073929) (xy 5.017549 -487.182681) (xy 5.081196 -487.295609)
			(xy 5.137699 -487.412274) (xy 5.18684 -487.532227) (xy 5.228428 -487.655003) (xy 5.262303 -487.780127)
			(xy 5.288333 -487.907115) (xy 5.306418 -488.035476) (xy 5.316488 -488.164712) (xy 5.318504 -488.294325)
			(xy 12.580876 -488.294325) (xy 12.582892 -488.164712) (xy 12.592962 -488.035476) (xy 12.611047 -487.907115)
			(xy 12.637077 -487.780127) (xy 12.670952 -487.655003) (xy 12.71254 -487.532227) (xy 12.761681 -487.412274)
			(xy 12.818184 -487.295609) (xy 12.881831 -487.182681) (xy 12.952375 -487.073929) (xy 13.029544 -486.969773)
			(xy 13.113039 -486.870616) (xy 13.202537 -486.776842) (xy 13.297692 -486.688813) (xy 13.398135 -486.60687)
			(xy 13.503478 -486.531331) (xy 13.613314 -486.462486) (xy 13.727218 -486.400603) (xy 13.844748 -486.345922)
			(xy 13.965451 -486.298652) (xy 14.088859 -486.258979) (xy 14.214495 -486.227054) (xy 14.341872 -486.203002)
			(xy 14.470498 -486.186915) (xy 14.599876 -486.178856) (xy 14.66469 -486.178352) (xy 14.729504 -486.178856)
			(xy 14.858882 -486.186915) (xy 14.987508 -486.203002) (xy 15.114885 -486.227054) (xy 15.240521 -486.258979)
			(xy 15.363929 -486.298652) (xy 15.484632 -486.345922) (xy 15.602162 -486.400603) (xy 15.716066 -486.462486)
			(xy 15.825902 -486.531331) (xy 15.931245 -486.60687) (xy 16.031688 -486.688813) (xy 16.126843 -486.776842)
			(xy 16.216341 -486.870616) (xy 16.299836 -486.969773) (xy 16.31575 -486.991253) (xy 73.724508 -486.991253)
			(xy 73.724508 -486.919931) (xy 73.732494 -486.849057) (xy 73.748364 -486.779522) (xy 73.771921 -486.712202)
			(xy 73.802866 -486.647943) (xy 73.840812 -486.587552) (xy 73.885281 -486.53179) (xy 73.935714 -486.481357)
			(xy 73.991476 -486.436888) (xy 74.051867 -486.398942) (xy 74.116126 -486.367997) (xy 74.183446 -486.34444)
			(xy 74.252981 -486.32857) (xy 74.323855 -486.320584) (xy 74.359516 -486.320084) (xy 74.395177 -486.320584)
			(xy 74.466051 -486.32857) (xy 74.535586 -486.34444) (xy 74.602906 -486.367997) (xy 74.667165 -486.398942)
			(xy 74.727556 -486.436888) (xy 74.783318 -486.481357) (xy 74.833751 -486.53179) (xy 74.87822 -486.587552)
			(xy 74.916166 -486.647943) (xy 74.947111 -486.712202) (xy 74.970668 -486.779522) (xy 74.986538 -486.849057)
			(xy 74.994524 -486.919931) (xy 74.994524 -486.991253) (xy 75.653638 -486.991253) (xy 75.653638 -486.919931)
			(xy 75.661624 -486.849057) (xy 75.677494 -486.779522) (xy 75.701051 -486.712202) (xy 75.731996 -486.647943)
			(xy 75.769942 -486.587552) (xy 75.814411 -486.53179) (xy 75.864844 -486.481357) (xy 75.920606 -486.436888)
			(xy 75.980997 -486.398942) (xy 76.045256 -486.367997) (xy 76.112576 -486.34444) (xy 76.182111 -486.32857)
			(xy 76.252985 -486.320584) (xy 76.288646 -486.320084) (xy 76.324307 -486.320584) (xy 76.395181 -486.32857)
			(xy 76.464716 -486.34444) (xy 76.532036 -486.367997) (xy 76.596295 -486.398942) (xy 76.656686 -486.436888)
			(xy 76.712448 -486.481357) (xy 76.762881 -486.53179) (xy 76.80735 -486.587552) (xy 76.845296 -486.647943)
			(xy 76.876241 -486.712202) (xy 76.899798 -486.779522) (xy 76.915668 -486.849057) (xy 76.923654 -486.919931)
			(xy 76.923654 -486.991253) (xy 76.918502 -487.036973) (xy 77.397602 -487.036973) (xy 77.397602 -486.965651)
			(xy 77.405588 -486.894777) (xy 77.421458 -486.825242) (xy 77.445015 -486.757922) (xy 77.47596 -486.693663)
			(xy 77.513906 -486.633272) (xy 77.558375 -486.57751) (xy 77.608808 -486.527077) (xy 77.66457 -486.482608)
			(xy 77.724961 -486.444662) (xy 77.78922 -486.413717) (xy 77.85654 -486.39016) (xy 77.926075 -486.37429)
			(xy 77.996949 -486.366304) (xy 78.03261 -486.365804) (xy 78.068271 -486.366304) (xy 78.139145 -486.37429)
			(xy 78.20868 -486.39016) (xy 78.276 -486.413717) (xy 78.340259 -486.444662) (xy 78.40065 -486.482608)
			(xy 78.456412 -486.527077) (xy 78.506845 -486.57751) (xy 78.551314 -486.633272) (xy 78.58926 -486.693663)
			(xy 78.620205 -486.757922) (xy 78.643762 -486.825242) (xy 78.659632 -486.894777) (xy 78.667618 -486.965651)
			(xy 78.667618 -487.036973) (xy 79.326732 -487.036973) (xy 79.326732 -486.965651) (xy 79.334718 -486.894777)
			(xy 79.350588 -486.825242) (xy 79.374145 -486.757922) (xy 79.40509 -486.693663) (xy 79.443036 -486.633272)
			(xy 79.487505 -486.57751) (xy 79.537938 -486.527077) (xy 79.5937 -486.482608) (xy 79.654091 -486.444662)
			(xy 79.71835 -486.413717) (xy 79.78567 -486.39016) (xy 79.855205 -486.37429) (xy 79.926079 -486.366304)
			(xy 79.96174 -486.365804) (xy 79.997401 -486.366304) (xy 80.068275 -486.37429) (xy 80.13781 -486.39016)
			(xy 80.20513 -486.413717) (xy 80.269389 -486.444662) (xy 80.32978 -486.482608) (xy 80.385542 -486.527077)
			(xy 80.435975 -486.57751) (xy 80.480444 -486.633272) (xy 80.51839 -486.693663) (xy 80.549335 -486.757922)
			(xy 80.572892 -486.825242) (xy 80.575279 -486.8357) (xy 87.30918 -486.8357) (xy 87.30918 -486.775764)
			(xy 87.317003 -486.716342) (xy 87.332516 -486.658449) (xy 87.355452 -486.603076) (xy 87.385419 -486.55117)
			(xy 87.421906 -486.50362) (xy 87.464286 -486.46124) (xy 87.511836 -486.424753) (xy 87.563742 -486.394786)
			(xy 87.619115 -486.37185) (xy 87.677008 -486.356337) (xy 87.73643 -486.348514) (xy 87.766398 -486.348024)
			(xy 87.796366 -486.348514) (xy 87.855788 -486.356337) (xy 87.913681 -486.37185) (xy 87.969054 -486.394786)
			(xy 88.02096 -486.424753) (xy 88.06851 -486.46124) (xy 88.11089 -486.50362) (xy 88.147377 -486.55117)
			(xy 88.177344 -486.603076) (xy 88.20028 -486.658449) (xy 88.215793 -486.716342) (xy 88.223616 -486.775764)
			(xy 88.223616 -486.8357) (xy 88.215793 -486.895122) (xy 88.20028 -486.953015) (xy 88.177344 -487.008388)
			(xy 88.147377 -487.060294) (xy 88.11089 -487.107844) (xy 88.06851 -487.150224) (xy 88.02096 -487.186711)
			(xy 87.969054 -487.216678) (xy 87.913681 -487.239614) (xy 87.855788 -487.255127) (xy 87.796366 -487.26295)
			(xy 87.73643 -487.26295) (xy 87.677008 -487.255127) (xy 87.619115 -487.239614) (xy 87.563742 -487.216678)
			(xy 87.511836 -487.186711) (xy 87.464286 -487.150224) (xy 87.421906 -487.107844) (xy 87.385419 -487.060294)
			(xy 87.355452 -487.008388) (xy 87.332516 -486.953015) (xy 87.317003 -486.895122) (xy 87.30918 -486.8357)
			(xy 80.575279 -486.8357) (xy 80.588762 -486.894777) (xy 80.596748 -486.965651) (xy 80.596748 -487.036973)
			(xy 80.588762 -487.107847) (xy 80.572892 -487.177382) (xy 80.549335 -487.244702) (xy 80.531629 -487.28147)
			(xy 91.836476 -487.28147) (xy 91.836476 -487.221534) (xy 91.844299 -487.162112) (xy 91.859812 -487.104219)
			(xy 91.882748 -487.048846) (xy 91.912715 -486.99694) (xy 91.949202 -486.94939) (xy 91.991582 -486.90701)
			(xy 92.039132 -486.870523) (xy 92.091038 -486.840556) (xy 92.146411 -486.81762) (xy 92.204304 -486.802107)
			(xy 92.263726 -486.794284) (xy 92.293694 -486.793794) (xy 92.323662 -486.794284) (xy 92.383084 -486.802107)
			(xy 92.440977 -486.81762) (xy 92.49635 -486.840556) (xy 92.548256 -486.870523) (xy 92.595806 -486.90701)
			(xy 92.638186 -486.94939) (xy 92.674673 -486.99694) (xy 92.684674 -487.014262) (xy 95.911144 -487.014262)
			(xy 95.911144 -486.954326) (xy 95.918967 -486.894904) (xy 95.93448 -486.837011) (xy 95.957416 -486.781638)
			(xy 95.987383 -486.729732) (xy 96.02387 -486.682182) (xy 96.06625 -486.639802) (xy 96.1138 -486.603315)
			(xy 96.165706 -486.573348) (xy 96.221079 -486.550412) (xy 96.278972 -486.534899) (xy 96.338394 -486.527076)
			(xy 96.368362 -486.526586) (xy 96.39833 -486.527076) (xy 96.457752 -486.534899) (xy 96.515645 -486.550412)
			(xy 96.571018 -486.573348) (xy 96.622924 -486.603315) (xy 96.670474 -486.639802) (xy 96.712854 -486.682182)
			(xy 96.749341 -486.729732) (xy 96.779308 -486.781638) (xy 96.802244 -486.837011) (xy 96.817757 -486.894904)
			(xy 96.82558 -486.954326) (xy 96.82558 -487.014262) (xy 96.817757 -487.073684) (xy 96.802244 -487.131577)
			(xy 96.779308 -487.18695) (xy 96.749341 -487.238856) (xy 96.712854 -487.286406) (xy 96.670474 -487.328786)
			(xy 96.622924 -487.365273) (xy 96.571018 -487.39524) (xy 96.515645 -487.418176) (xy 96.457752 -487.433689)
			(xy 96.39833 -487.441512) (xy 96.338394 -487.441512) (xy 96.278972 -487.433689) (xy 96.221079 -487.418176)
			(xy 96.165706 -487.39524) (xy 96.1138 -487.365273) (xy 96.06625 -487.328786) (xy 96.02387 -487.286406)
			(xy 95.987383 -487.238856) (xy 95.957416 -487.18695) (xy 95.93448 -487.131577) (xy 95.918967 -487.073684)
			(xy 95.911144 -487.014262) (xy 92.684674 -487.014262) (xy 92.70464 -487.048846) (xy 92.727576 -487.104219)
			(xy 92.743089 -487.162112) (xy 92.750912 -487.221534) (xy 92.750912 -487.28147) (xy 92.743089 -487.340892)
			(xy 92.727576 -487.398785) (xy 92.70464 -487.454158) (xy 92.674673 -487.506064) (xy 92.665752 -487.51769)
			(xy 94.735632 -487.51769) (xy 94.735632 -487.457754) (xy 94.743455 -487.398332) (xy 94.758968 -487.340439)
			(xy 94.781904 -487.285066) (xy 94.811871 -487.23316) (xy 94.848358 -487.18561) (xy 94.890738 -487.14323)
			(xy 94.938288 -487.106743) (xy 94.990194 -487.076776) (xy 95.045567 -487.05384) (xy 95.10346 -487.038327)
			(xy 95.162882 -487.030504) (xy 95.19285 -487.030014) (xy 95.222818 -487.030504) (xy 95.28224 -487.038327)
			(xy 95.340133 -487.05384) (xy 95.395506 -487.076776) (xy 95.447412 -487.106743) (xy 95.494962 -487.14323)
			(xy 95.537342 -487.18561) (xy 95.573829 -487.23316) (xy 95.603796 -487.285066) (xy 95.626732 -487.340439)
			(xy 95.642245 -487.398332) (xy 95.650068 -487.457754) (xy 95.650068 -487.51769) (xy 95.642245 -487.577112)
			(xy 95.626732 -487.635005) (xy 95.603796 -487.690378) (xy 95.573829 -487.742284) (xy 95.537342 -487.789834)
			(xy 95.494962 -487.832214) (xy 95.447412 -487.868701) (xy 95.395506 -487.898668) (xy 95.340133 -487.921604)
			(xy 95.28224 -487.937117) (xy 95.222818 -487.94494) (xy 95.162882 -487.94494) (xy 95.10346 -487.937117)
			(xy 95.045567 -487.921604) (xy 94.990194 -487.898668) (xy 94.938288 -487.868701) (xy 94.890738 -487.832214)
			(xy 94.848358 -487.789834) (xy 94.811871 -487.742284) (xy 94.781904 -487.690378) (xy 94.758968 -487.635005)
			(xy 94.743455 -487.577112) (xy 94.735632 -487.51769) (xy 92.665752 -487.51769) (xy 92.638186 -487.553614)
			(xy 92.595806 -487.595994) (xy 92.548256 -487.632481) (xy 92.49635 -487.662448) (xy 92.440977 -487.685384)
			(xy 92.383084 -487.700897) (xy 92.323662 -487.70872) (xy 92.263726 -487.70872) (xy 92.204304 -487.700897)
			(xy 92.146411 -487.685384) (xy 92.091038 -487.662448) (xy 92.039132 -487.632481) (xy 91.991582 -487.595994)
			(xy 91.949202 -487.553614) (xy 91.912715 -487.506064) (xy 91.882748 -487.454158) (xy 91.859812 -487.398785)
			(xy 91.844299 -487.340892) (xy 91.836476 -487.28147) (xy 80.531629 -487.28147) (xy 80.51839 -487.308961)
			(xy 80.480444 -487.369352) (xy 80.435975 -487.425114) (xy 80.385542 -487.475547) (xy 80.32978 -487.520016)
			(xy 80.269389 -487.557962) (xy 80.20513 -487.588907) (xy 80.13781 -487.612464) (xy 80.068275 -487.628334)
			(xy 79.997401 -487.63632) (xy 79.926079 -487.63632) (xy 79.855205 -487.628334) (xy 79.78567 -487.612464)
			(xy 79.71835 -487.588907) (xy 79.654091 -487.557962) (xy 79.5937 -487.520016) (xy 79.537938 -487.475547)
			(xy 79.487505 -487.425114) (xy 79.443036 -487.369352) (xy 79.40509 -487.308961) (xy 79.374145 -487.244702)
			(xy 79.350588 -487.177382) (xy 79.334718 -487.107847) (xy 79.326732 -487.036973) (xy 78.667618 -487.036973)
			(xy 78.659632 -487.107847) (xy 78.643762 -487.177382) (xy 78.620205 -487.244702) (xy 78.58926 -487.308961)
			(xy 78.551314 -487.369352) (xy 78.506845 -487.425114) (xy 78.456412 -487.475547) (xy 78.40065 -487.520016)
			(xy 78.340259 -487.557962) (xy 78.276 -487.588907) (xy 78.20868 -487.612464) (xy 78.139145 -487.628334)
			(xy 78.068271 -487.63632) (xy 77.996949 -487.63632) (xy 77.926075 -487.628334) (xy 77.85654 -487.612464)
			(xy 77.78922 -487.588907) (xy 77.724961 -487.557962) (xy 77.66457 -487.520016) (xy 77.608808 -487.475547)
			(xy 77.558375 -487.425114) (xy 77.513906 -487.369352) (xy 77.47596 -487.308961) (xy 77.445015 -487.244702)
			(xy 77.421458 -487.177382) (xy 77.405588 -487.107847) (xy 77.397602 -487.036973) (xy 76.918502 -487.036973)
			(xy 76.915668 -487.062127) (xy 76.899798 -487.131662) (xy 76.876241 -487.198982) (xy 76.845296 -487.263241)
			(xy 76.80735 -487.323632) (xy 76.762881 -487.379394) (xy 76.712448 -487.429827) (xy 76.656686 -487.474296)
			(xy 76.596295 -487.512242) (xy 76.532036 -487.543187) (xy 76.464716 -487.566744) (xy 76.395181 -487.582614)
			(xy 76.324307 -487.5906) (xy 76.252985 -487.5906) (xy 76.182111 -487.582614) (xy 76.112576 -487.566744)
			(xy 76.045256 -487.543187) (xy 75.980997 -487.512242) (xy 75.920606 -487.474296) (xy 75.864844 -487.429827)
			(xy 75.814411 -487.379394) (xy 75.769942 -487.323632) (xy 75.731996 -487.263241) (xy 75.701051 -487.198982)
			(xy 75.677494 -487.131662) (xy 75.661624 -487.062127) (xy 75.653638 -486.991253) (xy 74.994524 -486.991253)
			(xy 74.986538 -487.062127) (xy 74.970668 -487.131662) (xy 74.947111 -487.198982) (xy 74.916166 -487.263241)
			(xy 74.87822 -487.323632) (xy 74.833751 -487.379394) (xy 74.783318 -487.429827) (xy 74.727556 -487.474296)
			(xy 74.667165 -487.512242) (xy 74.602906 -487.543187) (xy 74.535586 -487.566744) (xy 74.466051 -487.582614)
			(xy 74.395177 -487.5906) (xy 74.323855 -487.5906) (xy 74.252981 -487.582614) (xy 74.183446 -487.566744)
			(xy 74.116126 -487.543187) (xy 74.051867 -487.512242) (xy 73.991476 -487.474296) (xy 73.935714 -487.429827)
			(xy 73.885281 -487.379394) (xy 73.840812 -487.323632) (xy 73.802866 -487.263241) (xy 73.771921 -487.198982)
			(xy 73.748364 -487.131662) (xy 73.732494 -487.062127) (xy 73.724508 -486.991253) (xy 16.31575 -486.991253)
			(xy 16.377005 -487.073929) (xy 16.447549 -487.182681) (xy 16.511196 -487.295609) (xy 16.567699 -487.412274)
			(xy 16.61684 -487.532227) (xy 16.658428 -487.655003) (xy 16.692303 -487.780127) (xy 16.718333 -487.907115)
			(xy 16.736418 -488.035476) (xy 16.746488 -488.164712) (xy 16.748504 -488.294325) (xy 16.742458 -488.423812)
			(xy 16.728374 -488.552673) (xy 16.706305 -488.680409) (xy 16.68791 -488.757823) (xy 73.724508 -488.757823)
			(xy 73.724508 -488.686501) (xy 73.732494 -488.615627) (xy 73.748364 -488.546092) (xy 73.771921 -488.478772)
			(xy 73.802866 -488.414513) (xy 73.840812 -488.354122) (xy 73.885281 -488.29836) (xy 73.935714 -488.247927)
			(xy 73.991476 -488.203458) (xy 74.051867 -488.165512) (xy 74.116126 -488.134567) (xy 74.183446 -488.11101)
			(xy 74.252981 -488.09514) (xy 74.323855 -488.087154) (xy 74.359516 -488.086654) (xy 74.395177 -488.087154)
			(xy 74.466051 -488.09514) (xy 74.535586 -488.11101) (xy 74.602906 -488.134567) (xy 74.667165 -488.165512)
			(xy 74.727556 -488.203458) (xy 74.783318 -488.247927) (xy 74.833751 -488.29836) (xy 74.87822 -488.354122)
			(xy 74.916166 -488.414513) (xy 74.947111 -488.478772) (xy 74.970668 -488.546092) (xy 74.986538 -488.615627)
			(xy 74.994524 -488.686501) (xy 74.994524 -488.757823) (xy 75.653638 -488.757823) (xy 75.653638 -488.686501)
			(xy 75.661624 -488.615627) (xy 75.677494 -488.546092) (xy 75.701051 -488.478772) (xy 75.731996 -488.414513)
			(xy 75.769942 -488.354122) (xy 75.814411 -488.29836) (xy 75.864844 -488.247927) (xy 75.920606 -488.203458)
			(xy 75.980997 -488.165512) (xy 76.045256 -488.134567) (xy 76.112576 -488.11101) (xy 76.182111 -488.09514)
			(xy 76.252985 -488.087154) (xy 76.288646 -488.086654) (xy 76.324307 -488.087154) (xy 76.395181 -488.09514)
			(xy 76.464716 -488.11101) (xy 76.532036 -488.134567) (xy 76.596295 -488.165512) (xy 76.656686 -488.203458)
			(xy 76.712448 -488.247927) (xy 76.762881 -488.29836) (xy 76.80735 -488.354122) (xy 76.845296 -488.414513)
			(xy 76.876241 -488.478772) (xy 76.899798 -488.546092) (xy 76.915668 -488.615627) (xy 76.923654 -488.686501)
			(xy 76.923654 -488.757823) (xy 76.918502 -488.803543) (xy 77.397602 -488.803543) (xy 77.397602 -488.732221)
			(xy 77.405588 -488.661347) (xy 77.421458 -488.591812) (xy 77.445015 -488.524492) (xy 77.47596 -488.460233)
			(xy 77.513906 -488.399842) (xy 77.558375 -488.34408) (xy 77.608808 -488.293647) (xy 77.66457 -488.249178)
			(xy 77.724961 -488.211232) (xy 77.78922 -488.180287) (xy 77.85654 -488.15673) (xy 77.926075 -488.14086)
			(xy 77.996949 -488.132874) (xy 78.03261 -488.132374) (xy 78.068271 -488.132874) (xy 78.139145 -488.14086)
			(xy 78.20868 -488.15673) (xy 78.276 -488.180287) (xy 78.340259 -488.211232) (xy 78.40065 -488.249178)
			(xy 78.456412 -488.293647) (xy 78.506845 -488.34408) (xy 78.551314 -488.399842) (xy 78.58926 -488.460233)
			(xy 78.620205 -488.524492) (xy 78.643762 -488.591812) (xy 78.659632 -488.661347) (xy 78.667618 -488.732221)
			(xy 78.667618 -488.803543) (xy 79.326732 -488.803543) (xy 79.326732 -488.732221) (xy 79.334718 -488.661347)
			(xy 79.350588 -488.591812) (xy 79.374145 -488.524492) (xy 79.40509 -488.460233) (xy 79.443036 -488.399842)
			(xy 79.487505 -488.34408) (xy 79.537938 -488.293647) (xy 79.5937 -488.249178) (xy 79.654091 -488.211232)
			(xy 79.71835 -488.180287) (xy 79.78567 -488.15673) (xy 79.855205 -488.14086) (xy 79.926079 -488.132874)
			(xy 79.96174 -488.132374) (xy 79.997401 -488.132874) (xy 80.068275 -488.14086) (xy 80.13781 -488.15673)
			(xy 80.20513 -488.180287) (xy 80.269389 -488.211232) (xy 80.32978 -488.249178) (xy 80.385542 -488.293647)
			(xy 80.413749 -488.321854) (xy 85.988126 -488.321854) (xy 85.988126 -488.261918) (xy 85.995949 -488.202496)
			(xy 86.011462 -488.144603) (xy 86.034398 -488.08923) (xy 86.064365 -488.037324) (xy 86.100852 -487.989774)
			(xy 86.143232 -487.947394) (xy 86.190782 -487.910907) (xy 86.242688 -487.88094) (xy 86.298061 -487.858004)
			(xy 86.355954 -487.842491) (xy 86.415376 -487.834668) (xy 86.445344 -487.834178) (xy 86.475312 -487.834668)
			(xy 86.534734 -487.842491) (xy 86.592627 -487.858004) (xy 86.648 -487.88094) (xy 86.699906 -487.910907)
			(xy 86.747456 -487.947394) (xy 86.789836 -487.989774) (xy 86.826323 -488.037324) (xy 86.85629 -488.08923)
			(xy 86.879226 -488.144603) (xy 86.894739 -488.202496) (xy 86.902293 -488.259878) (xy 87.852486 -488.259878)
			(xy 87.852486 -488.199942) (xy 87.860309 -488.14052) (xy 87.875822 -488.082627) (xy 87.898758 -488.027254)
			(xy 87.928725 -487.975348) (xy 87.965212 -487.927798) (xy 88.007592 -487.885418) (xy 88.055142 -487.848931)
			(xy 88.107048 -487.818964) (xy 88.162421 -487.796028) (xy 88.220314 -487.780515) (xy 88.279736 -487.772692)
			(xy 88.309704 -487.772202) (xy 88.339672 -487.772692) (xy 88.399094 -487.780515) (xy 88.456987 -487.796028)
			(xy 88.51236 -487.818964) (xy 88.564266 -487.848931) (xy 88.608258 -487.882688) (xy 90.555554 -487.882688)
			(xy 90.555554 -487.822752) (xy 90.563377 -487.76333) (xy 90.57889 -487.705437) (xy 90.601826 -487.650064)
			(xy 90.631793 -487.598158) (xy 90.66828 -487.550608) (xy 90.71066 -487.508228) (xy 90.75821 -487.471741)
			(xy 90.810116 -487.441774) (xy 90.865489 -487.418838) (xy 90.923382 -487.403325) (xy 90.982804 -487.395502)
			(xy 91.012772 -487.395012) (xy 91.04274 -487.395502) (xy 91.102162 -487.403325) (xy 91.160055 -487.418838)
			(xy 91.215428 -487.441774) (xy 91.267334 -487.471741) (xy 91.314884 -487.508228) (xy 91.357264 -487.550608)
			(xy 91.393751 -487.598158) (xy 91.423718 -487.650064) (xy 91.446654 -487.705437) (xy 91.462167 -487.76333)
			(xy 91.46999 -487.822752) (xy 91.46999 -487.882688) (xy 91.462167 -487.94211) (xy 91.446654 -488.000003)
			(xy 91.423718 -488.055376) (xy 91.393751 -488.107282) (xy 91.357264 -488.154832) (xy 91.314884 -488.197212)
			(xy 91.267334 -488.233699) (xy 91.215428 -488.263666) (xy 91.160055 -488.286602) (xy 91.102162 -488.302115)
			(xy 91.04274 -488.309938) (xy 90.982804 -488.309938) (xy 90.923382 -488.302115) (xy 90.865489 -488.286602)
			(xy 90.810116 -488.263666) (xy 90.75821 -488.233699) (xy 90.71066 -488.197212) (xy 90.66828 -488.154832)
			(xy 90.631793 -488.107282) (xy 90.601826 -488.055376) (xy 90.57889 -488.000003) (xy 90.563377 -487.94211)
			(xy 90.555554 -487.882688) (xy 88.608258 -487.882688) (xy 88.611816 -487.885418) (xy 88.654196 -487.927798)
			(xy 88.690683 -487.975348) (xy 88.72065 -488.027254) (xy 88.743586 -488.082627) (xy 88.759099 -488.14052)
			(xy 88.766922 -488.199942) (xy 88.766922 -488.259878) (xy 88.759099 -488.3193) (xy 88.743586 -488.377193)
			(xy 88.72065 -488.432566) (xy 88.690683 -488.484472) (xy 88.654196 -488.532022) (xy 88.611816 -488.574402)
			(xy 88.593373 -488.588554) (xy 91.849176 -488.588554) (xy 91.849176 -488.528618) (xy 91.856999 -488.469196)
			(xy 91.872512 -488.411303) (xy 91.895448 -488.35593) (xy 91.925415 -488.304024) (xy 91.961902 -488.256474)
			(xy 92.004282 -488.214094) (xy 92.051832 -488.177607) (xy 92.103738 -488.14764) (xy 92.159111 -488.124704)
			(xy 92.217004 -488.109191) (xy 92.276426 -488.101368) (xy 92.306394 -488.100878) (xy 92.336362 -488.101368)
			(xy 92.395784 -488.109191) (xy 92.453677 -488.124704) (xy 92.50905 -488.14764) (xy 92.540675 -488.165898)
			(xy 93.458774 -488.165898) (xy 93.458774 -488.105962) (xy 93.466597 -488.04654) (xy 93.48211 -487.988647)
			(xy 93.505046 -487.933274) (xy 93.535013 -487.881368) (xy 93.5715 -487.833818) (xy 93.61388 -487.791438)
			(xy 93.66143 -487.754951) (xy 93.713336 -487.724984) (xy 93.768709 -487.702048) (xy 93.826602 -487.686535)
			(xy 93.886024 -487.678712) (xy 93.915992 -487.678222) (xy 93.94596 -487.678712) (xy 94.005382 -487.686535)
			(xy 94.063275 -487.702048) (xy 94.118648 -487.724984) (xy 94.170554 -487.754951) (xy 94.218104 -487.791438)
			(xy 94.260484 -487.833818) (xy 94.296971 -487.881368) (xy 94.326938 -487.933274) (xy 94.349874 -487.988647)
			(xy 94.365387 -488.04654) (xy 94.37321 -488.105962) (xy 94.37321 -488.165898) (xy 94.365387 -488.22532)
			(xy 94.349874 -488.283213) (xy 94.326938 -488.338586) (xy 94.296971 -488.390492) (xy 94.260484 -488.438042)
			(xy 94.218104 -488.480422) (xy 94.170554 -488.516909) (xy 94.118648 -488.546876) (xy 94.063275 -488.569812)
			(xy 94.005382 -488.585325) (xy 93.94596 -488.593148) (xy 93.886024 -488.593148) (xy 93.826602 -488.585325)
			(xy 93.768709 -488.569812) (xy 93.713336 -488.546876) (xy 93.66143 -488.516909) (xy 93.61388 -488.480422)
			(xy 93.5715 -488.438042) (xy 93.535013 -488.390492) (xy 93.505046 -488.338586) (xy 93.48211 -488.283213)
			(xy 93.466597 -488.22532) (xy 93.458774 -488.165898) (xy 92.540675 -488.165898) (xy 92.560956 -488.177607)
			(xy 92.608506 -488.214094) (xy 92.650886 -488.256474) (xy 92.687373 -488.304024) (xy 92.71734 -488.35593)
			(xy 92.740276 -488.411303) (xy 92.755789 -488.469196) (xy 92.763612 -488.528618) (xy 92.763612 -488.588554)
			(xy 92.755789 -488.647976) (xy 92.740276 -488.705869) (xy 92.71734 -488.761242) (xy 92.687373 -488.813148)
			(xy 92.650886 -488.860698) (xy 92.608506 -488.903078) (xy 92.560956 -488.939565) (xy 92.50905 -488.969532)
			(xy 92.453677 -488.992468) (xy 92.395784 -489.007981) (xy 92.336362 -489.015804) (xy 92.276426 -489.015804)
			(xy 92.217004 -489.007981) (xy 92.159111 -488.992468) (xy 92.103738 -488.969532) (xy 92.051832 -488.939565)
			(xy 92.004282 -488.903078) (xy 91.961902 -488.860698) (xy 91.925415 -488.813148) (xy 91.895448 -488.761242)
			(xy 91.872512 -488.705869) (xy 91.856999 -488.647976) (xy 91.849176 -488.588554) (xy 88.593373 -488.588554)
			(xy 88.564266 -488.610889) (xy 88.51236 -488.640856) (xy 88.456987 -488.663792) (xy 88.399094 -488.679305)
			(xy 88.339672 -488.687128) (xy 88.279736 -488.687128) (xy 88.220314 -488.679305) (xy 88.162421 -488.663792)
			(xy 88.107048 -488.640856) (xy 88.055142 -488.610889) (xy 88.007592 -488.574402) (xy 87.965212 -488.532022)
			(xy 87.928725 -488.484472) (xy 87.898758 -488.432566) (xy 87.875822 -488.377193) (xy 87.860309 -488.3193)
			(xy 87.852486 -488.259878) (xy 86.902293 -488.259878) (xy 86.902562 -488.261918) (xy 86.902562 -488.321854)
			(xy 86.894739 -488.381276) (xy 86.879226 -488.439169) (xy 86.85629 -488.494542) (xy 86.826323 -488.546448)
			(xy 86.789836 -488.593998) (xy 86.747456 -488.636378) (xy 86.699906 -488.672865) (xy 86.648 -488.702832)
			(xy 86.592627 -488.725768) (xy 86.534734 -488.741281) (xy 86.475312 -488.749104) (xy 86.415376 -488.749104)
			(xy 86.355954 -488.741281) (xy 86.298061 -488.725768) (xy 86.242688 -488.702832) (xy 86.190782 -488.672865)
			(xy 86.143232 -488.636378) (xy 86.100852 -488.593998) (xy 86.064365 -488.546448) (xy 86.034398 -488.494542)
			(xy 86.011462 -488.439169) (xy 85.995949 -488.381276) (xy 85.988126 -488.321854) (xy 80.413749 -488.321854)
			(xy 80.435975 -488.34408) (xy 80.480444 -488.399842) (xy 80.51839 -488.460233) (xy 80.549335 -488.524492)
			(xy 80.572892 -488.591812) (xy 80.588762 -488.661347) (xy 80.596748 -488.732221) (xy 80.596748 -488.803543)
			(xy 80.588762 -488.874417) (xy 80.572892 -488.943952) (xy 80.549335 -489.011272) (xy 80.51839 -489.075531)
			(xy 80.480444 -489.135922) (xy 80.435975 -489.191684) (xy 80.385542 -489.242117) (xy 80.32978 -489.286586)
			(xy 80.269389 -489.324532) (xy 80.20513 -489.355477) (xy 80.13781 -489.379034) (xy 80.068275 -489.394904)
			(xy 79.997401 -489.40289) (xy 79.926079 -489.40289) (xy 79.855205 -489.394904) (xy 79.78567 -489.379034)
			(xy 79.71835 -489.355477) (xy 79.654091 -489.324532) (xy 79.5937 -489.286586) (xy 79.537938 -489.242117)
			(xy 79.487505 -489.191684) (xy 79.443036 -489.135922) (xy 79.40509 -489.075531) (xy 79.374145 -489.011272)
			(xy 79.350588 -488.943952) (xy 79.334718 -488.874417) (xy 79.326732 -488.803543) (xy 78.667618 -488.803543)
			(xy 78.659632 -488.874417) (xy 78.643762 -488.943952) (xy 78.620205 -489.011272) (xy 78.58926 -489.075531)
			(xy 78.551314 -489.135922) (xy 78.506845 -489.191684) (xy 78.456412 -489.242117) (xy 78.40065 -489.286586)
			(xy 78.340259 -489.324532) (xy 78.276 -489.355477) (xy 78.20868 -489.379034) (xy 78.139145 -489.394904)
			(xy 78.068271 -489.40289) (xy 77.996949 -489.40289) (xy 77.926075 -489.394904) (xy 77.85654 -489.379034)
			(xy 77.78922 -489.355477) (xy 77.724961 -489.324532) (xy 77.66457 -489.286586) (xy 77.608808 -489.242117)
			(xy 77.558375 -489.191684) (xy 77.513906 -489.135922) (xy 77.47596 -489.075531) (xy 77.445015 -489.011272)
			(xy 77.421458 -488.943952) (xy 77.405588 -488.874417) (xy 77.397602 -488.803543) (xy 76.918502 -488.803543)
			(xy 76.915668 -488.828697) (xy 76.899798 -488.898232) (xy 76.876241 -488.965552) (xy 76.845296 -489.029811)
			(xy 76.80735 -489.090202) (xy 76.762881 -489.145964) (xy 76.712448 -489.196397) (xy 76.656686 -489.240866)
			(xy 76.596295 -489.278812) (xy 76.532036 -489.309757) (xy 76.464716 -489.333314) (xy 76.395181 -489.349184)
			(xy 76.324307 -489.35717) (xy 76.252985 -489.35717) (xy 76.182111 -489.349184) (xy 76.112576 -489.333314)
			(xy 76.045256 -489.309757) (xy 75.980997 -489.278812) (xy 75.920606 -489.240866) (xy 75.864844 -489.196397)
			(xy 75.814411 -489.145964) (xy 75.769942 -489.090202) (xy 75.731996 -489.029811) (xy 75.701051 -488.965552)
			(xy 75.677494 -488.898232) (xy 75.661624 -488.828697) (xy 75.653638 -488.757823) (xy 74.994524 -488.757823)
			(xy 74.986538 -488.828697) (xy 74.970668 -488.898232) (xy 74.947111 -488.965552) (xy 74.916166 -489.029811)
			(xy 74.87822 -489.090202) (xy 74.833751 -489.145964) (xy 74.783318 -489.196397) (xy 74.727556 -489.240866)
			(xy 74.667165 -489.278812) (xy 74.602906 -489.309757) (xy 74.535586 -489.333314) (xy 74.466051 -489.349184)
			(xy 74.395177 -489.35717) (xy 74.323855 -489.35717) (xy 74.252981 -489.349184) (xy 74.183446 -489.333314)
			(xy 74.116126 -489.309757) (xy 74.051867 -489.278812) (xy 73.991476 -489.240866) (xy 73.935714 -489.196397)
			(xy 73.885281 -489.145964) (xy 73.840812 -489.090202) (xy 73.802866 -489.029811) (xy 73.771921 -488.965552)
			(xy 73.748364 -488.898232) (xy 73.732494 -488.828697) (xy 73.724508 -488.757823) (xy 16.68791 -488.757823)
			(xy 16.676338 -488.806526) (xy 16.638589 -488.930536) (xy 16.593202 -489.051959) (xy 16.540355 -489.170326)
			(xy 16.480251 -489.285178) (xy 16.413123 -489.396071) (xy 16.386901 -489.433866) (xy 83.972128 -489.433866)
			(xy 83.972128 -489.37393) (xy 83.979951 -489.314508) (xy 83.995464 -489.256615) (xy 84.0184 -489.201242)
			(xy 84.048367 -489.149336) (xy 84.084854 -489.101786) (xy 84.127234 -489.059406) (xy 84.174784 -489.022919)
			(xy 84.22669 -488.992952) (xy 84.282063 -488.970016) (xy 84.339956 -488.954503) (xy 84.399378 -488.94668)
			(xy 84.429346 -488.94619) (xy 84.459314 -488.94668) (xy 84.518736 -488.954503) (xy 84.576629 -488.970016)
			(xy 84.632002 -488.992952) (xy 84.683908 -489.022919) (xy 84.731458 -489.059406) (xy 84.773838 -489.101786)
			(xy 84.810325 -489.149336) (xy 84.840292 -489.201242) (xy 84.863228 -489.256615) (xy 84.878741 -489.314508)
			(xy 84.886564 -489.37393) (xy 84.886564 -489.433866) (xy 84.878741 -489.493288) (xy 84.863228 -489.551181)
			(xy 84.840292 -489.606554) (xy 84.817397 -489.64621) (xy 85.473268 -489.64621) (xy 85.473268 -489.586274)
			(xy 85.481091 -489.526852) (xy 85.496604 -489.468959) (xy 85.51954 -489.413586) (xy 85.549507 -489.36168)
			(xy 85.585994 -489.31413) (xy 85.628374 -489.27175) (xy 85.675924 -489.235263) (xy 85.72783 -489.205296)
			(xy 85.783203 -489.18236) (xy 85.841096 -489.166847) (xy 85.900518 -489.159024) (xy 85.930486 -489.158534)
			(xy 85.960454 -489.159024) (xy 86.019876 -489.166847) (xy 86.077769 -489.18236) (xy 86.133142 -489.205296)
			(xy 86.185048 -489.235263) (xy 86.232598 -489.27175) (xy 86.274978 -489.31413) (xy 86.311465 -489.36168)
			(xy 86.341432 -489.413586) (xy 86.364368 -489.468959) (xy 86.379881 -489.526852) (xy 86.387704 -489.586274)
			(xy 86.387704 -489.64621) (xy 86.379881 -489.705632) (xy 86.364368 -489.763525) (xy 86.341432 -489.818898)
			(xy 86.311465 -489.870804) (xy 86.274978 -489.918354) (xy 86.232598 -489.960734) (xy 86.185048 -489.997221)
			(xy 86.133142 -490.027188) (xy 86.077769 -490.050124) (xy 86.019876 -490.065637) (xy 85.960454 -490.07346)
			(xy 85.900518 -490.07346) (xy 85.841096 -490.065637) (xy 85.783203 -490.050124) (xy 85.72783 -490.027188)
			(xy 85.675924 -489.997221) (xy 85.628374 -489.960734) (xy 85.585994 -489.918354) (xy 85.549507 -489.870804)
			(xy 85.51954 -489.818898) (xy 85.496604 -489.763525) (xy 85.481091 -489.705632) (xy 85.473268 -489.64621)
			(xy 84.817397 -489.64621) (xy 84.810325 -489.65846) (xy 84.773838 -489.70601) (xy 84.731458 -489.74839)
			(xy 84.683908 -489.784877) (xy 84.632002 -489.814844) (xy 84.576629 -489.83778) (xy 84.518736 -489.853293)
			(xy 84.459314 -489.861116) (xy 84.399378 -489.861116) (xy 84.339956 -489.853293) (xy 84.282063 -489.83778)
			(xy 84.22669 -489.814844) (xy 84.174784 -489.784877) (xy 84.127234 -489.74839) (xy 84.084854 -489.70601)
			(xy 84.048367 -489.65846) (xy 84.0184 -489.606554) (xy 83.995464 -489.551181) (xy 83.979951 -489.493288)
			(xy 83.972128 -489.433866) (xy 16.386901 -489.433866) (xy 16.339231 -489.502577) (xy 16.25886 -489.604283)
			(xy 16.172322 -489.700795) (xy 16.07995 -489.79174) (xy 15.982104 -489.876767) (xy 15.879161 -489.955547)
			(xy 15.771519 -490.027774) (xy 15.659595 -490.093169) (xy 15.543822 -490.15148) (xy 15.424648 -490.20248)
			(xy 15.302534 -490.245972) (xy 15.177951 -490.281789) (xy 15.051384 -490.309791) (xy 14.92332 -490.32987)
			(xy 14.794256 -490.341949) (xy 14.66469 -490.34598) (xy 14.535124 -490.341949) (xy 14.40606 -490.32987)
			(xy 14.277996 -490.309791) (xy 14.151429 -490.281789) (xy 14.026846 -490.245972) (xy 13.904732 -490.20248)
			(xy 13.785558 -490.15148) (xy 13.669785 -490.093169) (xy 13.557861 -490.027774) (xy 13.450219 -489.955547)
			(xy 13.347276 -489.876767) (xy 13.24943 -489.79174) (xy 13.157058 -489.700795) (xy 13.07052 -489.604283)
			(xy 12.990149 -489.502577) (xy 12.916257 -489.396071) (xy 12.849129 -489.285178) (xy 12.789025 -489.170326)
			(xy 12.736178 -489.051959) (xy 12.690791 -488.930536) (xy 12.653042 -488.806526) (xy 12.623075 -488.680409)
			(xy 12.601006 -488.552673) (xy 12.586922 -488.423812) (xy 12.580876 -488.294325) (xy 5.318504 -488.294325)
			(xy 5.312458 -488.423812) (xy 5.298374 -488.552673) (xy 5.276305 -488.680409) (xy 5.246338 -488.806526)
			(xy 5.208589 -488.930536) (xy 5.163202 -489.051959) (xy 5.110355 -489.170326) (xy 5.050251 -489.285178)
			(xy 4.983123 -489.396071) (xy 4.909231 -489.502577) (xy 4.82886 -489.604283) (xy 4.742322 -489.700795)
			(xy 4.64995 -489.79174) (xy 4.552104 -489.876767) (xy 4.449161 -489.955547) (xy 4.341519 -490.027774)
			(xy 4.229595 -490.093169) (xy 4.113822 -490.15148) (xy 3.994648 -490.20248) (xy 3.872534 -490.245972)
			(xy 3.747951 -490.281789) (xy 3.621384 -490.309791) (xy 3.49332 -490.32987) (xy 3.364256 -490.341949)
			(xy 3.23469 -490.34598) (xy 3.105124 -490.341949) (xy 2.97606 -490.32987) (xy 2.847996 -490.309791)
			(xy 2.721429 -490.281789) (xy 2.596846 -490.245972) (xy 2.474732 -490.20248) (xy 2.355558 -490.15148)
			(xy 2.239785 -490.093169) (xy 2.127861 -490.027774) (xy 2.020219 -489.955547) (xy 1.917276 -489.876767)
			(xy 1.81943 -489.79174) (xy 1.727058 -489.700795) (xy 1.64052 -489.604283) (xy 1.560149 -489.502577)
			(xy 1.486257 -489.396071) (xy 1.419129 -489.285178) (xy 1.359025 -489.170326) (xy 1.306178 -489.051959)
			(xy 1.260791 -488.930536) (xy 1.223042 -488.806526) (xy 1.193075 -488.680409) (xy 1.171006 -488.552673)
			(xy 1.156922 -488.423812) (xy 1.150876 -488.294325) (xy 0.509016 -488.294325) (xy 0.509016 -493.78616)
			(xy 3.678936 -493.78616) (xy 5.330444 -493.78616) (xy 5.330444 -494.652469) (xy 6.21918 -494.652469)
			(xy 6.21918 -494.571359) (xy 6.22713 -494.49064) (xy 6.242953 -494.411089) (xy 6.266498 -494.333473)
			(xy 6.297537 -494.258537) (xy 6.335772 -494.187005) (xy 6.380834 -494.119565) (xy 6.432289 -494.056866)
			(xy 6.489642 -493.999513) (xy 6.552341 -493.948058) (xy 6.619781 -493.902996) (xy 6.691313 -493.864761)
			(xy 6.766249 -493.833722) (xy 6.843865 -493.810177) (xy 6.923416 -493.794354) (xy 7.004135 -493.786404)
			(xy 7.04469 -493.785906) (xy 7.085245 -493.786404) (xy 7.165964 -493.794354) (xy 7.245515 -493.810177)
			(xy 7.323131 -493.833722) (xy 7.398067 -493.864761) (xy 7.469599 -493.902996) (xy 7.537039 -493.948058)
			(xy 7.599738 -493.999513) (xy 7.657091 -494.056866) (xy 7.708546 -494.119565) (xy 7.753608 -494.187005)
			(xy 7.791843 -494.258537) (xy 7.822882 -494.333473) (xy 7.846427 -494.411089) (xy 7.86225 -494.49064)
			(xy 7.8702 -494.571359) (xy 7.8702 -494.652469) (xy 11.29918 -494.652469) (xy 11.29918 -494.571359)
			(xy 11.30713 -494.49064) (xy 11.322953 -494.411089) (xy 11.346498 -494.333473) (xy 11.377537 -494.258537)
			(xy 11.415772 -494.187005) (xy 11.460834 -494.119565) (xy 11.512289 -494.056866) (xy 11.569642 -493.999513)
			(xy 11.632341 -493.948058) (xy 11.699781 -493.902996) (xy 11.771313 -493.864761) (xy 11.846249 -493.833722)
			(xy 11.923865 -493.810177) (xy 12.003416 -493.794354) (xy 12.084135 -493.786404) (xy 12.12469 -493.785906)
			(xy 12.165245 -493.786404) (xy 12.245964 -493.794354) (xy 12.325515 -493.810177) (xy 12.403131 -493.833722)
			(xy 12.478067 -493.864761) (xy 12.549599 -493.902996) (xy 12.617039 -493.948058) (xy 12.679738 -493.999513)
			(xy 12.737091 -494.056866) (xy 12.788546 -494.119565) (xy 12.833608 -494.187005) (xy 12.871843 -494.258537)
			(xy 12.902882 -494.333473) (xy 12.926427 -494.411089) (xy 12.94225 -494.49064) (xy 12.9502 -494.571359)
			(xy 12.9502 -494.652469) (xy 12.94225 -494.733188) (xy 12.926427 -494.812739) (xy 12.902882 -494.890355)
			(xy 12.871843 -494.965291) (xy 12.833608 -495.036823) (xy 12.788546 -495.104263) (xy 12.737091 -495.166962)
			(xy 12.679738 -495.224315) (xy 12.617039 -495.27577) (xy 12.549599 -495.320832) (xy 12.478067 -495.359067)
			(xy 12.403131 -495.390106) (xy 12.325515 -495.413651) (xy 12.245964 -495.429474) (xy 12.165245 -495.437424)
			(xy 12.084135 -495.437424) (xy 12.003416 -495.429474) (xy 11.923865 -495.413651) (xy 11.846249 -495.390106)
			(xy 11.771313 -495.359067) (xy 11.699781 -495.320832) (xy 11.632341 -495.27577) (xy 11.569642 -495.224315)
			(xy 11.512289 -495.166962) (xy 11.460834 -495.104263) (xy 11.415772 -495.036823) (xy 11.377537 -494.965291)
			(xy 11.346498 -494.890355) (xy 11.322953 -494.812739) (xy 11.30713 -494.733188) (xy 11.29918 -494.652469)
			(xy 7.8702 -494.652469) (xy 7.86225 -494.733188) (xy 7.846427 -494.812739) (xy 7.822882 -494.890355)
			(xy 7.791843 -494.965291) (xy 7.753608 -495.036823) (xy 7.708546 -495.104263) (xy 7.657091 -495.166962)
			(xy 7.599738 -495.224315) (xy 7.537039 -495.27577) (xy 7.469599 -495.320832) (xy 7.398067 -495.359067)
			(xy 7.323131 -495.390106) (xy 7.245515 -495.413651) (xy 7.165964 -495.429474) (xy 7.085245 -495.437424)
			(xy 7.004135 -495.437424) (xy 6.923416 -495.429474) (xy 6.843865 -495.413651) (xy 6.766249 -495.390106)
			(xy 6.691313 -495.359067) (xy 6.619781 -495.320832) (xy 6.552341 -495.27577) (xy 6.489642 -495.224315)
			(xy 6.432289 -495.166962) (xy 6.380834 -495.104263) (xy 6.335772 -495.036823) (xy 6.297537 -494.965291)
			(xy 6.266498 -494.890355) (xy 6.242953 -494.812739) (xy 6.22713 -494.733188) (xy 6.21918 -494.652469)
			(xy 5.330444 -494.652469) (xy 5.330444 -495.437668) (xy 3.678936 -495.437668) (xy 3.678936 -493.78616)
			(xy 0.509016 -493.78616) (xy 0.509016 -495.831047) (xy 39.818567 -495.831047) (xy 39.824576 -495.715126)
			(xy 39.838567 -495.599897) (xy 39.860475 -495.485907) (xy 39.890195 -495.3737) (xy 39.927585 -495.263811)
			(xy 39.972468 -495.156764) (xy 40.024629 -495.053068) (xy 40.08382 -494.953218) (xy 40.149759 -494.857689)
			(xy 40.222131 -494.766938) (xy 40.300592 -494.681395) (xy 40.384767 -494.601469) (xy 40.474256 -494.527542)
			(xy 40.568632 -494.459964) (xy 40.667446 -494.399058) (xy 40.770226 -494.345115) (xy 40.876483 -494.298391)
			(xy 40.98571 -494.25911) (xy 41.097387 -494.227458) (xy 41.210982 -494.203585) (xy 41.325953 -494.187607)
			(xy 41.441752 -494.179599) (xy 41.49979 -494.179098) (xy 41.557828 -494.179599) (xy 41.673627 -494.187607)
			(xy 41.788598 -494.203585) (xy 41.902193 -494.227458) (xy 42.01387 -494.25911) (xy 42.123097 -494.298391)
			(xy 42.229354 -494.345115) (xy 42.332134 -494.399058) (xy 42.430948 -494.459964) (xy 42.474432 -494.491101)
			(xy 63.647829 -494.491101) (xy 63.653878 -494.415531) (xy 63.667925 -494.341033) (xy 63.689811 -494.26845)
			(xy 63.719288 -494.198604) (xy 63.756023 -494.132287) (xy 63.799598 -494.070251) (xy 63.84952 -494.013198)
			(xy 63.905224 -493.961774) (xy 63.966079 -493.916563) (xy 64.031394 -493.878076) (xy 64.10043 -493.84675)
			(xy 64.172405 -493.82294) (xy 64.246503 -493.806915) (xy 64.321884 -493.798856) (xy 64.35979 -493.798352)
			(xy 64.397696 -493.798856) (xy 64.473077 -493.806915) (xy 64.547175 -493.82294) (xy 64.61915 -493.84675)
			(xy 64.688186 -493.878076) (xy 64.753501 -493.916563) (xy 64.814356 -493.961774) (xy 64.87006 -494.013198)
			(xy 64.919982 -494.070251) (xy 64.963557 -494.132287) (xy 65.000292 -494.198604) (xy 65.029769 -494.26845)
			(xy 65.051655 -494.341033) (xy 65.065702 -494.415531) (xy 65.071751 -494.491101) (xy 66.187829 -494.491101)
			(xy 66.193878 -494.415531) (xy 66.207925 -494.341033) (xy 66.229811 -494.26845) (xy 66.259288 -494.198604)
			(xy 66.296023 -494.132287) (xy 66.339598 -494.070251) (xy 66.38952 -494.013198) (xy 66.445224 -493.961774)
			(xy 66.506079 -493.916563) (xy 66.571394 -493.878076) (xy 66.64043 -493.84675) (xy 66.712405 -493.82294)
			(xy 66.786503 -493.806915) (xy 66.861884 -493.798856) (xy 66.89979 -493.798352) (xy 66.937696 -493.798856)
			(xy 67.013077 -493.806915) (xy 67.087175 -493.82294) (xy 67.15915 -493.84675) (xy 67.228186 -493.878076)
			(xy 67.293501 -493.916563) (xy 67.354356 -493.961774) (xy 67.41006 -494.013198) (xy 67.459982 -494.070251)
			(xy 67.503557 -494.132287) (xy 67.540292 -494.198604) (xy 67.569769 -494.26845) (xy 67.591655 -494.341033)
			(xy 67.605702 -494.415531) (xy 67.611751 -494.491101) (xy 68.727829 -494.491101) (xy 68.733878 -494.415531)
			(xy 68.747925 -494.341033) (xy 68.769811 -494.26845) (xy 68.799288 -494.198604) (xy 68.836023 -494.132287)
			(xy 68.879598 -494.070251) (xy 68.92952 -494.013198) (xy 68.985224 -493.961774) (xy 69.046079 -493.916563)
			(xy 69.111394 -493.878076) (xy 69.18043 -493.84675) (xy 69.252405 -493.82294) (xy 69.326503 -493.806915)
			(xy 69.401884 -493.798856) (xy 69.43979 -493.798352) (xy 69.477696 -493.798856) (xy 69.553077 -493.806915)
			(xy 69.627175 -493.82294) (xy 69.69915 -493.84675) (xy 69.768186 -493.878076) (xy 69.833501 -493.916563)
			(xy 69.894356 -493.961774) (xy 69.95006 -494.013198) (xy 69.999982 -494.070251) (xy 70.043557 -494.132287)
			(xy 70.080292 -494.198604) (xy 70.109769 -494.26845) (xy 70.131655 -494.341033) (xy 70.145702 -494.415531)
			(xy 70.151751 -494.491101) (xy 71.267829 -494.491101) (xy 71.273878 -494.415531) (xy 71.287925 -494.341033)
			(xy 71.309811 -494.26845) (xy 71.339288 -494.198604) (xy 71.376023 -494.132287) (xy 71.419598 -494.070251)
			(xy 71.46952 -494.013198) (xy 71.525224 -493.961774) (xy 71.586079 -493.916563) (xy 71.651394 -493.878076)
			(xy 71.72043 -493.84675) (xy 71.792405 -493.82294) (xy 71.866503 -493.806915) (xy 71.941884 -493.798856)
			(xy 71.97979 -493.798352) (xy 72.017696 -493.798856) (xy 72.093077 -493.806915) (xy 72.167175 -493.82294)
			(xy 72.23915 -493.84675) (xy 72.308186 -493.878076) (xy 72.373501 -493.916563) (xy 72.434356 -493.961774)
			(xy 72.49006 -494.013198) (xy 72.539982 -494.070251) (xy 72.583557 -494.132287) (xy 72.620292 -494.198604)
			(xy 72.649769 -494.26845) (xy 72.671655 -494.341033) (xy 72.685702 -494.415531) (xy 72.691751 -494.491101)
			(xy 73.807829 -494.491101) (xy 73.813878 -494.415531) (xy 73.827925 -494.341033) (xy 73.849811 -494.26845)
			(xy 73.879288 -494.198604) (xy 73.916023 -494.132287) (xy 73.959598 -494.070251) (xy 74.00952 -494.013198)
			(xy 74.065224 -493.961774) (xy 74.126079 -493.916563) (xy 74.191394 -493.878076) (xy 74.26043 -493.84675)
			(xy 74.332405 -493.82294) (xy 74.406503 -493.806915) (xy 74.481884 -493.798856) (xy 74.51979 -493.798352)
			(xy 74.557696 -493.798856) (xy 74.633077 -493.806915) (xy 74.707175 -493.82294) (xy 74.77915 -493.84675)
			(xy 74.848186 -493.878076) (xy 74.913501 -493.916563) (xy 74.974356 -493.961774) (xy 75.03006 -494.013198)
			(xy 75.079982 -494.070251) (xy 75.123557 -494.132287) (xy 75.160292 -494.198604) (xy 75.189769 -494.26845)
			(xy 75.211655 -494.341033) (xy 75.225702 -494.415531) (xy 75.231751 -494.491101) (xy 76.347829 -494.491101)
			(xy 76.353878 -494.415531) (xy 76.367925 -494.341033) (xy 76.389811 -494.26845) (xy 76.419288 -494.198604)
			(xy 76.456023 -494.132287) (xy 76.499598 -494.070251) (xy 76.54952 -494.013198) (xy 76.605224 -493.961774)
			(xy 76.666079 -493.916563) (xy 76.731394 -493.878076) (xy 76.80043 -493.84675) (xy 76.872405 -493.82294)
			(xy 76.946503 -493.806915) (xy 77.021884 -493.798856) (xy 77.05979 -493.798352) (xy 77.097696 -493.798856)
			(xy 77.173077 -493.806915) (xy 77.247175 -493.82294) (xy 77.31915 -493.84675) (xy 77.388186 -493.878076)
			(xy 77.453501 -493.916563) (xy 77.514356 -493.961774) (xy 77.57006 -494.013198) (xy 77.619982 -494.070251)
			(xy 77.663557 -494.132287) (xy 77.700292 -494.198604) (xy 77.729769 -494.26845) (xy 77.751655 -494.341033)
			(xy 77.765702 -494.415531) (xy 77.771751 -494.491101) (xy 78.887829 -494.491101) (xy 78.893878 -494.415531)
			(xy 78.907925 -494.341033) (xy 78.929811 -494.26845) (xy 78.959288 -494.198604) (xy 78.996023 -494.132287)
			(xy 79.039598 -494.070251) (xy 79.08952 -494.013198) (xy 79.145224 -493.961774) (xy 79.206079 -493.916563)
			(xy 79.271394 -493.878076) (xy 79.34043 -493.84675) (xy 79.412405 -493.82294) (xy 79.486503 -493.806915)
			(xy 79.561884 -493.798856) (xy 79.59979 -493.798352) (xy 79.637696 -493.798856) (xy 79.713077 -493.806915)
			(xy 79.787175 -493.82294) (xy 79.85915 -493.84675) (xy 79.928186 -493.878076) (xy 79.993501 -493.916563)
			(xy 80.054356 -493.961774) (xy 80.11006 -494.013198) (xy 80.159982 -494.070251) (xy 80.203557 -494.132287)
			(xy 80.240292 -494.198604) (xy 80.269769 -494.26845) (xy 80.291655 -494.341033) (xy 80.305702 -494.415531)
			(xy 80.311751 -494.491101) (xy 81.427829 -494.491101) (xy 81.433878 -494.415531) (xy 81.447925 -494.341033)
			(xy 81.469811 -494.26845) (xy 81.499288 -494.198604) (xy 81.536023 -494.132287) (xy 81.579598 -494.070251)
			(xy 81.62952 -494.013198) (xy 81.685224 -493.961774) (xy 81.746079 -493.916563) (xy 81.811394 -493.878076)
			(xy 81.88043 -493.84675) (xy 81.952405 -493.82294) (xy 82.026503 -493.806915) (xy 82.101884 -493.798856)
			(xy 82.13979 -493.798352) (xy 82.177696 -493.798856) (xy 82.253077 -493.806915) (xy 82.327175 -493.82294)
			(xy 82.39915 -493.84675) (xy 82.468186 -493.878076) (xy 82.533501 -493.916563) (xy 82.559813 -493.936111)
			(xy 86.197949 -493.936111) (xy 86.203998 -493.860541) (xy 86.218045 -493.786043) (xy 86.239931 -493.71346)
			(xy 86.269408 -493.643614) (xy 86.306143 -493.577297) (xy 86.349718 -493.515261) (xy 86.39964 -493.458208)
			(xy 86.455344 -493.406784) (xy 86.516199 -493.361573) (xy 86.581514 -493.323086) (xy 86.65055 -493.29176)
			(xy 86.722525 -493.26795) (xy 86.796623 -493.251925) (xy 86.872004 -493.243866) (xy 86.90991 -493.243362)
			(xy 86.947816 -493.243866) (xy 87.023197 -493.251925) (xy 87.097295 -493.26795) (xy 87.16927 -493.29176)
			(xy 87.238306 -493.323086) (xy 87.303621 -493.361573) (xy 87.364476 -493.406784) (xy 87.42018 -493.458208)
			(xy 87.470102 -493.515261) (xy 87.513677 -493.577297) (xy 87.550412 -493.643614) (xy 87.579889 -493.71346)
			(xy 87.601775 -493.786043) (xy 87.615822 -493.860541) (xy 87.621871 -493.936111) (xy 88.737949 -493.936111)
			(xy 88.743998 -493.860541) (xy 88.758045 -493.786043) (xy 88.779931 -493.71346) (xy 88.809408 -493.643614)
			(xy 88.846143 -493.577297) (xy 88.889718 -493.515261) (xy 88.93964 -493.458208) (xy 88.995344 -493.406784)
			(xy 89.056199 -493.361573) (xy 89.121514 -493.323086) (xy 89.19055 -493.29176) (xy 89.262525 -493.26795)
			(xy 89.336623 -493.251925) (xy 89.412004 -493.243866) (xy 89.44991 -493.243362) (xy 89.487816 -493.243866)
			(xy 89.563197 -493.251925) (xy 89.637295 -493.26795) (xy 89.70927 -493.29176) (xy 89.778306 -493.323086)
			(xy 89.843621 -493.361573) (xy 89.904476 -493.406784) (xy 89.96018 -493.458208) (xy 90.010102 -493.515261)
			(xy 90.053677 -493.577297) (xy 90.090412 -493.643614) (xy 90.119889 -493.71346) (xy 90.141775 -493.786043)
			(xy 90.155822 -493.860541) (xy 90.161871 -493.936111) (xy 91.277949 -493.936111) (xy 91.283998 -493.860541)
			(xy 91.298045 -493.786043) (xy 91.319931 -493.71346) (xy 91.349408 -493.643614) (xy 91.386143 -493.577297)
			(xy 91.429718 -493.515261) (xy 91.47964 -493.458208) (xy 91.535344 -493.406784) (xy 91.596199 -493.361573)
			(xy 91.661514 -493.323086) (xy 91.73055 -493.29176) (xy 91.802525 -493.26795) (xy 91.876623 -493.251925)
			(xy 91.952004 -493.243866) (xy 91.98991 -493.243362) (xy 92.027816 -493.243866) (xy 92.103197 -493.251925)
			(xy 92.177295 -493.26795) (xy 92.24927 -493.29176) (xy 92.318306 -493.323086) (xy 92.383621 -493.361573)
			(xy 92.444476 -493.406784) (xy 92.50018 -493.458208) (xy 92.550102 -493.515261) (xy 92.593677 -493.577297)
			(xy 92.630412 -493.643614) (xy 92.659889 -493.71346) (xy 92.681775 -493.786043) (xy 92.695822 -493.860541)
			(xy 92.701871 -493.936111) (xy 92.699852 -494.011895) (xy 92.68979 -494.087035) (xy 92.671798 -494.16068)
			(xy 92.64608 -494.231996) (xy 92.612928 -494.300173) (xy 92.572716 -494.364441) (xy 92.525901 -494.42407)
			(xy 92.473013 -494.478386) (xy 92.414651 -494.526772) (xy 92.351476 -494.56868) (xy 92.284205 -494.603636)
			(xy 92.2136 -494.631243) (xy 92.140459 -494.651189) (xy 92.065614 -494.663248) (xy 91.98991 -494.667283)
			(xy 91.914206 -494.663248) (xy 91.839361 -494.651189) (xy 91.76622 -494.631243) (xy 91.695615 -494.603636)
			(xy 91.628344 -494.56868) (xy 91.565169 -494.526772) (xy 91.506807 -494.478386) (xy 91.453919 -494.42407)
			(xy 91.407104 -494.364441) (xy 91.366892 -494.300173) (xy 91.33374 -494.231996) (xy 91.308022 -494.16068)
			(xy 91.29003 -494.087035) (xy 91.279968 -494.011895) (xy 91.277949 -493.936111) (xy 90.161871 -493.936111)
			(xy 90.159852 -494.011895) (xy 90.14979 -494.087035) (xy 90.131798 -494.16068) (xy 90.10608 -494.231996)
			(xy 90.072928 -494.300173) (xy 90.032716 -494.364441) (xy 89.985901 -494.42407) (xy 89.933013 -494.478386)
			(xy 89.874651 -494.526772) (xy 89.811476 -494.56868) (xy 89.744205 -494.603636) (xy 89.6736 -494.631243)
			(xy 89.600459 -494.651189) (xy 89.525614 -494.663248) (xy 89.44991 -494.667283) (xy 89.374206 -494.663248)
			(xy 89.299361 -494.651189) (xy 89.22622 -494.631243) (xy 89.155615 -494.603636) (xy 89.088344 -494.56868)
			(xy 89.025169 -494.526772) (xy 88.966807 -494.478386) (xy 88.913919 -494.42407) (xy 88.867104 -494.364441)
			(xy 88.826892 -494.300173) (xy 88.79374 -494.231996) (xy 88.768022 -494.16068) (xy 88.75003 -494.087035)
			(xy 88.739968 -494.011895) (xy 88.737949 -493.936111) (xy 87.621871 -493.936111) (xy 87.619852 -494.011895)
			(xy 87.60979 -494.087035) (xy 87.591798 -494.16068) (xy 87.56608 -494.231996) (xy 87.532928 -494.300173)
			(xy 87.492716 -494.364441) (xy 87.445901 -494.42407) (xy 87.393013 -494.478386) (xy 87.334651 -494.526772)
			(xy 87.271476 -494.56868) (xy 87.204205 -494.603636) (xy 87.1336 -494.631243) (xy 87.060459 -494.651189)
			(xy 86.985614 -494.663248) (xy 86.90991 -494.667283) (xy 86.834206 -494.663248) (xy 86.759361 -494.651189)
			(xy 86.68622 -494.631243) (xy 86.615615 -494.603636) (xy 86.548344 -494.56868) (xy 86.485169 -494.526772)
			(xy 86.426807 -494.478386) (xy 86.373919 -494.42407) (xy 86.327104 -494.364441) (xy 86.286892 -494.300173)
			(xy 86.25374 -494.231996) (xy 86.228022 -494.16068) (xy 86.21003 -494.087035) (xy 86.199968 -494.011895)
			(xy 86.197949 -493.936111) (xy 82.559813 -493.936111) (xy 82.594356 -493.961774) (xy 82.65006 -494.013198)
			(xy 82.699982 -494.070251) (xy 82.743557 -494.132287) (xy 82.780292 -494.198604) (xy 82.809769 -494.26845)
			(xy 82.831655 -494.341033) (xy 82.845702 -494.415531) (xy 82.851751 -494.491101) (xy 82.849732 -494.566885)
			(xy 82.83967 -494.642025) (xy 82.821678 -494.71567) (xy 82.79596 -494.786986) (xy 82.762808 -494.855163)
			(xy 82.722596 -494.919431) (xy 82.675781 -494.97906) (xy 82.622893 -495.033376) (xy 82.564531 -495.081762)
			(xy 82.501356 -495.12367) (xy 82.434085 -495.158626) (xy 82.36348 -495.186233) (xy 82.290588 -495.206111)
			(xy 84.927949 -495.206111) (xy 84.933998 -495.130541) (xy 84.948045 -495.056043) (xy 84.969931 -494.98346)
			(xy 84.999408 -494.913614) (xy 85.036143 -494.847297) (xy 85.079718 -494.785261) (xy 85.12964 -494.728208)
			(xy 85.185344 -494.676784) (xy 85.246199 -494.631573) (xy 85.311514 -494.593086) (xy 85.38055 -494.56176)
			(xy 85.452525 -494.53795) (xy 85.526623 -494.521925) (xy 85.602004 -494.513866) (xy 85.63991 -494.513362)
			(xy 85.677816 -494.513866) (xy 85.753197 -494.521925) (xy 85.827295 -494.53795) (xy 85.89927 -494.56176)
			(xy 85.968306 -494.593086) (xy 86.033621 -494.631573) (xy 86.094476 -494.676784) (xy 86.15018 -494.728208)
			(xy 86.200102 -494.785261) (xy 86.243677 -494.847297) (xy 86.280412 -494.913614) (xy 86.309889 -494.98346)
			(xy 86.331775 -495.056043) (xy 86.345822 -495.130541) (xy 86.351871 -495.206111) (xy 87.467949 -495.206111)
			(xy 87.473998 -495.130541) (xy 87.488045 -495.056043) (xy 87.509931 -494.98346) (xy 87.539408 -494.913614)
			(xy 87.576143 -494.847297) (xy 87.619718 -494.785261) (xy 87.66964 -494.728208) (xy 87.725344 -494.676784)
			(xy 87.786199 -494.631573) (xy 87.851514 -494.593086) (xy 87.92055 -494.56176) (xy 87.992525 -494.53795)
			(xy 88.066623 -494.521925) (xy 88.142004 -494.513866) (xy 88.17991 -494.513362) (xy 88.217816 -494.513866)
			(xy 88.293197 -494.521925) (xy 88.367295 -494.53795) (xy 88.43927 -494.56176) (xy 88.508306 -494.593086)
			(xy 88.573621 -494.631573) (xy 88.634476 -494.676784) (xy 88.69018 -494.728208) (xy 88.740102 -494.785261)
			(xy 88.783677 -494.847297) (xy 88.820412 -494.913614) (xy 88.849889 -494.98346) (xy 88.871775 -495.056043)
			(xy 88.885822 -495.130541) (xy 88.891871 -495.206111) (xy 90.007949 -495.206111) (xy 90.013998 -495.130541)
			(xy 90.028045 -495.056043) (xy 90.049931 -494.98346) (xy 90.079408 -494.913614) (xy 90.116143 -494.847297)
			(xy 90.159718 -494.785261) (xy 90.20964 -494.728208) (xy 90.265344 -494.676784) (xy 90.326199 -494.631573)
			(xy 90.391514 -494.593086) (xy 90.46055 -494.56176) (xy 90.532525 -494.53795) (xy 90.606623 -494.521925)
			(xy 90.682004 -494.513866) (xy 90.71991 -494.513362) (xy 90.757816 -494.513866) (xy 90.833197 -494.521925)
			(xy 90.907295 -494.53795) (xy 90.97927 -494.56176) (xy 91.048306 -494.593086) (xy 91.113621 -494.631573)
			(xy 91.174476 -494.676784) (xy 91.23018 -494.728208) (xy 91.280102 -494.785261) (xy 91.323677 -494.847297)
			(xy 91.360412 -494.913614) (xy 91.389889 -494.98346) (xy 91.411775 -495.056043) (xy 91.425822 -495.130541)
			(xy 91.431871 -495.206111) (xy 91.429852 -495.281895) (xy 91.41979 -495.357035) (xy 91.401798 -495.43068)
			(xy 91.37608 -495.501996) (xy 91.342928 -495.570173) (xy 91.302716 -495.634441) (xy 91.255901 -495.69407)
			(xy 91.203013 -495.748386) (xy 91.144651 -495.796772) (xy 91.081476 -495.83868) (xy 91.014205 -495.873636)
			(xy 90.9436 -495.901243) (xy 90.870459 -495.921189) (xy 90.795614 -495.933248) (xy 90.71991 -495.937283)
			(xy 90.644206 -495.933248) (xy 90.569361 -495.921189) (xy 90.49622 -495.901243) (xy 90.425615 -495.873636)
			(xy 90.358344 -495.83868) (xy 90.295169 -495.796772) (xy 90.236807 -495.748386) (xy 90.183919 -495.69407)
			(xy 90.137104 -495.634441) (xy 90.096892 -495.570173) (xy 90.06374 -495.501996) (xy 90.038022 -495.43068)
			(xy 90.02003 -495.357035) (xy 90.009968 -495.281895) (xy 90.007949 -495.206111) (xy 88.891871 -495.206111)
			(xy 88.889852 -495.281895) (xy 88.87979 -495.357035) (xy 88.861798 -495.43068) (xy 88.83608 -495.501996)
			(xy 88.802928 -495.570173) (xy 88.762716 -495.634441) (xy 88.715901 -495.69407) (xy 88.663013 -495.748386)
			(xy 88.604651 -495.796772) (xy 88.541476 -495.83868) (xy 88.474205 -495.873636) (xy 88.4036 -495.901243)
			(xy 88.330459 -495.921189) (xy 88.255614 -495.933248) (xy 88.17991 -495.937283) (xy 88.104206 -495.933248)
			(xy 88.029361 -495.921189) (xy 87.95622 -495.901243) (xy 87.885615 -495.873636) (xy 87.818344 -495.83868)
			(xy 87.755169 -495.796772) (xy 87.696807 -495.748386) (xy 87.643919 -495.69407) (xy 87.597104 -495.634441)
			(xy 87.556892 -495.570173) (xy 87.52374 -495.501996) (xy 87.498022 -495.43068) (xy 87.48003 -495.357035)
			(xy 87.469968 -495.281895) (xy 87.467949 -495.206111) (xy 86.351871 -495.206111) (xy 86.349852 -495.281895)
			(xy 86.33979 -495.357035) (xy 86.321798 -495.43068) (xy 86.29608 -495.501996) (xy 86.262928 -495.570173)
			(xy 86.222716 -495.634441) (xy 86.175901 -495.69407) (xy 86.123013 -495.748386) (xy 86.064651 -495.796772)
			(xy 86.001476 -495.83868) (xy 85.934205 -495.873636) (xy 85.8636 -495.901243) (xy 85.790459 -495.921189)
			(xy 85.715614 -495.933248) (xy 85.63991 -495.937283) (xy 85.564206 -495.933248) (xy 85.489361 -495.921189)
			(xy 85.41622 -495.901243) (xy 85.345615 -495.873636) (xy 85.278344 -495.83868) (xy 85.215169 -495.796772)
			(xy 85.156807 -495.748386) (xy 85.103919 -495.69407) (xy 85.057104 -495.634441) (xy 85.016892 -495.570173)
			(xy 84.98374 -495.501996) (xy 84.958022 -495.43068) (xy 84.94003 -495.357035) (xy 84.929968 -495.281895)
			(xy 84.927949 -495.206111) (xy 82.290588 -495.206111) (xy 82.290339 -495.206179) (xy 82.215494 -495.218238)
			(xy 82.13979 -495.222273) (xy 82.064086 -495.218238) (xy 81.989241 -495.206179) (xy 81.9161 -495.186233)
			(xy 81.845495 -495.158626) (xy 81.778224 -495.12367) (xy 81.715049 -495.081762) (xy 81.656687 -495.033376)
			(xy 81.603799 -494.97906) (xy 81.556984 -494.919431) (xy 81.516772 -494.855163) (xy 81.48362 -494.786986)
			(xy 81.457902 -494.71567) (xy 81.43991 -494.642025) (xy 81.429848 -494.566885) (xy 81.427829 -494.491101)
			(xy 80.311751 -494.491101) (xy 80.309732 -494.566885) (xy 80.29967 -494.642025) (xy 80.281678 -494.71567)
			(xy 80.25596 -494.786986) (xy 80.222808 -494.855163) (xy 80.182596 -494.919431) (xy 80.135781 -494.97906)
			(xy 80.082893 -495.033376) (xy 80.024531 -495.081762) (xy 79.961356 -495.12367) (xy 79.894085 -495.158626)
			(xy 79.82348 -495.186233) (xy 79.750339 -495.206179) (xy 79.675494 -495.218238) (xy 79.59979 -495.222273)
			(xy 79.524086 -495.218238) (xy 79.449241 -495.206179) (xy 79.3761 -495.186233) (xy 79.305495 -495.158626)
			(xy 79.238224 -495.12367) (xy 79.175049 -495.081762) (xy 79.116687 -495.033376) (xy 79.063799 -494.97906)
			(xy 79.016984 -494.919431) (xy 78.976772 -494.855163) (xy 78.94362 -494.786986) (xy 78.917902 -494.71567)
			(xy 78.89991 -494.642025) (xy 78.889848 -494.566885) (xy 78.887829 -494.491101) (xy 77.771751 -494.491101)
			(xy 77.769732 -494.566885) (xy 77.75967 -494.642025) (xy 77.741678 -494.71567) (xy 77.71596 -494.786986)
			(xy 77.682808 -494.855163) (xy 77.642596 -494.919431) (xy 77.595781 -494.97906) (xy 77.542893 -495.033376)
			(xy 77.484531 -495.081762) (xy 77.421356 -495.12367) (xy 77.354085 -495.158626) (xy 77.28348 -495.186233)
			(xy 77.210339 -495.206179) (xy 77.135494 -495.218238) (xy 77.05979 -495.222273) (xy 76.984086 -495.218238)
			(xy 76.909241 -495.206179) (xy 76.8361 -495.186233) (xy 76.765495 -495.158626) (xy 76.698224 -495.12367)
			(xy 76.635049 -495.081762) (xy 76.576687 -495.033376) (xy 76.523799 -494.97906) (xy 76.476984 -494.919431)
			(xy 76.436772 -494.855163) (xy 76.40362 -494.786986) (xy 76.377902 -494.71567) (xy 76.35991 -494.642025)
			(xy 76.349848 -494.566885) (xy 76.347829 -494.491101) (xy 75.231751 -494.491101) (xy 75.229732 -494.566885)
			(xy 75.21967 -494.642025) (xy 75.201678 -494.71567) (xy 75.17596 -494.786986) (xy 75.142808 -494.855163)
			(xy 75.102596 -494.919431) (xy 75.055781 -494.97906) (xy 75.002893 -495.033376) (xy 74.944531 -495.081762)
			(xy 74.881356 -495.12367) (xy 74.814085 -495.158626) (xy 74.74348 -495.186233) (xy 74.670339 -495.206179)
			(xy 74.595494 -495.218238) (xy 74.51979 -495.222273) (xy 74.444086 -495.218238) (xy 74.369241 -495.206179)
			(xy 74.2961 -495.186233) (xy 74.225495 -495.158626) (xy 74.158224 -495.12367) (xy 74.095049 -495.081762)
			(xy 74.036687 -495.033376) (xy 73.983799 -494.97906) (xy 73.936984 -494.919431) (xy 73.896772 -494.855163)
			(xy 73.86362 -494.786986) (xy 73.837902 -494.71567) (xy 73.81991 -494.642025) (xy 73.809848 -494.566885)
			(xy 73.807829 -494.491101) (xy 72.691751 -494.491101) (xy 72.689732 -494.566885) (xy 72.67967 -494.642025)
			(xy 72.661678 -494.71567) (xy 72.63596 -494.786986) (xy 72.602808 -494.855163) (xy 72.562596 -494.919431)
			(xy 72.515781 -494.97906) (xy 72.462893 -495.033376) (xy 72.404531 -495.081762) (xy 72.341356 -495.12367)
			(xy 72.274085 -495.158626) (xy 72.20348 -495.186233) (xy 72.130339 -495.206179) (xy 72.055494 -495.218238)
			(xy 71.97979 -495.222273) (xy 71.904086 -495.218238) (xy 71.829241 -495.206179) (xy 71.7561 -495.186233)
			(xy 71.685495 -495.158626) (xy 71.618224 -495.12367) (xy 71.555049 -495.081762) (xy 71.496687 -495.033376)
			(xy 71.443799 -494.97906) (xy 71.396984 -494.919431) (xy 71.356772 -494.855163) (xy 71.32362 -494.786986)
			(xy 71.297902 -494.71567) (xy 71.27991 -494.642025) (xy 71.269848 -494.566885) (xy 71.267829 -494.491101)
			(xy 70.151751 -494.491101) (xy 70.149732 -494.566885) (xy 70.13967 -494.642025) (xy 70.121678 -494.71567)
			(xy 70.09596 -494.786986) (xy 70.062808 -494.855163) (xy 70.022596 -494.919431) (xy 69.975781 -494.97906)
			(xy 69.922893 -495.033376) (xy 69.864531 -495.081762) (xy 69.801356 -495.12367) (xy 69.734085 -495.158626)
			(xy 69.66348 -495.186233) (xy 69.590339 -495.206179) (xy 69.515494 -495.218238) (xy 69.43979 -495.222273)
			(xy 69.364086 -495.218238) (xy 69.289241 -495.206179) (xy 69.2161 -495.186233) (xy 69.145495 -495.158626)
			(xy 69.078224 -495.12367) (xy 69.015049 -495.081762) (xy 68.956687 -495.033376) (xy 68.903799 -494.97906)
			(xy 68.856984 -494.919431) (xy 68.816772 -494.855163) (xy 68.78362 -494.786986) (xy 68.757902 -494.71567)
			(xy 68.73991 -494.642025) (xy 68.729848 -494.566885) (xy 68.727829 -494.491101) (xy 67.611751 -494.491101)
			(xy 67.609732 -494.566885) (xy 67.59967 -494.642025) (xy 67.581678 -494.71567) (xy 67.55596 -494.786986)
			(xy 67.522808 -494.855163) (xy 67.482596 -494.919431) (xy 67.435781 -494.97906) (xy 67.382893 -495.033376)
			(xy 67.324531 -495.081762) (xy 67.261356 -495.12367) (xy 67.194085 -495.158626) (xy 67.12348 -495.186233)
			(xy 67.050339 -495.206179) (xy 66.975494 -495.218238) (xy 66.89979 -495.222273) (xy 66.824086 -495.218238)
			(xy 66.749241 -495.206179) (xy 66.6761 -495.186233) (xy 66.605495 -495.158626) (xy 66.538224 -495.12367)
			(xy 66.475049 -495.081762) (xy 66.416687 -495.033376) (xy 66.363799 -494.97906) (xy 66.316984 -494.919431)
			(xy 66.276772 -494.855163) (xy 66.24362 -494.786986) (xy 66.217902 -494.71567) (xy 66.19991 -494.642025)
			(xy 66.189848 -494.566885) (xy 66.187829 -494.491101) (xy 65.071751 -494.491101) (xy 65.069732 -494.566885)
			(xy 65.05967 -494.642025) (xy 65.041678 -494.71567) (xy 65.01596 -494.786986) (xy 64.982808 -494.855163)
			(xy 64.942596 -494.919431) (xy 64.895781 -494.97906) (xy 64.842893 -495.033376) (xy 64.784531 -495.081762)
			(xy 64.721356 -495.12367) (xy 64.654085 -495.158626) (xy 64.58348 -495.186233) (xy 64.510339 -495.206179)
			(xy 64.435494 -495.218238) (xy 64.35979 -495.222273) (xy 64.284086 -495.218238) (xy 64.209241 -495.206179)
			(xy 64.1361 -495.186233) (xy 64.065495 -495.158626) (xy 63.998224 -495.12367) (xy 63.935049 -495.081762)
			(xy 63.876687 -495.033376) (xy 63.823799 -494.97906) (xy 63.776984 -494.919431) (xy 63.736772 -494.855163)
			(xy 63.70362 -494.786986) (xy 63.677902 -494.71567) (xy 63.65991 -494.642025) (xy 63.649848 -494.566885)
			(xy 63.647829 -494.491101) (xy 42.474432 -494.491101) (xy 42.525324 -494.527542) (xy 42.614813 -494.601469)
			(xy 42.698988 -494.681395) (xy 42.777449 -494.766938) (xy 42.849821 -494.857689) (xy 42.91576 -494.953218)
			(xy 42.974951 -495.053068) (xy 43.027112 -495.156764) (xy 43.071995 -495.263811) (xy 43.109385 -495.3737)
			(xy 43.139105 -495.485907) (xy 43.161013 -495.599897) (xy 43.175004 -495.715126) (xy 43.181013 -495.831047)
			(xy 43.179009 -495.947105) (xy 43.169003 -496.062749) (xy 43.151043 -496.177427) (xy 43.125213 -496.290593)
			(xy 43.091638 -496.401707) (xy 43.06342 -496.476111) (xy 86.197949 -496.476111) (xy 86.203998 -496.400541)
			(xy 86.218045 -496.326043) (xy 86.239931 -496.25346) (xy 86.269408 -496.183614) (xy 86.306143 -496.117297)
			(xy 86.349718 -496.055261) (xy 86.39964 -495.998208) (xy 86.455344 -495.946784) (xy 86.516199 -495.901573)
			(xy 86.581514 -495.863086) (xy 86.65055 -495.83176) (xy 86.722525 -495.80795) (xy 86.796623 -495.791925)
			(xy 86.872004 -495.783866) (xy 86.90991 -495.783362) (xy 86.947816 -495.783866) (xy 87.023197 -495.791925)
			(xy 87.097295 -495.80795) (xy 87.16927 -495.83176) (xy 87.238306 -495.863086) (xy 87.303621 -495.901573)
			(xy 87.364476 -495.946784) (xy 87.42018 -495.998208) (xy 87.470102 -496.055261) (xy 87.513677 -496.117297)
			(xy 87.550412 -496.183614) (xy 87.579889 -496.25346) (xy 87.601775 -496.326043) (xy 87.615822 -496.400541)
			(xy 87.621871 -496.476111) (xy 88.737949 -496.476111) (xy 88.743998 -496.400541) (xy 88.758045 -496.326043)
			(xy 88.779931 -496.25346) (xy 88.809408 -496.183614) (xy 88.846143 -496.117297) (xy 88.889718 -496.055261)
			(xy 88.93964 -495.998208) (xy 88.995344 -495.946784) (xy 89.056199 -495.901573) (xy 89.121514 -495.863086)
			(xy 89.19055 -495.83176) (xy 89.262525 -495.80795) (xy 89.336623 -495.791925) (xy 89.412004 -495.783866)
			(xy 89.44991 -495.783362) (xy 89.487816 -495.783866) (xy 89.563197 -495.791925) (xy 89.637295 -495.80795)
			(xy 89.70927 -495.83176) (xy 89.778306 -495.863086) (xy 89.843621 -495.901573) (xy 89.904476 -495.946784)
			(xy 89.96018 -495.998208) (xy 90.010102 -496.055261) (xy 90.053677 -496.117297) (xy 90.090412 -496.183614)
			(xy 90.119889 -496.25346) (xy 90.141775 -496.326043) (xy 90.155822 -496.400541) (xy 90.161871 -496.476111)
			(xy 91.277949 -496.476111) (xy 91.283998 -496.400541) (xy 91.298045 -496.326043) (xy 91.319931 -496.25346)
			(xy 91.349408 -496.183614) (xy 91.386143 -496.117297) (xy 91.429718 -496.055261) (xy 91.47964 -495.998208)
			(xy 91.535344 -495.946784) (xy 91.596199 -495.901573) (xy 91.661514 -495.863086) (xy 91.73055 -495.83176)
			(xy 91.802525 -495.80795) (xy 91.876623 -495.791925) (xy 91.952004 -495.783866) (xy 91.98991 -495.783362)
			(xy 92.027816 -495.783866) (xy 92.103197 -495.791925) (xy 92.177295 -495.80795) (xy 92.24927 -495.83176)
			(xy 92.318306 -495.863086) (xy 92.383621 -495.901573) (xy 92.444476 -495.946784) (xy 92.50018 -495.998208)
			(xy 92.550102 -496.055261) (xy 92.593677 -496.117297) (xy 92.630412 -496.183614) (xy 92.659889 -496.25346)
			(xy 92.681775 -496.326043) (xy 92.695822 -496.400541) (xy 92.701871 -496.476111) (xy 92.699852 -496.551895)
			(xy 92.68979 -496.627035) (xy 92.671798 -496.70068) (xy 92.64608 -496.771996) (xy 92.612928 -496.840173)
			(xy 92.572716 -496.904441) (xy 92.525901 -496.96407) (xy 92.473013 -497.018386) (xy 92.414651 -497.066772)
			(xy 92.351476 -497.10868) (xy 92.284205 -497.143636) (xy 92.2136 -497.171243) (xy 92.177855 -497.180991)
			(xy 93.154757 -497.180991) (xy 93.160779 -497.064808) (xy 93.174802 -496.949317) (xy 93.19676 -496.835069)
			(xy 93.226547 -496.722608) (xy 93.264022 -496.61247) (xy 93.309007 -496.50518) (xy 93.361286 -496.401249)
			(xy 93.420611 -496.301173) (xy 93.486699 -496.205427) (xy 93.559235 -496.11447) (xy 93.637874 -496.028734)
			(xy 93.72224 -495.948627) (xy 93.811932 -495.874531) (xy 93.906522 -495.806801) (xy 94.00556 -495.745757)
			(xy 94.108573 -495.691692) (xy 94.21507 -495.644862) (xy 94.324545 -495.605491) (xy 94.436475 -495.573767)
			(xy 94.550327 -495.549841) (xy 94.665559 -495.533827) (xy 94.781621 -495.5258) (xy 94.83979 -495.525298)
			(xy 94.897959 -495.5258) (xy 95.014021 -495.533827) (xy 95.129253 -495.549841) (xy 95.243105 -495.573767)
			(xy 95.355035 -495.605491) (xy 95.46451 -495.644862) (xy 95.571007 -495.691692) (xy 95.67402 -495.745757)
			(xy 95.773058 -495.806801) (xy 95.867648 -495.874531) (xy 95.95734 -495.948627) (xy 96.041706 -496.028734)
			(xy 96.120345 -496.11447) (xy 96.192881 -496.205427) (xy 96.258969 -496.301173) (xy 96.318294 -496.401249)
			(xy 96.370573 -496.50518) (xy 96.415558 -496.61247) (xy 96.453033 -496.722608) (xy 96.48282 -496.835069)
			(xy 96.504778 -496.949317) (xy 96.518801 -497.064808) (xy 96.524823 -497.180991) (xy 96.522815 -497.297313)
			(xy 96.512786 -497.413219) (xy 96.494785 -497.528156) (xy 96.468897 -497.641579) (xy 96.435246 -497.752944)
			(xy 96.393992 -497.861723) (xy 96.345331 -497.967397) (xy 96.289495 -498.069461) (xy 96.226752 -498.16743)
			(xy 96.157398 -498.260837) (xy 96.081766 -498.349237) (xy 96.000215 -498.432208) (xy 95.913134 -498.509355)
			(xy 95.820938 -498.58031) (xy 95.724066 -498.644736) (xy 95.622981 -498.702325) (xy 95.518163 -498.752802)
			(xy 95.410112 -498.795928) (xy 95.299344 -498.831497) (xy 95.186385 -498.859339) (xy 95.071775 -498.879321)
			(xy 94.95606 -498.891348) (xy 94.83979 -498.895364) (xy 94.72352 -498.891348) (xy 94.607805 -498.879321)
			(xy 94.493195 -498.859339) (xy 94.380236 -498.831497) (xy 94.269468 -498.795928) (xy 94.161417 -498.752802)
			(xy 94.056599 -498.702325) (xy 93.955514 -498.644736) (xy 93.858642 -498.58031) (xy 93.766446 -498.509355)
			(xy 93.679365 -498.432208) (xy 93.597814 -498.349237) (xy 93.522182 -498.260837) (xy 93.452828 -498.16743)
			(xy 93.390085 -498.069461) (xy 93.334249 -497.967397) (xy 93.285588 -497.861723) (xy 93.244334 -497.752944)
			(xy 93.210683 -497.641579) (xy 93.184795 -497.528156) (xy 93.166794 -497.413219) (xy 93.156765 -497.297313)
			(xy 93.154757 -497.180991) (xy 92.177855 -497.180991) (xy 92.140459 -497.191189) (xy 92.065614 -497.203248)
			(xy 91.98991 -497.207283) (xy 91.914206 -497.203248) (xy 91.839361 -497.191189) (xy 91.76622 -497.171243)
			(xy 91.695615 -497.143636) (xy 91.628344 -497.10868) (xy 91.565169 -497.066772) (xy 91.506807 -497.018386)
			(xy 91.453919 -496.96407) (xy 91.407104 -496.904441) (xy 91.366892 -496.840173) (xy 91.33374 -496.771996)
			(xy 91.308022 -496.70068) (xy 91.29003 -496.627035) (xy 91.279968 -496.551895) (xy 91.277949 -496.476111)
			(xy 90.161871 -496.476111) (xy 90.159852 -496.551895) (xy 90.14979 -496.627035) (xy 90.131798 -496.70068)
			(xy 90.10608 -496.771996) (xy 90.072928 -496.840173) (xy 90.032716 -496.904441) (xy 89.985901 -496.96407)
			(xy 89.933013 -497.018386) (xy 89.874651 -497.066772) (xy 89.811476 -497.10868) (xy 89.744205 -497.143636)
			(xy 89.6736 -497.171243) (xy 89.600459 -497.191189) (xy 89.525614 -497.203248) (xy 89.44991 -497.207283)
			(xy 89.374206 -497.203248) (xy 89.299361 -497.191189) (xy 89.22622 -497.171243) (xy 89.155615 -497.143636)
			(xy 89.088344 -497.10868) (xy 89.025169 -497.066772) (xy 88.966807 -497.018386) (xy 88.913919 -496.96407)
			(xy 88.867104 -496.904441) (xy 88.826892 -496.840173) (xy 88.79374 -496.771996) (xy 88.768022 -496.70068)
			(xy 88.75003 -496.627035) (xy 88.739968 -496.551895) (xy 88.737949 -496.476111) (xy 87.621871 -496.476111)
			(xy 87.619852 -496.551895) (xy 87.60979 -496.627035) (xy 87.591798 -496.70068) (xy 87.56608 -496.771996)
			(xy 87.532928 -496.840173) (xy 87.492716 -496.904441) (xy 87.445901 -496.96407) (xy 87.393013 -497.018386)
			(xy 87.334651 -497.066772) (xy 87.271476 -497.10868) (xy 87.204205 -497.143636) (xy 87.1336 -497.171243)
			(xy 87.060459 -497.191189) (xy 86.985614 -497.203248) (xy 86.90991 -497.207283) (xy 86.834206 -497.203248)
			(xy 86.759361 -497.191189) (xy 86.68622 -497.171243) (xy 86.615615 -497.143636) (xy 86.548344 -497.10868)
			(xy 86.485169 -497.066772) (xy 86.426807 -497.018386) (xy 86.373919 -496.96407) (xy 86.327104 -496.904441)
			(xy 86.286892 -496.840173) (xy 86.25374 -496.771996) (xy 86.228022 -496.70068) (xy 86.21003 -496.627035)
			(xy 86.199968 -496.551895) (xy 86.197949 -496.476111) (xy 43.06342 -496.476111) (xy 43.050477 -496.51024)
			(xy 43.001926 -496.615674) (xy 42.946217 -496.717508) (xy 42.883615 -496.815256) (xy 42.814419 -496.908451)
			(xy 42.738957 -496.996651) (xy 42.65759 -497.079434) (xy 42.570706 -497.156407) (xy 42.525601 -497.191121)
			(xy 63.647829 -497.191121) (xy 63.653878 -497.115551) (xy 63.667925 -497.041053) (xy 63.689811 -496.96847)
			(xy 63.719288 -496.898624) (xy 63.756023 -496.832307) (xy 63.799598 -496.770271) (xy 63.84952 -496.713218)
			(xy 63.905224 -496.661794) (xy 63.966079 -496.616583) (xy 64.031394 -496.578096) (xy 64.10043 -496.54677)
			(xy 64.172405 -496.52296) (xy 64.246503 -496.506935) (xy 64.321884 -496.498876) (xy 64.35979 -496.498372)
			(xy 64.397696 -496.498876) (xy 64.473077 -496.506935) (xy 64.547175 -496.52296) (xy 64.61915 -496.54677)
			(xy 64.688186 -496.578096) (xy 64.753501 -496.616583) (xy 64.814356 -496.661794) (xy 64.87006 -496.713218)
			(xy 64.919982 -496.770271) (xy 64.963557 -496.832307) (xy 65.000292 -496.898624) (xy 65.029769 -496.96847)
			(xy 65.051655 -497.041053) (xy 65.065702 -497.115551) (xy 65.071751 -497.191121) (xy 66.187829 -497.191121)
			(xy 66.193878 -497.115551) (xy 66.207925 -497.041053) (xy 66.229811 -496.96847) (xy 66.259288 -496.898624)
			(xy 66.296023 -496.832307) (xy 66.339598 -496.770271) (xy 66.38952 -496.713218) (xy 66.445224 -496.661794)
			(xy 66.506079 -496.616583) (xy 66.571394 -496.578096) (xy 66.64043 -496.54677) (xy 66.712405 -496.52296)
			(xy 66.786503 -496.506935) (xy 66.861884 -496.498876) (xy 66.89979 -496.498372) (xy 66.937696 -496.498876)
			(xy 67.013077 -496.506935) (xy 67.087175 -496.52296) (xy 67.15915 -496.54677) (xy 67.228186 -496.578096)
			(xy 67.293501 -496.616583) (xy 67.354356 -496.661794) (xy 67.41006 -496.713218) (xy 67.459982 -496.770271)
			(xy 67.503557 -496.832307) (xy 67.540292 -496.898624) (xy 67.569769 -496.96847) (xy 67.591655 -497.041053)
			(xy 67.605702 -497.115551) (xy 67.611751 -497.191121) (xy 68.727829 -497.191121) (xy 68.733878 -497.115551)
			(xy 68.747925 -497.041053) (xy 68.769811 -496.96847) (xy 68.799288 -496.898624) (xy 68.836023 -496.832307)
			(xy 68.879598 -496.770271) (xy 68.92952 -496.713218) (xy 68.985224 -496.661794) (xy 69.046079 -496.616583)
			(xy 69.111394 -496.578096) (xy 69.18043 -496.54677) (xy 69.252405 -496.52296) (xy 69.326503 -496.506935)
			(xy 69.401884 -496.498876) (xy 69.43979 -496.498372) (xy 69.477696 -496.498876) (xy 69.553077 -496.506935)
			(xy 69.627175 -496.52296) (xy 69.69915 -496.54677) (xy 69.768186 -496.578096) (xy 69.833501 -496.616583)
			(xy 69.894356 -496.661794) (xy 69.95006 -496.713218) (xy 69.999982 -496.770271) (xy 70.043557 -496.832307)
			(xy 70.080292 -496.898624) (xy 70.109769 -496.96847) (xy 70.131655 -497.041053) (xy 70.145702 -497.115551)
			(xy 70.151751 -497.191121) (xy 71.267829 -497.191121) (xy 71.273878 -497.115551) (xy 71.287925 -497.041053)
			(xy 71.309811 -496.96847) (xy 71.339288 -496.898624) (xy 71.376023 -496.832307) (xy 71.419598 -496.770271)
			(xy 71.46952 -496.713218) (xy 71.525224 -496.661794) (xy 71.586079 -496.616583) (xy 71.651394 -496.578096)
			(xy 71.72043 -496.54677) (xy 71.792405 -496.52296) (xy 71.866503 -496.506935) (xy 71.941884 -496.498876)
			(xy 71.97979 -496.498372) (xy 72.017696 -496.498876) (xy 72.093077 -496.506935) (xy 72.167175 -496.52296)
			(xy 72.23915 -496.54677) (xy 72.308186 -496.578096) (xy 72.373501 -496.616583) (xy 72.434356 -496.661794)
			(xy 72.49006 -496.713218) (xy 72.539982 -496.770271) (xy 72.583557 -496.832307) (xy 72.620292 -496.898624)
			(xy 72.649769 -496.96847) (xy 72.671655 -497.041053) (xy 72.685702 -497.115551) (xy 72.691751 -497.191121)
			(xy 73.807829 -497.191121) (xy 73.813878 -497.115551) (xy 73.827925 -497.041053) (xy 73.849811 -496.96847)
			(xy 73.879288 -496.898624) (xy 73.916023 -496.832307) (xy 73.959598 -496.770271) (xy 74.00952 -496.713218)
			(xy 74.065224 -496.661794) (xy 74.126079 -496.616583) (xy 74.191394 -496.578096) (xy 74.26043 -496.54677)
			(xy 74.332405 -496.52296) (xy 74.406503 -496.506935) (xy 74.481884 -496.498876) (xy 74.51979 -496.498372)
			(xy 74.557696 -496.498876) (xy 74.633077 -496.506935) (xy 74.707175 -496.52296) (xy 74.77915 -496.54677)
			(xy 74.848186 -496.578096) (xy 74.913501 -496.616583) (xy 74.974356 -496.661794) (xy 75.03006 -496.713218)
			(xy 75.079982 -496.770271) (xy 75.123557 -496.832307) (xy 75.160292 -496.898624) (xy 75.189769 -496.96847)
			(xy 75.211655 -497.041053) (xy 75.225702 -497.115551) (xy 75.231751 -497.191121) (xy 76.347829 -497.191121)
			(xy 76.353878 -497.115551) (xy 76.367925 -497.041053) (xy 76.389811 -496.96847) (xy 76.419288 -496.898624)
			(xy 76.456023 -496.832307) (xy 76.499598 -496.770271) (xy 76.54952 -496.713218) (xy 76.605224 -496.661794)
			(xy 76.666079 -496.616583) (xy 76.731394 -496.578096) (xy 76.80043 -496.54677) (xy 76.872405 -496.52296)
			(xy 76.946503 -496.506935) (xy 77.021884 -496.498876) (xy 77.05979 -496.498372) (xy 77.097696 -496.498876)
			(xy 77.173077 -496.506935) (xy 77.247175 -496.52296) (xy 77.31915 -496.54677) (xy 77.388186 -496.578096)
			(xy 77.453501 -496.616583) (xy 77.514356 -496.661794) (xy 77.57006 -496.713218) (xy 77.619982 -496.770271)
			(xy 77.663557 -496.832307) (xy 77.700292 -496.898624) (xy 77.729769 -496.96847) (xy 77.751655 -497.041053)
			(xy 77.765702 -497.115551) (xy 77.771751 -497.191121) (xy 78.887829 -497.191121) (xy 78.893878 -497.115551)
			(xy 78.907925 -497.041053) (xy 78.929811 -496.96847) (xy 78.959288 -496.898624) (xy 78.996023 -496.832307)
			(xy 79.039598 -496.770271) (xy 79.08952 -496.713218) (xy 79.145224 -496.661794) (xy 79.206079 -496.616583)
			(xy 79.271394 -496.578096) (xy 79.34043 -496.54677) (xy 79.412405 -496.52296) (xy 79.486503 -496.506935)
			(xy 79.561884 -496.498876) (xy 79.59979 -496.498372) (xy 79.637696 -496.498876) (xy 79.713077 -496.506935)
			(xy 79.787175 -496.52296) (xy 79.85915 -496.54677) (xy 79.928186 -496.578096) (xy 79.993501 -496.616583)
			(xy 80.054356 -496.661794) (xy 80.11006 -496.713218) (xy 80.159982 -496.770271) (xy 80.203557 -496.832307)
			(xy 80.240292 -496.898624) (xy 80.269769 -496.96847) (xy 80.291655 -497.041053) (xy 80.305702 -497.115551)
			(xy 80.311751 -497.191121) (xy 81.427829 -497.191121) (xy 81.433878 -497.115551) (xy 81.447925 -497.041053)
			(xy 81.469811 -496.96847) (xy 81.499288 -496.898624) (xy 81.536023 -496.832307) (xy 81.579598 -496.770271)
			(xy 81.62952 -496.713218) (xy 81.685224 -496.661794) (xy 81.746079 -496.616583) (xy 81.811394 -496.578096)
			(xy 81.88043 -496.54677) (xy 81.952405 -496.52296) (xy 82.026503 -496.506935) (xy 82.101884 -496.498876)
			(xy 82.13979 -496.498372) (xy 82.177696 -496.498876) (xy 82.253077 -496.506935) (xy 82.327175 -496.52296)
			(xy 82.39915 -496.54677) (xy 82.468186 -496.578096) (xy 82.533501 -496.616583) (xy 82.594356 -496.661794)
			(xy 82.65006 -496.713218) (xy 82.699982 -496.770271) (xy 82.743557 -496.832307) (xy 82.780292 -496.898624)
			(xy 82.809769 -496.96847) (xy 82.831655 -497.041053) (xy 82.845702 -497.115551) (xy 82.851751 -497.191121)
			(xy 82.849732 -497.266905) (xy 82.83967 -497.342045) (xy 82.821678 -497.41569) (xy 82.79596 -497.487006)
			(xy 82.762808 -497.555183) (xy 82.722596 -497.619451) (xy 82.675781 -497.67908) (xy 82.622893 -497.733396)
			(xy 82.607556 -497.746111) (xy 84.927949 -497.746111) (xy 84.933998 -497.670541) (xy 84.948045 -497.596043)
			(xy 84.969931 -497.52346) (xy 84.999408 -497.453614) (xy 85.036143 -497.387297) (xy 85.079718 -497.325261)
			(xy 85.12964 -497.268208) (xy 85.185344 -497.216784) (xy 85.246199 -497.171573) (xy 85.311514 -497.133086)
			(xy 85.38055 -497.10176) (xy 85.452525 -497.07795) (xy 85.526623 -497.061925) (xy 85.602004 -497.053866)
			(xy 85.63991 -497.053362) (xy 85.677816 -497.053866) (xy 85.753197 -497.061925) (xy 85.827295 -497.07795)
			(xy 85.89927 -497.10176) (xy 85.968306 -497.133086) (xy 86.033621 -497.171573) (xy 86.094476 -497.216784)
			(xy 86.15018 -497.268208) (xy 86.200102 -497.325261) (xy 86.243677 -497.387297) (xy 86.280412 -497.453614)
			(xy 86.309889 -497.52346) (xy 86.331775 -497.596043) (xy 86.345822 -497.670541) (xy 86.351871 -497.746111)
			(xy 87.467949 -497.746111) (xy 87.473998 -497.670541) (xy 87.488045 -497.596043) (xy 87.509931 -497.52346)
			(xy 87.539408 -497.453614) (xy 87.576143 -497.387297) (xy 87.619718 -497.325261) (xy 87.66964 -497.268208)
			(xy 87.725344 -497.216784) (xy 87.786199 -497.171573) (xy 87.851514 -497.133086) (xy 87.92055 -497.10176)
			(xy 87.992525 -497.07795) (xy 88.066623 -497.061925) (xy 88.142004 -497.053866) (xy 88.17991 -497.053362)
			(xy 88.217816 -497.053866) (xy 88.293197 -497.061925) (xy 88.367295 -497.07795) (xy 88.43927 -497.10176)
			(xy 88.508306 -497.133086) (xy 88.573621 -497.171573) (xy 88.634476 -497.216784) (xy 88.69018 -497.268208)
			(xy 88.740102 -497.325261) (xy 88.783677 -497.387297) (xy 88.820412 -497.453614) (xy 88.849889 -497.52346)
			(xy 88.871775 -497.596043) (xy 88.885822 -497.670541) (xy 88.891871 -497.746111) (xy 90.007949 -497.746111)
			(xy 90.013998 -497.670541) (xy 90.028045 -497.596043) (xy 90.049931 -497.52346) (xy 90.079408 -497.453614)
			(xy 90.116143 -497.387297) (xy 90.159718 -497.325261) (xy 90.20964 -497.268208) (xy 90.265344 -497.216784)
			(xy 90.326199 -497.171573) (xy 90.391514 -497.133086) (xy 90.46055 -497.10176) (xy 90.532525 -497.07795)
			(xy 90.606623 -497.061925) (xy 90.682004 -497.053866) (xy 90.71991 -497.053362) (xy 90.757816 -497.053866)
			(xy 90.833197 -497.061925) (xy 90.907295 -497.07795) (xy 90.97927 -497.10176) (xy 91.048306 -497.133086)
			(xy 91.113621 -497.171573) (xy 91.174476 -497.216784) (xy 91.23018 -497.268208) (xy 91.280102 -497.325261)
			(xy 91.323677 -497.387297) (xy 91.360412 -497.453614) (xy 91.389889 -497.52346) (xy 91.411775 -497.596043)
			(xy 91.425822 -497.670541) (xy 91.431871 -497.746111) (xy 91.429852 -497.821895) (xy 91.41979 -497.897035)
			(xy 91.401798 -497.97068) (xy 91.37608 -498.041996) (xy 91.342928 -498.110173) (xy 91.302716 -498.174441)
			(xy 91.255901 -498.23407) (xy 91.203013 -498.288386) (xy 91.144651 -498.336772) (xy 91.081476 -498.37868)
			(xy 91.014205 -498.413636) (xy 90.9436 -498.441243) (xy 90.870459 -498.461189) (xy 90.795614 -498.473248)
			(xy 90.71991 -498.477283) (xy 90.644206 -498.473248) (xy 90.569361 -498.461189) (xy 90.49622 -498.441243)
			(xy 90.425615 -498.413636) (xy 90.358344 -498.37868) (xy 90.295169 -498.336772) (xy 90.236807 -498.288386)
			(xy 90.183919 -498.23407) (xy 90.137104 -498.174441) (xy 90.096892 -498.110173) (xy 90.06374 -498.041996)
			(xy 90.038022 -497.97068) (xy 90.02003 -497.897035) (xy 90.009968 -497.821895) (xy 90.007949 -497.746111)
			(xy 88.891871 -497.746111) (xy 88.889852 -497.821895) (xy 88.87979 -497.897035) (xy 88.861798 -497.97068)
			(xy 88.83608 -498.041996) (xy 88.802928 -498.110173) (xy 88.762716 -498.174441) (xy 88.715901 -498.23407)
			(xy 88.663013 -498.288386) (xy 88.604651 -498.336772) (xy 88.541476 -498.37868) (xy 88.474205 -498.413636)
			(xy 88.4036 -498.441243) (xy 88.330459 -498.461189) (xy 88.255614 -498.473248) (xy 88.17991 -498.477283)
			(xy 88.104206 -498.473248) (xy 88.029361 -498.461189) (xy 87.95622 -498.441243) (xy 87.885615 -498.413636)
			(xy 87.818344 -498.37868) (xy 87.755169 -498.336772) (xy 87.696807 -498.288386) (xy 87.643919 -498.23407)
			(xy 87.597104 -498.174441) (xy 87.556892 -498.110173) (xy 87.52374 -498.041996) (xy 87.498022 -497.97068)
			(xy 87.48003 -497.897035) (xy 87.469968 -497.821895) (xy 87.467949 -497.746111) (xy 86.351871 -497.746111)
			(xy 86.349852 -497.821895) (xy 86.33979 -497.897035) (xy 86.321798 -497.97068) (xy 86.29608 -498.041996)
			(xy 86.262928 -498.110173) (xy 86.222716 -498.174441) (xy 86.175901 -498.23407) (xy 86.123013 -498.288386)
			(xy 86.064651 -498.336772) (xy 86.001476 -498.37868) (xy 85.934205 -498.413636) (xy 85.8636 -498.441243)
			(xy 85.790459 -498.461189) (xy 85.715614 -498.473248) (xy 85.63991 -498.477283) (xy 85.564206 -498.473248)
			(xy 85.489361 -498.461189) (xy 85.41622 -498.441243) (xy 85.345615 -498.413636) (xy 85.278344 -498.37868)
			(xy 85.215169 -498.336772) (xy 85.156807 -498.288386) (xy 85.103919 -498.23407) (xy 85.057104 -498.174441)
			(xy 85.016892 -498.110173) (xy 84.98374 -498.041996) (xy 84.958022 -497.97068) (xy 84.94003 -497.897035)
			(xy 84.929968 -497.821895) (xy 84.927949 -497.746111) (xy 82.607556 -497.746111) (xy 82.564531 -497.781782)
			(xy 82.501356 -497.82369) (xy 82.434085 -497.858646) (xy 82.36348 -497.886253) (xy 82.290339 -497.906199)
			(xy 82.215494 -497.918258) (xy 82.13979 -497.922293) (xy 82.064086 -497.918258) (xy 81.989241 -497.906199)
			(xy 81.9161 -497.886253) (xy 81.845495 -497.858646) (xy 81.778224 -497.82369) (xy 81.715049 -497.781782)
			(xy 81.656687 -497.733396) (xy 81.603799 -497.67908) (xy 81.556984 -497.619451) (xy 81.516772 -497.555183)
			(xy 81.48362 -497.487006) (xy 81.457902 -497.41569) (xy 81.43991 -497.342045) (xy 81.429848 -497.266905)
			(xy 81.427829 -497.191121) (xy 80.311751 -497.191121) (xy 80.309732 -497.266905) (xy 80.29967 -497.342045)
			(xy 80.281678 -497.41569) (xy 80.25596 -497.487006) (xy 80.222808 -497.555183) (xy 80.182596 -497.619451)
			(xy 80.135781 -497.67908) (xy 80.082893 -497.733396) (xy 80.024531 -497.781782) (xy 79.961356 -497.82369)
			(xy 79.894085 -497.858646) (xy 79.82348 -497.886253) (xy 79.750339 -497.906199) (xy 79.675494 -497.918258)
			(xy 79.59979 -497.922293) (xy 79.524086 -497.918258) (xy 79.449241 -497.906199) (xy 79.3761 -497.886253)
			(xy 79.305495 -497.858646) (xy 79.238224 -497.82369) (xy 79.175049 -497.781782) (xy 79.116687 -497.733396)
			(xy 79.063799 -497.67908) (xy 79.016984 -497.619451) (xy 78.976772 -497.555183) (xy 78.94362 -497.487006)
			(xy 78.917902 -497.41569) (xy 78.89991 -497.342045) (xy 78.889848 -497.266905) (xy 78.887829 -497.191121)
			(xy 77.771751 -497.191121) (xy 77.769732 -497.266905) (xy 77.75967 -497.342045) (xy 77.741678 -497.41569)
			(xy 77.71596 -497.487006) (xy 77.682808 -497.555183) (xy 77.642596 -497.619451) (xy 77.595781 -497.67908)
			(xy 77.542893 -497.733396) (xy 77.484531 -497.781782) (xy 77.421356 -497.82369) (xy 77.354085 -497.858646)
			(xy 77.28348 -497.886253) (xy 77.210339 -497.906199) (xy 77.135494 -497.918258) (xy 77.05979 -497.922293)
			(xy 76.984086 -497.918258) (xy 76.909241 -497.906199) (xy 76.8361 -497.886253) (xy 76.765495 -497.858646)
			(xy 76.698224 -497.82369) (xy 76.635049 -497.781782) (xy 76.576687 -497.733396) (xy 76.523799 -497.67908)
			(xy 76.476984 -497.619451) (xy 76.436772 -497.555183) (xy 76.40362 -497.487006) (xy 76.377902 -497.41569)
			(xy 76.35991 -497.342045) (xy 76.349848 -497.266905) (xy 76.347829 -497.191121) (xy 75.231751 -497.191121)
			(xy 75.229732 -497.266905) (xy 75.21967 -497.342045) (xy 75.201678 -497.41569) (xy 75.17596 -497.487006)
			(xy 75.142808 -497.555183) (xy 75.102596 -497.619451) (xy 75.055781 -497.67908) (xy 75.002893 -497.733396)
			(xy 74.944531 -497.781782) (xy 74.881356 -497.82369) (xy 74.814085 -497.858646) (xy 74.74348 -497.886253)
			(xy 74.670339 -497.906199) (xy 74.595494 -497.918258) (xy 74.51979 -497.922293) (xy 74.444086 -497.918258)
			(xy 74.369241 -497.906199) (xy 74.2961 -497.886253) (xy 74.225495 -497.858646) (xy 74.158224 -497.82369)
			(xy 74.095049 -497.781782) (xy 74.036687 -497.733396) (xy 73.983799 -497.67908) (xy 73.936984 -497.619451)
			(xy 73.896772 -497.555183) (xy 73.86362 -497.487006) (xy 73.837902 -497.41569) (xy 73.81991 -497.342045)
			(xy 73.809848 -497.266905) (xy 73.807829 -497.191121) (xy 72.691751 -497.191121) (xy 72.689732 -497.266905)
			(xy 72.67967 -497.342045) (xy 72.661678 -497.41569) (xy 72.63596 -497.487006) (xy 72.602808 -497.555183)
			(xy 72.562596 -497.619451) (xy 72.515781 -497.67908) (xy 72.462893 -497.733396) (xy 72.404531 -497.781782)
			(xy 72.341356 -497.82369) (xy 72.274085 -497.858646) (xy 72.20348 -497.886253) (xy 72.130339 -497.906199)
			(xy 72.055494 -497.918258) (xy 71.97979 -497.922293) (xy 71.904086 -497.918258) (xy 71.829241 -497.906199)
			(xy 71.7561 -497.886253) (xy 71.685495 -497.858646) (xy 71.618224 -497.82369) (xy 71.555049 -497.781782)
			(xy 71.496687 -497.733396) (xy 71.443799 -497.67908) (xy 71.396984 -497.619451) (xy 71.356772 -497.555183)
			(xy 71.32362 -497.487006) (xy 71.297902 -497.41569) (xy 71.27991 -497.342045) (xy 71.269848 -497.266905)
			(xy 71.267829 -497.191121) (xy 70.151751 -497.191121) (xy 70.149732 -497.266905) (xy 70.13967 -497.342045)
			(xy 70.121678 -497.41569) (xy 70.09596 -497.487006) (xy 70.062808 -497.555183) (xy 70.022596 -497.619451)
			(xy 69.975781 -497.67908) (xy 69.922893 -497.733396) (xy 69.864531 -497.781782) (xy 69.801356 -497.82369)
			(xy 69.734085 -497.858646) (xy 69.66348 -497.886253) (xy 69.590339 -497.906199) (xy 69.515494 -497.918258)
			(xy 69.43979 -497.922293) (xy 69.364086 -497.918258) (xy 69.289241 -497.906199) (xy 69.2161 -497.886253)
			(xy 69.145495 -497.858646) (xy 69.078224 -497.82369) (xy 69.015049 -497.781782) (xy 68.956687 -497.733396)
			(xy 68.903799 -497.67908) (xy 68.856984 -497.619451) (xy 68.816772 -497.555183) (xy 68.78362 -497.487006)
			(xy 68.757902 -497.41569) (xy 68.73991 -497.342045) (xy 68.729848 -497.266905) (xy 68.727829 -497.191121)
			(xy 67.611751 -497.191121) (xy 67.609732 -497.266905) (xy 67.59967 -497.342045) (xy 67.581678 -497.41569)
			(xy 67.55596 -497.487006) (xy 67.522808 -497.555183) (xy 67.482596 -497.619451) (xy 67.435781 -497.67908)
			(xy 67.382893 -497.733396) (xy 67.324531 -497.781782) (xy 67.261356 -497.82369) (xy 67.194085 -497.858646)
			(xy 67.12348 -497.886253) (xy 67.050339 -497.906199) (xy 66.975494 -497.918258) (xy 66.89979 -497.922293)
			(xy 66.824086 -497.918258) (xy 66.749241 -497.906199) (xy 66.6761 -497.886253) (xy 66.605495 -497.858646)
			(xy 66.538224 -497.82369) (xy 66.475049 -497.781782) (xy 66.416687 -497.733396) (xy 66.363799 -497.67908)
			(xy 66.316984 -497.619451) (xy 66.276772 -497.555183) (xy 66.24362 -497.487006) (xy 66.217902 -497.41569)
			(xy 66.19991 -497.342045) (xy 66.189848 -497.266905) (xy 66.187829 -497.191121) (xy 65.071751 -497.191121)
			(xy 65.069732 -497.266905) (xy 65.05967 -497.342045) (xy 65.041678 -497.41569) (xy 65.01596 -497.487006)
			(xy 64.982808 -497.555183) (xy 64.942596 -497.619451) (xy 64.895781 -497.67908) (xy 64.842893 -497.733396)
			(xy 64.784531 -497.781782) (xy 64.721356 -497.82369) (xy 64.654085 -497.858646) (xy 64.58348 -497.886253)
			(xy 64.510339 -497.906199) (xy 64.435494 -497.918258) (xy 64.35979 -497.922293) (xy 64.284086 -497.918258)
			(xy 64.209241 -497.906199) (xy 64.1361 -497.886253) (xy 64.065495 -497.858646) (xy 63.998224 -497.82369)
			(xy 63.935049 -497.781782) (xy 63.876687 -497.733396) (xy 63.823799 -497.67908) (xy 63.776984 -497.619451)
			(xy 63.736772 -497.555183) (xy 63.70362 -497.487006) (xy 63.677902 -497.41569) (xy 63.65991 -497.342045)
			(xy 63.649848 -497.266905) (xy 63.647829 -497.191121) (xy 42.525601 -497.191121) (xy 42.478719 -497.227202)
			(xy 42.382066 -497.291482) (xy 42.281209 -497.34894) (xy 42.176629 -497.399304) (xy 42.068822 -497.442332)
			(xy 41.958305 -497.47782) (xy 41.845602 -497.505599) (xy 41.731251 -497.525536) (xy 41.615797 -497.537537)
			(xy 41.49979 -497.541543) (xy 41.383783 -497.537537) (xy 41.268329 -497.525536) (xy 41.153978 -497.505599)
			(xy 41.041275 -497.47782) (xy 40.930758 -497.442332) (xy 40.822951 -497.399304) (xy 40.718371 -497.34894)
			(xy 40.617514 -497.291482) (xy 40.520861 -497.227202) (xy 40.428874 -497.156407) (xy 40.34199 -497.079434)
			(xy 40.260623 -496.996651) (xy 40.185161 -496.908451) (xy 40.115965 -496.815256) (xy 40.053363 -496.717508)
			(xy 39.997654 -496.615674) (xy 39.949103 -496.51024) (xy 39.907942 -496.401707) (xy 39.874367 -496.290593)
			(xy 39.848537 -496.177427) (xy 39.830577 -496.062749) (xy 39.820571 -495.947105) (xy 39.818567 -495.831047)
			(xy 0.509016 -495.831047) (xy 0.509016 -497.192469) (xy 4.94918 -497.192469) (xy 4.94918 -497.111359)
			(xy 4.95713 -497.03064) (xy 4.972953 -496.951089) (xy 4.996498 -496.873473) (xy 5.027537 -496.798537)
			(xy 5.065772 -496.727005) (xy 5.110834 -496.659565) (xy 5.162289 -496.596866) (xy 5.219642 -496.539513)
			(xy 5.282341 -496.488058) (xy 5.349781 -496.442996) (xy 5.421313 -496.404761) (xy 5.496249 -496.373722)
			(xy 5.573865 -496.350177) (xy 5.653416 -496.334354) (xy 5.734135 -496.326404) (xy 5.77469 -496.325906)
			(xy 5.815245 -496.326404) (xy 5.895964 -496.334354) (xy 5.975515 -496.350177) (xy 6.053131 -496.373722)
			(xy 6.128067 -496.404761) (xy 6.199599 -496.442996) (xy 6.267039 -496.488058) (xy 6.329738 -496.539513)
			(xy 6.387091 -496.596866) (xy 6.438546 -496.659565) (xy 6.483608 -496.727005) (xy 6.521843 -496.798537)
			(xy 6.552882 -496.873473) (xy 6.576427 -496.951089) (xy 6.59225 -497.03064) (xy 6.6002 -497.111359)
			(xy 6.6002 -497.192469) (xy 7.48918 -497.192469) (xy 7.48918 -497.111359) (xy 7.49713 -497.03064)
			(xy 7.512953 -496.951089) (xy 7.536498 -496.873473) (xy 7.567537 -496.798537) (xy 7.605772 -496.727005)
			(xy 7.650834 -496.659565) (xy 7.702289 -496.596866) (xy 7.759642 -496.539513) (xy 7.822341 -496.488058)
			(xy 7.889781 -496.442996) (xy 7.961313 -496.404761) (xy 8.036249 -496.373722) (xy 8.113865 -496.350177)
			(xy 8.193416 -496.334354) (xy 8.274135 -496.326404) (xy 8.31469 -496.325906) (xy 8.355245 -496.326404)
			(xy 8.435964 -496.334354) (xy 8.515515 -496.350177) (xy 8.593131 -496.373722) (xy 8.668067 -496.404761)
			(xy 8.739599 -496.442996) (xy 8.807039 -496.488058) (xy 8.869738 -496.539513) (xy 8.927091 -496.596866)
			(xy 8.978546 -496.659565) (xy 9.023608 -496.727005) (xy 9.061843 -496.798537) (xy 9.092882 -496.873473)
			(xy 9.116427 -496.951089) (xy 9.13225 -497.03064) (xy 9.1402 -497.111359) (xy 9.1402 -497.192469)
			(xy 10.02918 -497.192469) (xy 10.02918 -497.111359) (xy 10.03713 -497.03064) (xy 10.052953 -496.951089)
			(xy 10.076498 -496.873473) (xy 10.107537 -496.798537) (xy 10.145772 -496.727005) (xy 10.190834 -496.659565)
			(xy 10.242289 -496.596866) (xy 10.299642 -496.539513) (xy 10.362341 -496.488058) (xy 10.429781 -496.442996)
			(xy 10.501313 -496.404761) (xy 10.576249 -496.373722) (xy 10.653865 -496.350177) (xy 10.733416 -496.334354)
			(xy 10.814135 -496.326404) (xy 10.85469 -496.325906) (xy 10.895245 -496.326404) (xy 10.975964 -496.334354)
			(xy 11.055515 -496.350177) (xy 11.133131 -496.373722) (xy 11.208067 -496.404761) (xy 11.279599 -496.442996)
			(xy 11.347039 -496.488058) (xy 11.409738 -496.539513) (xy 11.467091 -496.596866) (xy 11.518546 -496.659565)
			(xy 11.563608 -496.727005) (xy 11.601843 -496.798537) (xy 11.632882 -496.873473) (xy 11.656427 -496.951089)
			(xy 11.67225 -497.03064) (xy 11.6802 -497.111359) (xy 11.6802 -497.192469) (xy 12.56918 -497.192469)
			(xy 12.56918 -497.111359) (xy 12.57713 -497.03064) (xy 12.592953 -496.951089) (xy 12.616498 -496.873473)
			(xy 12.647537 -496.798537) (xy 12.685772 -496.727005) (xy 12.730834 -496.659565) (xy 12.782289 -496.596866)
			(xy 12.839642 -496.539513) (xy 12.902341 -496.488058) (xy 12.969781 -496.442996) (xy 13.041313 -496.404761)
			(xy 13.116249 -496.373722) (xy 13.193865 -496.350177) (xy 13.273416 -496.334354) (xy 13.354135 -496.326404)
			(xy 13.39469 -496.325906) (xy 13.435245 -496.326404) (xy 13.515964 -496.334354) (xy 13.595515 -496.350177)
			(xy 13.673131 -496.373722) (xy 13.748067 -496.404761) (xy 13.819599 -496.442996) (xy 13.887039 -496.488058)
			(xy 13.949738 -496.539513) (xy 14.007091 -496.596866) (xy 14.058546 -496.659565) (xy 14.103608 -496.727005)
			(xy 14.141843 -496.798537) (xy 14.172882 -496.873473) (xy 14.196427 -496.951089) (xy 14.21225 -497.03064)
			(xy 14.2202 -497.111359) (xy 14.2202 -497.192469) (xy 14.21225 -497.273188) (xy 14.196427 -497.352739)
			(xy 14.172882 -497.430355) (xy 14.171636 -497.433362) (xy 29.519874 -497.433362) (xy 29.519874 -497.346462)
			(xy 29.527892 -497.259933) (xy 29.54386 -497.174513) (xy 29.567641 -497.090931) (xy 29.599033 -497.009899)
			(xy 29.637767 -496.93211) (xy 29.683514 -496.858226) (xy 29.735883 -496.788879) (xy 29.794427 -496.724659)
			(xy 29.858647 -496.666115) (xy 29.927994 -496.613746) (xy 30.001878 -496.567999) (xy 30.079667 -496.529265)
			(xy 30.160699 -496.497873) (xy 30.244281 -496.474092) (xy 30.329701 -496.458124) (xy 30.41623 -496.450106)
			(xy 30.45968 -496.449604) (xy 30.50313 -496.450106) (xy 30.589659 -496.458124) (xy 30.675079 -496.474092)
			(xy 30.758661 -496.497873) (xy 30.839693 -496.529265) (xy 30.917482 -496.567999) (xy 30.991366 -496.613746)
			(xy 31.060713 -496.666115) (xy 31.124933 -496.724659) (xy 31.183477 -496.788879) (xy 31.235846 -496.858226)
			(xy 31.281593 -496.93211) (xy 31.320327 -497.009899) (xy 31.351719 -497.090931) (xy 31.3755 -497.174513)
			(xy 31.391468 -497.259933) (xy 31.399486 -497.346462) (xy 31.399486 -497.433362) (xy 34.599874 -497.433362)
			(xy 34.599874 -497.346462) (xy 34.607892 -497.259933) (xy 34.62386 -497.174513) (xy 34.647641 -497.090931)
			(xy 34.679033 -497.009899) (xy 34.717767 -496.93211) (xy 34.763514 -496.858226) (xy 34.815883 -496.788879)
			(xy 34.874427 -496.724659) (xy 34.938647 -496.666115) (xy 35.007994 -496.613746) (xy 35.081878 -496.567999)
			(xy 35.159667 -496.529265) (xy 35.240699 -496.497873) (xy 35.324281 -496.474092) (xy 35.409701 -496.458124)
			(xy 35.49623 -496.450106) (xy 35.53968 -496.449604) (xy 35.58313 -496.450106) (xy 35.669659 -496.458124)
			(xy 35.755079 -496.474092) (xy 35.838661 -496.497873) (xy 35.919693 -496.529265) (xy 35.997482 -496.567999)
			(xy 36.071366 -496.613746) (xy 36.140713 -496.666115) (xy 36.204933 -496.724659) (xy 36.263477 -496.788879)
			(xy 36.315846 -496.858226) (xy 36.361593 -496.93211) (xy 36.400327 -497.009899) (xy 36.431719 -497.090931)
			(xy 36.4555 -497.174513) (xy 36.471468 -497.259933) (xy 36.479486 -497.346462) (xy 36.479486 -497.433362)
			(xy 36.471468 -497.519891) (xy 36.4555 -497.605311) (xy 36.431719 -497.688893) (xy 36.400327 -497.769925)
			(xy 36.361593 -497.847714) (xy 36.315846 -497.921598) (xy 36.263477 -497.990945) (xy 36.204933 -498.055165)
			(xy 36.140713 -498.113709) (xy 36.071366 -498.166078) (xy 35.997482 -498.211825) (xy 35.919693 -498.250559)
			(xy 35.838661 -498.281951) (xy 35.755079 -498.305732) (xy 35.669659 -498.3217) (xy 35.58313 -498.329718)
			(xy 35.49623 -498.329718) (xy 35.409701 -498.3217) (xy 35.324281 -498.305732) (xy 35.240699 -498.281951)
			(xy 35.159667 -498.250559) (xy 35.081878 -498.211825) (xy 35.007994 -498.166078) (xy 34.938647 -498.113709)
			(xy 34.874427 -498.055165) (xy 34.815883 -497.990945) (xy 34.763514 -497.921598) (xy 34.717767 -497.847714)
			(xy 34.679033 -497.769925) (xy 34.647641 -497.688893) (xy 34.62386 -497.605311) (xy 34.607892 -497.519891)
			(xy 34.599874 -497.433362) (xy 31.399486 -497.433362) (xy 31.391468 -497.519891) (xy 31.3755 -497.605311)
			(xy 31.351719 -497.688893) (xy 31.320327 -497.769925) (xy 31.281593 -497.847714) (xy 31.235846 -497.921598)
			(xy 31.183477 -497.990945) (xy 31.124933 -498.055165) (xy 31.060713 -498.113709) (xy 30.991366 -498.166078)
			(xy 30.917482 -498.211825) (xy 30.839693 -498.250559) (xy 30.758661 -498.281951) (xy 30.675079 -498.305732)
			(xy 30.589659 -498.3217) (xy 30.50313 -498.329718) (xy 30.41623 -498.329718) (xy 30.329701 -498.3217)
			(xy 30.244281 -498.305732) (xy 30.160699 -498.281951) (xy 30.079667 -498.250559) (xy 30.001878 -498.211825)
			(xy 29.927994 -498.166078) (xy 29.858647 -498.113709) (xy 29.794427 -498.055165) (xy 29.735883 -497.990945)
			(xy 29.683514 -497.921598) (xy 29.637767 -497.847714) (xy 29.599033 -497.769925) (xy 29.567641 -497.688893)
			(xy 29.54386 -497.605311) (xy 29.527892 -497.519891) (xy 29.519874 -497.433362) (xy 14.171636 -497.433362)
			(xy 14.141843 -497.505291) (xy 14.103608 -497.576823) (xy 14.058546 -497.644263) (xy 14.007091 -497.706962)
			(xy 13.949738 -497.764315) (xy 13.887039 -497.81577) (xy 13.819599 -497.860832) (xy 13.748067 -497.899067)
			(xy 13.673131 -497.930106) (xy 13.595515 -497.953651) (xy 13.515964 -497.969474) (xy 13.435245 -497.977424)
			(xy 13.354135 -497.977424) (xy 13.273416 -497.969474) (xy 13.193865 -497.953651) (xy 13.116249 -497.930106)
			(xy 13.041313 -497.899067) (xy 12.969781 -497.860832) (xy 12.902341 -497.81577) (xy 12.839642 -497.764315)
			(xy 12.782289 -497.706962) (xy 12.730834 -497.644263) (xy 12.685772 -497.576823) (xy 12.647537 -497.505291)
			(xy 12.616498 -497.430355) (xy 12.592953 -497.352739) (xy 12.57713 -497.273188) (xy 12.56918 -497.192469)
			(xy 11.6802 -497.192469) (xy 11.67225 -497.273188) (xy 11.656427 -497.352739) (xy 11.632882 -497.430355)
			(xy 11.601843 -497.505291) (xy 11.563608 -497.576823) (xy 11.518546 -497.644263) (xy 11.467091 -497.706962)
			(xy 11.409738 -497.764315) (xy 11.347039 -497.81577) (xy 11.279599 -497.860832) (xy 11.208067 -497.899067)
			(xy 11.133131 -497.930106) (xy 11.055515 -497.953651) (xy 10.975964 -497.969474) (xy 10.895245 -497.977424)
			(xy 10.814135 -497.977424) (xy 10.733416 -497.969474) (xy 10.653865 -497.953651) (xy 10.576249 -497.930106)
			(xy 10.501313 -497.899067) (xy 10.429781 -497.860832) (xy 10.362341 -497.81577) (xy 10.299642 -497.764315)
			(xy 10.242289 -497.706962) (xy 10.190834 -497.644263) (xy 10.145772 -497.576823) (xy 10.107537 -497.505291)
			(xy 10.076498 -497.430355) (xy 10.052953 -497.352739) (xy 10.03713 -497.273188) (xy 10.02918 -497.192469)
			(xy 9.1402 -497.192469) (xy 9.13225 -497.273188) (xy 9.116427 -497.352739) (xy 9.092882 -497.430355)
			(xy 9.061843 -497.505291) (xy 9.023608 -497.576823) (xy 8.978546 -497.644263) (xy 8.927091 -497.706962)
			(xy 8.869738 -497.764315) (xy 8.807039 -497.81577) (xy 8.739599 -497.860832) (xy 8.668067 -497.899067)
			(xy 8.593131 -497.930106) (xy 8.515515 -497.953651) (xy 8.435964 -497.969474) (xy 8.355245 -497.977424)
			(xy 8.274135 -497.977424) (xy 8.193416 -497.969474) (xy 8.113865 -497.953651) (xy 8.036249 -497.930106)
			(xy 7.961313 -497.899067) (xy 7.889781 -497.860832) (xy 7.822341 -497.81577) (xy 7.759642 -497.764315)
			(xy 7.702289 -497.706962) (xy 7.650834 -497.644263) (xy 7.605772 -497.576823) (xy 7.567537 -497.505291)
			(xy 7.536498 -497.430355) (xy 7.512953 -497.352739) (xy 7.49713 -497.273188) (xy 7.48918 -497.192469)
			(xy 6.6002 -497.192469) (xy 6.59225 -497.273188) (xy 6.576427 -497.352739) (xy 6.552882 -497.430355)
			(xy 6.521843 -497.505291) (xy 6.483608 -497.576823) (xy 6.438546 -497.644263) (xy 6.387091 -497.706962)
			(xy 6.329738 -497.764315) (xy 6.267039 -497.81577) (xy 6.199599 -497.860832) (xy 6.128067 -497.899067)
			(xy 6.053131 -497.930106) (xy 5.975515 -497.953651) (xy 5.895964 -497.969474) (xy 5.815245 -497.977424)
			(xy 5.734135 -497.977424) (xy 5.653416 -497.969474) (xy 5.573865 -497.953651) (xy 5.496249 -497.930106)
			(xy 5.421313 -497.899067) (xy 5.349781 -497.860832) (xy 5.282341 -497.81577) (xy 5.219642 -497.764315)
			(xy 5.162289 -497.706962) (xy 5.110834 -497.644263) (xy 5.065772 -497.576823) (xy 5.027537 -497.505291)
			(xy 4.996498 -497.430355) (xy 4.972953 -497.352739) (xy 4.95713 -497.273188) (xy 4.94918 -497.192469)
			(xy 0.509016 -497.192469) (xy 0.509016 -499.973362) (xy 29.519874 -499.973362) (xy 29.519874 -499.886462)
			(xy 29.527892 -499.799933) (xy 29.54386 -499.714513) (xy 29.567641 -499.630931) (xy 29.599033 -499.549899)
			(xy 29.637767 -499.47211) (xy 29.683514 -499.398226) (xy 29.735883 -499.328879) (xy 29.794427 -499.264659)
			(xy 29.858647 -499.206115) (xy 29.927994 -499.153746) (xy 30.001878 -499.107999) (xy 30.079667 -499.069265)
			(xy 30.160699 -499.037873) (xy 30.244281 -499.014092) (xy 30.329701 -498.998124) (xy 30.41623 -498.990106)
			(xy 30.45968 -498.989604) (xy 30.50313 -498.990106) (xy 30.589659 -498.998124) (xy 30.675079 -499.014092)
			(xy 30.758661 -499.037873) (xy 30.839693 -499.069265) (xy 30.917482 -499.107999) (xy 30.991366 -499.153746)
			(xy 31.060713 -499.206115) (xy 31.124933 -499.264659) (xy 31.183477 -499.328879) (xy 31.235846 -499.398226)
			(xy 31.281593 -499.47211) (xy 31.320327 -499.549899) (xy 31.351719 -499.630931) (xy 31.3755 -499.714513)
			(xy 31.391468 -499.799933) (xy 31.399486 -499.886462) (xy 31.399486 -499.973362) (xy 34.599874 -499.973362)
			(xy 34.599874 -499.886462) (xy 34.607892 -499.799933) (xy 34.62386 -499.714513) (xy 34.647641 -499.630931)
			(xy 34.679033 -499.549899) (xy 34.717767 -499.47211) (xy 34.763514 -499.398226) (xy 34.815883 -499.328879)
			(xy 34.874427 -499.264659) (xy 34.938647 -499.206115) (xy 35.007994 -499.153746) (xy 35.081878 -499.107999)
			(xy 35.159667 -499.069265) (xy 35.240699 -499.037873) (xy 35.324281 -499.014092) (xy 35.409701 -498.998124)
			(xy 35.49623 -498.990106) (xy 35.53968 -498.989604) (xy 35.58313 -498.990106) (xy 35.669659 -498.998124)
			(xy 35.755079 -499.014092) (xy 35.838661 -499.037873) (xy 35.919693 -499.069265) (xy 35.997482 -499.107999)
			(xy 36.071366 -499.153746) (xy 36.140713 -499.206115) (xy 36.204933 -499.264659) (xy 36.263477 -499.328879)
			(xy 36.315846 -499.398226) (xy 36.361593 -499.47211) (xy 36.400327 -499.549899) (xy 36.431719 -499.630931)
			(xy 36.4555 -499.714513) (xy 36.471468 -499.799933) (xy 36.479486 -499.886462) (xy 36.479486 -499.973362)
			(xy 36.471468 -500.059891) (xy 36.4555 -500.145311) (xy 36.431719 -500.228893) (xy 36.400327 -500.309925)
			(xy 36.361593 -500.387714) (xy 36.315846 -500.461598) (xy 36.263477 -500.530945) (xy 36.204933 -500.595165)
			(xy 36.140713 -500.653709) (xy 36.071366 -500.706078) (xy 35.997482 -500.751825) (xy 35.919693 -500.790559)
			(xy 35.838661 -500.821951) (xy 35.755079 -500.845732) (xy 35.669659 -500.8617) (xy 35.58313 -500.869718)
			(xy 35.49623 -500.869718) (xy 35.409701 -500.8617) (xy 35.324281 -500.845732) (xy 35.240699 -500.821951)
			(xy 35.159667 -500.790559) (xy 35.081878 -500.751825) (xy 35.007994 -500.706078) (xy 34.938647 -500.653709)
			(xy 34.874427 -500.595165) (xy 34.815883 -500.530945) (xy 34.763514 -500.461598) (xy 34.717767 -500.387714)
			(xy 34.679033 -500.309925) (xy 34.647641 -500.228893) (xy 34.62386 -500.145311) (xy 34.607892 -500.059891)
			(xy 34.599874 -499.973362) (xy 31.399486 -499.973362) (xy 31.391468 -500.059891) (xy 31.3755 -500.145311)
			(xy 31.351719 -500.228893) (xy 31.320327 -500.309925) (xy 31.281593 -500.387714) (xy 31.235846 -500.461598)
			(xy 31.183477 -500.530945) (xy 31.124933 -500.595165) (xy 31.060713 -500.653709) (xy 30.991366 -500.706078)
			(xy 30.917482 -500.751825) (xy 30.839693 -500.790559) (xy 30.758661 -500.821951) (xy 30.675079 -500.845732)
			(xy 30.589659 -500.8617) (xy 30.50313 -500.869718) (xy 30.41623 -500.869718) (xy 30.329701 -500.8617)
			(xy 30.244281 -500.845732) (xy 30.160699 -500.821951) (xy 30.079667 -500.790559) (xy 30.001878 -500.751825)
			(xy 29.927994 -500.706078) (xy 29.858647 -500.653709) (xy 29.794427 -500.595165) (xy 29.735883 -500.530945)
			(xy 29.683514 -500.461598) (xy 29.637767 -500.387714) (xy 29.599033 -500.309925) (xy 29.567641 -500.228893)
			(xy 29.54386 -500.145311) (xy 29.527892 -500.059891) (xy 29.519874 -499.973362) (xy 0.509016 -499.973362)
			(xy 0.509016 -502.513362) (xy 29.519874 -502.513362) (xy 29.519874 -502.426462) (xy 29.527892 -502.339933)
			(xy 29.54386 -502.254513) (xy 29.567641 -502.170931) (xy 29.599033 -502.089899) (xy 29.637767 -502.01211)
			(xy 29.683514 -501.938226) (xy 29.735883 -501.868879) (xy 29.794427 -501.804659) (xy 29.858647 -501.746115)
			(xy 29.927994 -501.693746) (xy 30.001878 -501.647999) (xy 30.079667 -501.609265) (xy 30.160699 -501.577873)
			(xy 30.244281 -501.554092) (xy 30.329701 -501.538124) (xy 30.41623 -501.530106) (xy 30.45968 -501.529604)
			(xy 30.50313 -501.530106) (xy 30.589659 -501.538124) (xy 30.675079 -501.554092) (xy 30.758661 -501.577873)
			(xy 30.839693 -501.609265) (xy 30.917482 -501.647999) (xy 30.991366 -501.693746) (xy 31.060713 -501.746115)
			(xy 31.124933 -501.804659) (xy 31.183477 -501.868879) (xy 31.235846 -501.938226) (xy 31.281593 -502.01211)
			(xy 31.320327 -502.089899) (xy 31.351719 -502.170931) (xy 31.3755 -502.254513) (xy 31.391468 -502.339933)
			(xy 31.399486 -502.426462) (xy 31.399486 -502.513362) (xy 34.599874 -502.513362) (xy 34.599874 -502.426462)
			(xy 34.607892 -502.339933) (xy 34.62386 -502.254513) (xy 34.647641 -502.170931) (xy 34.679033 -502.089899)
			(xy 34.717767 -502.01211) (xy 34.763514 -501.938226) (xy 34.815883 -501.868879) (xy 34.874427 -501.804659)
			(xy 34.938647 -501.746115) (xy 35.007994 -501.693746) (xy 35.081878 -501.647999) (xy 35.159667 -501.609265)
			(xy 35.240699 -501.577873) (xy 35.324281 -501.554092) (xy 35.409701 -501.538124) (xy 35.49623 -501.530106)
			(xy 35.53968 -501.529604) (xy 35.58313 -501.530106) (xy 35.669659 -501.538124) (xy 35.755079 -501.554092)
			(xy 35.838661 -501.577873) (xy 35.919693 -501.609265) (xy 35.997482 -501.647999) (xy 36.071366 -501.693746)
			(xy 36.140713 -501.746115) (xy 36.204933 -501.804659) (xy 36.263477 -501.868879) (xy 36.315846 -501.938226)
			(xy 36.361593 -502.01211) (xy 36.400327 -502.089899) (xy 36.431719 -502.170931) (xy 36.4555 -502.254513)
			(xy 36.471468 -502.339933) (xy 36.479486 -502.426462) (xy 36.479486 -502.513362) (xy 36.471468 -502.599891)
			(xy 36.4555 -502.685311) (xy 36.431719 -502.768893) (xy 36.400327 -502.849925) (xy 36.361593 -502.927714)
			(xy 36.315846 -503.001598) (xy 36.263477 -503.070945) (xy 36.204933 -503.135165) (xy 36.140713 -503.193709)
			(xy 36.071366 -503.246078) (xy 35.997482 -503.291825) (xy 35.919693 -503.330559) (xy 35.838661 -503.361951)
			(xy 35.755079 -503.385732) (xy 35.669659 -503.4017) (xy 35.58313 -503.409718) (xy 35.49623 -503.409718)
			(xy 35.409701 -503.4017) (xy 35.324281 -503.385732) (xy 35.240699 -503.361951) (xy 35.159667 -503.330559)
			(xy 35.081878 -503.291825) (xy 35.007994 -503.246078) (xy 34.938647 -503.193709) (xy 34.874427 -503.135165)
			(xy 34.815883 -503.070945) (xy 34.763514 -503.001598) (xy 34.717767 -502.927714) (xy 34.679033 -502.849925)
			(xy 34.647641 -502.768893) (xy 34.62386 -502.685311) (xy 34.607892 -502.599891) (xy 34.599874 -502.513362)
			(xy 31.399486 -502.513362) (xy 31.391468 -502.599891) (xy 31.3755 -502.685311) (xy 31.351719 -502.768893)
			(xy 31.320327 -502.849925) (xy 31.281593 -502.927714) (xy 31.235846 -503.001598) (xy 31.183477 -503.070945)
			(xy 31.124933 -503.135165) (xy 31.060713 -503.193709) (xy 30.991366 -503.246078) (xy 30.917482 -503.291825)
			(xy 30.839693 -503.330559) (xy 30.758661 -503.361951) (xy 30.675079 -503.385732) (xy 30.589659 -503.4017)
			(xy 30.50313 -503.409718) (xy 30.41623 -503.409718) (xy 30.329701 -503.4017) (xy 30.244281 -503.385732)
			(xy 30.160699 -503.361951) (xy 30.079667 -503.330559) (xy 30.001878 -503.291825) (xy 29.927994 -503.246078)
			(xy 29.858647 -503.193709) (xy 29.794427 -503.135165) (xy 29.735883 -503.070945) (xy 29.683514 -503.001598)
			(xy 29.637767 -502.927714) (xy 29.599033 -502.849925) (xy 29.567641 -502.768893) (xy 29.54386 -502.685311)
			(xy 29.527892 -502.599891) (xy 29.519874 -502.513362) (xy 0.509016 -502.513362) (xy 0.509016 -505.053362)
			(xy 29.519874 -505.053362) (xy 29.519874 -504.966462) (xy 29.527892 -504.879933) (xy 29.54386 -504.794513)
			(xy 29.567641 -504.710931) (xy 29.599033 -504.629899) (xy 29.637767 -504.55211) (xy 29.683514 -504.478226)
			(xy 29.735883 -504.408879) (xy 29.794427 -504.344659) (xy 29.858647 -504.286115) (xy 29.927994 -504.233746)
			(xy 30.001878 -504.187999) (xy 30.079667 -504.149265) (xy 30.160699 -504.117873) (xy 30.244281 -504.094092)
			(xy 30.329701 -504.078124) (xy 30.41623 -504.070106) (xy 30.45968 -504.069604) (xy 30.50313 -504.070106)
			(xy 30.589659 -504.078124) (xy 30.675079 -504.094092) (xy 30.758661 -504.117873) (xy 30.839693 -504.149265)
			(xy 30.917482 -504.187999) (xy 30.991366 -504.233746) (xy 31.060713 -504.286115) (xy 31.124933 -504.344659)
			(xy 31.183477 -504.408879) (xy 31.235846 -504.478226) (xy 31.281593 -504.55211) (xy 31.320327 -504.629899)
			(xy 31.351719 -504.710931) (xy 31.3755 -504.794513) (xy 31.391468 -504.879933) (xy 31.399486 -504.966462)
			(xy 31.399486 -505.053362) (xy 34.599874 -505.053362) (xy 34.599874 -504.966462) (xy 34.607892 -504.879933)
			(xy 34.62386 -504.794513) (xy 34.647641 -504.710931) (xy 34.679033 -504.629899) (xy 34.717767 -504.55211)
			(xy 34.763514 -504.478226) (xy 34.815883 -504.408879) (xy 34.874427 -504.344659) (xy 34.938647 -504.286115)
			(xy 35.007994 -504.233746) (xy 35.081878 -504.187999) (xy 35.159667 -504.149265) (xy 35.240699 -504.117873)
			(xy 35.324281 -504.094092) (xy 35.409701 -504.078124) (xy 35.49623 -504.070106) (xy 35.53968 -504.069604)
			(xy 35.58313 -504.070106) (xy 35.669659 -504.078124) (xy 35.755079 -504.094092) (xy 35.838661 -504.117873)
			(xy 35.919693 -504.149265) (xy 35.997482 -504.187999) (xy 36.071366 -504.233746) (xy 36.140713 -504.286115)
			(xy 36.204933 -504.344659) (xy 36.263477 -504.408879) (xy 36.315846 -504.478226) (xy 36.361593 -504.55211)
			(xy 36.400327 -504.629899) (xy 36.431719 -504.710931) (xy 36.4555 -504.794513) (xy 36.471468 -504.879933)
			(xy 36.479486 -504.966462) (xy 36.479486 -505.053362) (xy 36.471468 -505.139891) (xy 36.4555 -505.225311)
			(xy 36.431719 -505.308893) (xy 36.400327 -505.389925) (xy 36.361593 -505.467714) (xy 36.315846 -505.541598)
			(xy 36.263477 -505.610945) (xy 36.204933 -505.675165) (xy 36.140713 -505.733709) (xy 36.071366 -505.786078)
			(xy 35.997482 -505.831825) (xy 35.919693 -505.870559) (xy 35.838661 -505.901951) (xy 35.755079 -505.925732)
			(xy 35.669659 -505.9417) (xy 35.58313 -505.949718) (xy 35.49623 -505.949718) (xy 35.409701 -505.9417)
			(xy 35.324281 -505.925732) (xy 35.240699 -505.901951) (xy 35.159667 -505.870559) (xy 35.081878 -505.831825)
			(xy 35.007994 -505.786078) (xy 34.938647 -505.733709) (xy 34.874427 -505.675165) (xy 34.815883 -505.610945)
			(xy 34.763514 -505.541598) (xy 34.717767 -505.467714) (xy 34.679033 -505.389925) (xy 34.647641 -505.308893)
			(xy 34.62386 -505.225311) (xy 34.607892 -505.139891) (xy 34.599874 -505.053362) (xy 31.399486 -505.053362)
			(xy 31.391468 -505.139891) (xy 31.3755 -505.225311) (xy 31.351719 -505.308893) (xy 31.320327 -505.389925)
			(xy 31.281593 -505.467714) (xy 31.235846 -505.541598) (xy 31.183477 -505.610945) (xy 31.124933 -505.675165)
			(xy 31.060713 -505.733709) (xy 30.991366 -505.786078) (xy 30.917482 -505.831825) (xy 30.839693 -505.870559)
			(xy 30.758661 -505.901951) (xy 30.675079 -505.925732) (xy 30.589659 -505.9417) (xy 30.50313 -505.949718)
			(xy 30.41623 -505.949718) (xy 30.329701 -505.9417) (xy 30.244281 -505.925732) (xy 30.160699 -505.901951)
			(xy 30.079667 -505.870559) (xy 30.001878 -505.831825) (xy 29.927994 -505.786078) (xy 29.858647 -505.733709)
			(xy 29.794427 -505.675165) (xy 29.735883 -505.610945) (xy 29.683514 -505.541598) (xy 29.637767 -505.467714)
			(xy 29.599033 -505.389925) (xy 29.567641 -505.308893) (xy 29.54386 -505.225311) (xy 29.527892 -505.139891)
			(xy 29.519874 -505.053362) (xy 0.509016 -505.053362) (xy 0.509016 -507.593362) (xy 29.519874 -507.593362)
			(xy 29.519874 -507.506462) (xy 29.527892 -507.419933) (xy 29.54386 -507.334513) (xy 29.567641 -507.250931)
			(xy 29.599033 -507.169899) (xy 29.637767 -507.09211) (xy 29.683514 -507.018226) (xy 29.735883 -506.948879)
			(xy 29.794427 -506.884659) (xy 29.858647 -506.826115) (xy 29.927994 -506.773746) (xy 30.001878 -506.727999)
			(xy 30.079667 -506.689265) (xy 30.160699 -506.657873) (xy 30.244281 -506.634092) (xy 30.329701 -506.618124)
			(xy 30.41623 -506.610106) (xy 30.45968 -506.609604) (xy 30.50313 -506.610106) (xy 30.589659 -506.618124)
			(xy 30.675079 -506.634092) (xy 30.758661 -506.657873) (xy 30.839693 -506.689265) (xy 30.917482 -506.727999)
			(xy 30.991366 -506.773746) (xy 31.060713 -506.826115) (xy 31.124933 -506.884659) (xy 31.183477 -506.948879)
			(xy 31.235846 -507.018226) (xy 31.281593 -507.09211) (xy 31.320327 -507.169899) (xy 31.351719 -507.250931)
			(xy 31.3755 -507.334513) (xy 31.391468 -507.419933) (xy 31.399486 -507.506462) (xy 31.399486 -507.593362)
			(xy 34.599874 -507.593362) (xy 34.599874 -507.506462) (xy 34.607892 -507.419933) (xy 34.62386 -507.334513)
			(xy 34.647641 -507.250931) (xy 34.679033 -507.169899) (xy 34.717767 -507.09211) (xy 34.763514 -507.018226)
			(xy 34.815883 -506.948879) (xy 34.874427 -506.884659) (xy 34.938647 -506.826115) (xy 35.007994 -506.773746)
			(xy 35.081878 -506.727999) (xy 35.159667 -506.689265) (xy 35.240699 -506.657873) (xy 35.324281 -506.634092)
			(xy 35.409701 -506.618124) (xy 35.49623 -506.610106) (xy 35.53968 -506.609604) (xy 35.58313 -506.610106)
			(xy 35.669659 -506.618124) (xy 35.755079 -506.634092) (xy 35.838661 -506.657873) (xy 35.919693 -506.689265)
			(xy 35.997482 -506.727999) (xy 36.071366 -506.773746) (xy 36.140713 -506.826115) (xy 36.168463 -506.851412)
			(xy 51.474116 -506.851412) (xy 53.125624 -506.851412) (xy 53.125624 -508.503428) (xy 51.474116 -508.503428)
			(xy 51.474116 -506.851412) (xy 36.168463 -506.851412) (xy 36.204933 -506.884659) (xy 36.263477 -506.948879)
			(xy 36.315846 -507.018226) (xy 36.361593 -507.09211) (xy 36.400327 -507.169899) (xy 36.431719 -507.250931)
			(xy 36.4555 -507.334513) (xy 36.471468 -507.419933) (xy 36.479486 -507.506462) (xy 36.479486 -507.593362)
			(xy 36.471468 -507.679891) (xy 36.4555 -507.765311) (xy 36.431719 -507.848893) (xy 36.400327 -507.929925)
			(xy 36.361593 -508.007714) (xy 36.315846 -508.081598) (xy 36.263477 -508.150945) (xy 36.204933 -508.215165)
			(xy 36.140713 -508.273709) (xy 36.071366 -508.326078) (xy 35.997482 -508.371825) (xy 35.919693 -508.410559)
			(xy 35.838661 -508.441951) (xy 35.755079 -508.465732) (xy 35.669659 -508.4817) (xy 35.58313 -508.489718)
			(xy 35.49623 -508.489718) (xy 35.409701 -508.4817) (xy 35.324281 -508.465732) (xy 35.240699 -508.441951)
			(xy 35.159667 -508.410559) (xy 35.081878 -508.371825) (xy 35.007994 -508.326078) (xy 34.938647 -508.273709)
			(xy 34.874427 -508.215165) (xy 34.815883 -508.150945) (xy 34.763514 -508.081598) (xy 34.717767 -508.007714)
			(xy 34.679033 -507.929925) (xy 34.647641 -507.848893) (xy 34.62386 -507.765311) (xy 34.607892 -507.679891)
			(xy 34.599874 -507.593362) (xy 31.399486 -507.593362) (xy 31.391468 -507.679891) (xy 31.3755 -507.765311)
			(xy 31.351719 -507.848893) (xy 31.320327 -507.929925) (xy 31.281593 -508.007714) (xy 31.235846 -508.081598)
			(xy 31.183477 -508.150945) (xy 31.124933 -508.215165) (xy 31.060713 -508.273709) (xy 30.991366 -508.326078)
			(xy 30.917482 -508.371825) (xy 30.839693 -508.410559) (xy 30.758661 -508.441951) (xy 30.675079 -508.465732)
			(xy 30.589659 -508.4817) (xy 30.50313 -508.489718) (xy 30.41623 -508.489718) (xy 30.329701 -508.4817)
			(xy 30.244281 -508.465732) (xy 30.160699 -508.441951) (xy 30.079667 -508.410559) (xy 30.001878 -508.371825)
			(xy 29.927994 -508.326078) (xy 29.858647 -508.273709) (xy 29.794427 -508.215165) (xy 29.735883 -508.150945)
			(xy 29.683514 -508.081598) (xy 29.637767 -508.007714) (xy 29.599033 -507.929925) (xy 29.567641 -507.848893)
			(xy 29.54386 -507.765311) (xy 29.527892 -507.679891) (xy 29.519874 -507.593362) (xy 0.509016 -507.593362)
			(xy 0.509016 -509.010411) (xy 86.399122 -509.010411) (xy 86.401115 -508.810283) (xy 86.411112 -508.610394)
			(xy 86.429099 -508.411066) (xy 86.455047 -508.212617) (xy 86.488914 -508.015365) (xy 86.530646 -507.819626)
			(xy 86.580175 -507.625713) (xy 86.637424 -507.433938) (xy 86.702299 -507.244606) (xy 86.774698 -507.058022)
			(xy 86.854504 -506.874483) (xy 86.941589 -506.694285) (xy 87.035814 -506.517715) (xy 87.137028 -506.345056)
			(xy 87.245069 -506.176586) (xy 87.359764 -506.012572) (xy 87.48093 -505.853279) (xy 87.608371 -505.698962)
			(xy 87.741885 -505.549866) (xy 87.881257 -505.406232) (xy 88.026264 -505.26829) (xy 88.176675 -505.136259)
			(xy 88.332247 -505.010352) (xy 88.492732 -504.89077) (xy 88.657873 -504.777705) (xy 88.827405 -504.671337)
			(xy 89.001058 -504.571838) (xy 89.178552 -504.479366) (xy 89.359604 -504.39407) (xy 89.543924 -504.316086)
			(xy 89.731216 -504.245538) (xy 89.921181 -504.182541) (xy 90.113514 -504.127195) (xy 90.307908 -504.079588)
			(xy 90.504051 -504.039797) (xy 90.701628 -504.007885) (xy 90.900325 -503.983904) (xy 91.099821 -503.967891)
			(xy 91.299799 -503.959874) (xy 91.399868 -503.959368) (xy 91.499937 -503.959864) (xy 91.699915 -503.967861)
			(xy 91.899414 -503.983853) (xy 92.098112 -504.007814) (xy 92.295693 -504.039706) (xy 92.49184 -504.079477)
			(xy 92.686239 -504.127064) (xy 92.878578 -504.182391) (xy 93.068549 -504.245369) (xy 93.255848 -504.315897)
			(xy 93.440176 -504.393863) (xy 93.621237 -504.479141) (xy 93.79874 -504.571594) (xy 93.972403 -504.671076)
			(xy 94.141946 -504.777426) (xy 94.307099 -504.890475) (xy 94.467596 -505.01004) (xy 94.623181 -505.135932)
			(xy 94.773605 -505.267947) (xy 94.918626 -505.405875) (xy 95.058012 -505.549495) (xy 95.191541 -505.698576)
			(xy 95.318999 -505.852881) (xy 95.44018 -506.012162) (xy 95.554892 -506.176163) (xy 95.66295 -506.344623)
			(xy 95.764182 -506.517272) (xy 95.858425 -506.693832) (xy 95.945528 -506.874022) (xy 96.025353 -507.057552)
			(xy 96.09777 -507.244129) (xy 96.162665 -507.433454) (xy 96.219933 -507.625224) (xy 96.269483 -507.819131)
			(xy 96.311234 -508.014866) (xy 96.345121 -508.212115) (xy 96.371089 -508.410561) (xy 96.389096 -508.609888)
			(xy 96.399114 -508.809775) (xy 96.401127 -509.009903) (xy 96.395131 -509.209951) (xy 96.381135 -509.4096)
			(xy 96.359164 -509.608528) (xy 96.32925 -509.806418) (xy 96.291443 -510.002953) (xy 96.245804 -510.197818)
			(xy 96.192404 -510.390701) (xy 96.13133 -510.581293) (xy 96.062679 -510.769288) (xy 95.986561 -510.954387)
			(xy 95.903099 -511.136292) (xy 95.812426 -511.314711) (xy 95.714687 -511.489361) (xy 95.610038 -511.65996)
			(xy 95.498648 -511.826235) (xy 95.380694 -511.98792) (xy 95.256365 -512.144757) (xy 95.125862 -512.296494)
			(xy 94.989391 -512.442888) (xy 94.847173 -512.583704) (xy 94.699435 -512.718718) (xy 94.546413 -512.847713)
			(xy 94.388353 -512.970482) (xy 94.225507 -513.086829) (xy 94.058137 -513.196567) (xy 93.88651 -513.299521)
			(xy 93.710902 -513.395526) (xy 93.531592 -513.484428) (xy 93.34887 -513.566084) (xy 93.163027 -513.640365)
			(xy 92.97436 -513.707151) (xy 92.783173 -513.766334) (xy 92.589771 -513.817821) (xy 92.394464 -513.861529)
			(xy 92.197564 -513.897388) (xy 91.999387 -513.92534) (xy 91.800251 -513.94534) (xy 91.600474 -513.957358)
			(xy 91.400376 -513.961372) (xy 91.200278 -513.957378) (xy 91.000499 -513.945381) (xy 90.801361 -513.925401)
			(xy 90.603182 -513.897469) (xy 90.406278 -513.86163) (xy 90.210967 -513.817942) (xy 90.017559 -513.766475)
			(xy 89.826366 -513.707311) (xy 89.637693 -513.640544) (xy 89.451842 -513.566282) (xy 89.269111 -513.484644)
			(xy 89.089793 -513.395761) (xy 88.914175 -513.299774) (xy 88.742537 -513.196837) (xy 88.575156 -513.087116)
			(xy 88.412298 -512.970785) (xy 88.254226 -512.848032) (xy 88.101191 -512.719053) (xy 87.953439 -512.584055)
			(xy 87.811206 -512.443252) (xy 87.674721 -512.296872) (xy 87.544202 -512.145149) (xy 87.419858 -511.988325)
			(xy 87.301888 -511.826651) (xy 87.19048 -511.660387) (xy 87.085814 -511.489799) (xy 86.988057 -511.31516)
			(xy 86.897366 -511.136749) (xy 86.813885 -510.954853) (xy 86.737749 -510.769762) (xy 86.669079 -510.581773)
			(xy 86.607986 -510.391188) (xy 86.554566 -510.19831) (xy 86.508906 -510.00345) (xy 86.47108 -509.806919)
			(xy 86.441146 -509.609032) (xy 86.419154 -509.410106) (xy 86.405139 -509.210459) (xy 86.399122 -509.010411)
			(xy 0.509016 -509.010411) (xy 0.509016 -510.133362) (xy 29.519874 -510.133362) (xy 29.519874 -510.046462)
			(xy 29.527892 -509.959933) (xy 29.54386 -509.874513) (xy 29.567641 -509.790931) (xy 29.599033 -509.709899)
			(xy 29.637767 -509.63211) (xy 29.683514 -509.558226) (xy 29.735883 -509.488879) (xy 29.794427 -509.424659)
			(xy 29.858647 -509.366115) (xy 29.927994 -509.313746) (xy 30.001878 -509.267999) (xy 30.079667 -509.229265)
			(xy 30.160699 -509.197873) (xy 30.244281 -509.174092) (xy 30.329701 -509.158124) (xy 30.41623 -509.150106)
			(xy 30.45968 -509.149604) (xy 30.50313 -509.150106) (xy 30.589659 -509.158124) (xy 30.675079 -509.174092)
			(xy 30.758661 -509.197873) (xy 30.839693 -509.229265) (xy 30.917482 -509.267999) (xy 30.991366 -509.313746)
			(xy 31.060713 -509.366115) (xy 31.124933 -509.424659) (xy 31.183477 -509.488879) (xy 31.235846 -509.558226)
			(xy 31.281593 -509.63211) (xy 31.320327 -509.709899) (xy 31.351719 -509.790931) (xy 31.3755 -509.874513)
			(xy 31.391468 -509.959933) (xy 31.399486 -510.046462) (xy 31.399486 -510.133362) (xy 34.599874 -510.133362)
			(xy 34.599874 -510.046462) (xy 34.607892 -509.959933) (xy 34.62386 -509.874513) (xy 34.647641 -509.790931)
			(xy 34.679033 -509.709899) (xy 34.717767 -509.63211) (xy 34.763514 -509.558226) (xy 34.815883 -509.488879)
			(xy 34.874427 -509.424659) (xy 34.938647 -509.366115) (xy 35.007994 -509.313746) (xy 35.081878 -509.267999)
			(xy 35.159667 -509.229265) (xy 35.240699 -509.197873) (xy 35.324281 -509.174092) (xy 35.409701 -509.158124)
			(xy 35.49623 -509.150106) (xy 35.53968 -509.149604) (xy 35.58313 -509.150106) (xy 35.669659 -509.158124)
			(xy 35.755079 -509.174092) (xy 35.838661 -509.197873) (xy 35.919693 -509.229265) (xy 35.997482 -509.267999)
			(xy 36.071366 -509.313746) (xy 36.140713 -509.366115) (xy 36.204933 -509.424659) (xy 36.263477 -509.488879)
			(xy 36.315846 -509.558226) (xy 36.361593 -509.63211) (xy 36.400327 -509.709899) (xy 36.431719 -509.790931)
			(xy 36.4555 -509.874513) (xy 36.471468 -509.959933) (xy 36.479486 -510.046462) (xy 36.479486 -510.133362)
			(xy 36.471468 -510.219891) (xy 36.4555 -510.305311) (xy 36.431719 -510.388893) (xy 36.400327 -510.469925)
			(xy 36.361593 -510.547714) (xy 36.315846 -510.621598) (xy 36.263477 -510.690945) (xy 36.204933 -510.755165)
			(xy 36.140713 -510.813709) (xy 36.071366 -510.866078) (xy 35.997482 -510.911825) (xy 35.919693 -510.950559)
			(xy 35.838661 -510.981951) (xy 35.755079 -511.005732) (xy 35.669659 -511.0217) (xy 35.58313 -511.029718)
			(xy 35.49623 -511.029718) (xy 35.409701 -511.0217) (xy 35.324281 -511.005732) (xy 35.240699 -510.981951)
			(xy 35.159667 -510.950559) (xy 35.081878 -510.911825) (xy 35.007994 -510.866078) (xy 34.938647 -510.813709)
			(xy 34.874427 -510.755165) (xy 34.815883 -510.690945) (xy 34.763514 -510.621598) (xy 34.717767 -510.547714)
			(xy 34.679033 -510.469925) (xy 34.647641 -510.388893) (xy 34.62386 -510.305311) (xy 34.607892 -510.219891)
			(xy 34.599874 -510.133362) (xy 31.399486 -510.133362) (xy 31.391468 -510.219891) (xy 31.3755 -510.305311)
			(xy 31.351719 -510.388893) (xy 31.320327 -510.469925) (xy 31.281593 -510.547714) (xy 31.235846 -510.621598)
			(xy 31.183477 -510.690945) (xy 31.124933 -510.755165) (xy 31.060713 -510.813709) (xy 30.991366 -510.866078)
			(xy 30.917482 -510.911825) (xy 30.839693 -510.950559) (xy 30.758661 -510.981951) (xy 30.675079 -511.005732)
			(xy 30.589659 -511.0217) (xy 30.50313 -511.029718) (xy 30.41623 -511.029718) (xy 30.329701 -511.0217)
			(xy 30.244281 -511.005732) (xy 30.160699 -510.981951) (xy 30.079667 -510.950559) (xy 30.001878 -510.911825)
			(xy 29.927994 -510.866078) (xy 29.858647 -510.813709) (xy 29.794427 -510.755165) (xy 29.735883 -510.690945)
			(xy 29.683514 -510.621598) (xy 29.637767 -510.547714) (xy 29.599033 -510.469925) (xy 29.567641 -510.388893)
			(xy 29.54386 -510.305311) (xy 29.527892 -510.219891) (xy 29.519874 -510.133362) (xy 0.509016 -510.133362)
			(xy 0.509016 -512.673362) (xy 29.519874 -512.673362) (xy 29.519874 -512.586462) (xy 29.527892 -512.499933)
			(xy 29.54386 -512.414513) (xy 29.567641 -512.330931) (xy 29.599033 -512.249899) (xy 29.637767 -512.17211)
			(xy 29.683514 -512.098226) (xy 29.735883 -512.028879) (xy 29.794427 -511.964659) (xy 29.858647 -511.906115)
			(xy 29.927994 -511.853746) (xy 30.001878 -511.807999) (xy 30.079667 -511.769265) (xy 30.160699 -511.737873)
			(xy 30.244281 -511.714092) (xy 30.329701 -511.698124) (xy 30.41623 -511.690106) (xy 30.45968 -511.689604)
			(xy 30.50313 -511.690106) (xy 30.589659 -511.698124) (xy 30.675079 -511.714092) (xy 30.758661 -511.737873)
			(xy 30.839693 -511.769265) (xy 30.917482 -511.807999) (xy 30.991366 -511.853746) (xy 31.060713 -511.906115)
			(xy 31.124933 -511.964659) (xy 31.183477 -512.028879) (xy 31.235846 -512.098226) (xy 31.281593 -512.17211)
			(xy 31.320327 -512.249899) (xy 31.351719 -512.330931) (xy 31.3755 -512.414513) (xy 31.391468 -512.499933)
			(xy 31.399486 -512.586462) (xy 31.399486 -512.673362) (xy 34.599874 -512.673362) (xy 34.599874 -512.586462)
			(xy 34.607892 -512.499933) (xy 34.62386 -512.414513) (xy 34.647641 -512.330931) (xy 34.679033 -512.249899)
			(xy 34.717767 -512.17211) (xy 34.763514 -512.098226) (xy 34.815883 -512.028879) (xy 34.874427 -511.964659)
			(xy 34.938647 -511.906115) (xy 35.007994 -511.853746) (xy 35.081878 -511.807999) (xy 35.159667 -511.769265)
			(xy 35.240699 -511.737873) (xy 35.324281 -511.714092) (xy 35.409701 -511.698124) (xy 35.49623 -511.690106)
			(xy 35.53968 -511.689604) (xy 35.58313 -511.690106) (xy 35.669659 -511.698124) (xy 35.755079 -511.714092)
			(xy 35.838661 -511.737873) (xy 35.919693 -511.769265) (xy 35.997482 -511.807999) (xy 36.071366 -511.853746)
			(xy 36.140713 -511.906115) (xy 36.204933 -511.964659) (xy 36.263477 -512.028879) (xy 36.315846 -512.098226)
			(xy 36.361593 -512.17211) (xy 36.400327 -512.249899) (xy 36.431719 -512.330931) (xy 36.4555 -512.414513)
			(xy 36.471468 -512.499933) (xy 36.479486 -512.586462) (xy 36.479486 -512.673362) (xy 36.471468 -512.759891)
			(xy 36.4555 -512.845311) (xy 36.431719 -512.928893) (xy 36.400327 -513.009925) (xy 36.361593 -513.087714)
			(xy 36.315846 -513.161598) (xy 36.263477 -513.230945) (xy 36.204933 -513.295165) (xy 36.140713 -513.353709)
			(xy 36.131362 -513.360771) (xy 56.406534 -513.360771) (xy 56.406534 -513.289449) (xy 56.41452 -513.218575)
			(xy 56.43039 -513.14904) (xy 56.453947 -513.08172) (xy 56.484892 -513.017461) (xy 56.522838 -512.95707)
			(xy 56.567307 -512.901308) (xy 56.61774 -512.850875) (xy 56.673502 -512.806406) (xy 56.733893 -512.76846)
			(xy 56.798152 -512.737515) (xy 56.865472 -512.713958) (xy 56.935007 -512.698088) (xy 57.005881 -512.690102)
			(xy 57.041542 -512.689602) (xy 57.077203 -512.690102) (xy 57.148077 -512.698088) (xy 57.217612 -512.713958)
			(xy 57.284932 -512.737515) (xy 57.349191 -512.76846) (xy 57.409582 -512.806406) (xy 57.465344 -512.850875)
			(xy 57.515777 -512.901308) (xy 57.560246 -512.95707) (xy 57.598192 -513.017461) (xy 57.629137 -513.08172)
			(xy 57.652694 -513.14904) (xy 57.668564 -513.218575) (xy 57.67655 -513.289449) (xy 57.67655 -513.360771)
			(xy 58.938406 -513.360771) (xy 58.938406 -513.289449) (xy 58.946392 -513.218575) (xy 58.962262 -513.14904)
			(xy 58.985819 -513.08172) (xy 59.016764 -513.017461) (xy 59.05471 -512.95707) (xy 59.099179 -512.901308)
			(xy 59.149612 -512.850875) (xy 59.205374 -512.806406) (xy 59.265765 -512.76846) (xy 59.330024 -512.737515)
			(xy 59.397344 -512.713958) (xy 59.466879 -512.698088) (xy 59.537753 -512.690102) (xy 59.573414 -512.689602)
			(xy 59.609075 -512.690102) (xy 59.679949 -512.698088) (xy 59.749484 -512.713958) (xy 59.816804 -512.737515)
			(xy 59.881063 -512.76846) (xy 59.941454 -512.806406) (xy 59.997216 -512.850875) (xy 60.047649 -512.901308)
			(xy 60.092118 -512.95707) (xy 60.130064 -513.017461) (xy 60.161009 -513.08172) (xy 60.184566 -513.14904)
			(xy 60.200436 -513.218575) (xy 60.208422 -513.289449) (xy 60.208422 -513.360771) (xy 61.74282 -513.360771)
			(xy 61.74282 -513.289449) (xy 61.750806 -513.218575) (xy 61.766676 -513.14904) (xy 61.790233 -513.08172)
			(xy 61.821178 -513.017461) (xy 61.859124 -512.95707) (xy 61.903593 -512.901308) (xy 61.954026 -512.850875)
			(xy 62.009788 -512.806406) (xy 62.070179 -512.76846) (xy 62.134438 -512.737515) (xy 62.201758 -512.713958)
			(xy 62.271293 -512.698088) (xy 62.342167 -512.690102) (xy 62.377828 -512.689602) (xy 62.413489 -512.690102)
			(xy 62.484363 -512.698088) (xy 62.553898 -512.713958) (xy 62.621218 -512.737515) (xy 62.685477 -512.76846)
			(xy 62.745868 -512.806406) (xy 62.80163 -512.850875) (xy 62.852063 -512.901308) (xy 62.896532 -512.95707)
			(xy 62.934478 -513.017461) (xy 62.965423 -513.08172) (xy 62.98898 -513.14904) (xy 63.00485 -513.218575)
			(xy 63.012836 -513.289449) (xy 63.012836 -513.360771) (xy 64.98259 -513.360771) (xy 64.98259 -513.289449)
			(xy 64.990576 -513.218575) (xy 65.006446 -513.14904) (xy 65.030003 -513.08172) (xy 65.060948 -513.017461)
			(xy 65.098894 -512.95707) (xy 65.143363 -512.901308) (xy 65.193796 -512.850875) (xy 65.249558 -512.806406)
			(xy 65.309949 -512.76846) (xy 65.374208 -512.737515) (xy 65.441528 -512.713958) (xy 65.511063 -512.698088)
			(xy 65.581937 -512.690102) (xy 65.617598 -512.689602) (xy 65.653259 -512.690102) (xy 65.724133 -512.698088)
			(xy 65.793668 -512.713958) (xy 65.860988 -512.737515) (xy 65.925247 -512.76846) (xy 65.985638 -512.806406)
			(xy 66.0414 -512.850875) (xy 66.091833 -512.901308) (xy 66.136302 -512.95707) (xy 66.174248 -513.017461)
			(xy 66.205193 -513.08172) (xy 66.22875 -513.14904) (xy 66.24462 -513.218575) (xy 66.252606 -513.289449)
			(xy 66.252606 -513.360771) (xy 67.974202 -513.360771) (xy 67.974202 -513.289449) (xy 67.982188 -513.218575)
			(xy 67.998058 -513.14904) (xy 68.021615 -513.08172) (xy 68.05256 -513.017461) (xy 68.090506 -512.95707)
			(xy 68.134975 -512.901308) (xy 68.185408 -512.850875) (xy 68.24117 -512.806406) (xy 68.301561 -512.76846)
			(xy 68.36582 -512.737515) (xy 68.43314 -512.713958) (xy 68.502675 -512.698088) (xy 68.573549 -512.690102)
			(xy 68.60921 -512.689602) (xy 68.644871 -512.690102) (xy 68.715745 -512.698088) (xy 68.78528 -512.713958)
			(xy 68.8526 -512.737515) (xy 68.916859 -512.76846) (xy 68.97725 -512.806406) (xy 69.033012 -512.850875)
			(xy 69.083445 -512.901308) (xy 69.127914 -512.95707) (xy 69.16586 -513.017461) (xy 69.196805 -513.08172)
			(xy 69.220362 -513.14904) (xy 69.236232 -513.218575) (xy 69.244218 -513.289449) (xy 69.244218 -513.360771)
			(xy 69.236232 -513.431645) (xy 69.220362 -513.50118) (xy 69.196805 -513.5685) (xy 69.16586 -513.632759)
			(xy 69.127914 -513.69315) (xy 69.083445 -513.748912) (xy 69.033012 -513.799345) (xy 68.97725 -513.843814)
			(xy 68.916859 -513.88176) (xy 68.8526 -513.912705) (xy 68.78528 -513.936262) (xy 68.715745 -513.952132)
			(xy 68.644871 -513.960118) (xy 68.573549 -513.960118) (xy 68.502675 -513.952132) (xy 68.43314 -513.936262)
			(xy 68.36582 -513.912705) (xy 68.301561 -513.88176) (xy 68.24117 -513.843814) (xy 68.185408 -513.799345)
			(xy 68.134975 -513.748912) (xy 68.090506 -513.69315) (xy 68.05256 -513.632759) (xy 68.021615 -513.5685)
			(xy 67.998058 -513.50118) (xy 67.982188 -513.431645) (xy 67.974202 -513.360771) (xy 66.252606 -513.360771)
			(xy 66.24462 -513.431645) (xy 66.22875 -513.50118) (xy 66.205193 -513.5685) (xy 66.174248 -513.632759)
			(xy 66.136302 -513.69315) (xy 66.091833 -513.748912) (xy 66.0414 -513.799345) (xy 65.985638 -513.843814)
			(xy 65.925247 -513.88176) (xy 65.860988 -513.912705) (xy 65.793668 -513.936262) (xy 65.724133 -513.952132)
			(xy 65.653259 -513.960118) (xy 65.581937 -513.960118) (xy 65.511063 -513.952132) (xy 65.441528 -513.936262)
			(xy 65.374208 -513.912705) (xy 65.309949 -513.88176) (xy 65.249558 -513.843814) (xy 65.193796 -513.799345)
			(xy 65.143363 -513.748912) (xy 65.098894 -513.69315) (xy 65.060948 -513.632759) (xy 65.030003 -513.5685)
			(xy 65.006446 -513.50118) (xy 64.990576 -513.431645) (xy 64.98259 -513.360771) (xy 63.012836 -513.360771)
			(xy 63.00485 -513.431645) (xy 62.98898 -513.50118) (xy 62.965423 -513.5685) (xy 62.934478 -513.632759)
			(xy 62.896532 -513.69315) (xy 62.852063 -513.748912) (xy 62.80163 -513.799345) (xy 62.745868 -513.843814)
			(xy 62.685477 -513.88176) (xy 62.621218 -513.912705) (xy 62.553898 -513.936262) (xy 62.484363 -513.952132)
			(xy 62.413489 -513.960118) (xy 62.342167 -513.960118) (xy 62.271293 -513.952132) (xy 62.201758 -513.936262)
			(xy 62.134438 -513.912705) (xy 62.070179 -513.88176) (xy 62.009788 -513.843814) (xy 61.954026 -513.799345)
			(xy 61.903593 -513.748912) (xy 61.859124 -513.69315) (xy 61.821178 -513.632759) (xy 61.790233 -513.5685)
			(xy 61.766676 -513.50118) (xy 61.750806 -513.431645) (xy 61.74282 -513.360771) (xy 60.208422 -513.360771)
			(xy 60.200436 -513.431645) (xy 60.184566 -513.50118) (xy 60.161009 -513.5685) (xy 60.130064 -513.632759)
			(xy 60.092118 -513.69315) (xy 60.047649 -513.748912) (xy 59.997216 -513.799345) (xy 59.941454 -513.843814)
			(xy 59.881063 -513.88176) (xy 59.816804 -513.912705) (xy 59.749484 -513.936262) (xy 59.679949 -513.952132)
			(xy 59.609075 -513.960118) (xy 59.537753 -513.960118) (xy 59.466879 -513.952132) (xy 59.397344 -513.936262)
			(xy 59.330024 -513.912705) (xy 59.265765 -513.88176) (xy 59.205374 -513.843814) (xy 59.149612 -513.799345)
			(xy 59.099179 -513.748912) (xy 59.05471 -513.69315) (xy 59.016764 -513.632759) (xy 58.985819 -513.5685)
			(xy 58.962262 -513.50118) (xy 58.946392 -513.431645) (xy 58.938406 -513.360771) (xy 57.67655 -513.360771)
			(xy 57.668564 -513.431645) (xy 57.652694 -513.50118) (xy 57.629137 -513.5685) (xy 57.598192 -513.632759)
			(xy 57.560246 -513.69315) (xy 57.515777 -513.748912) (xy 57.465344 -513.799345) (xy 57.409582 -513.843814)
			(xy 57.349191 -513.88176) (xy 57.284932 -513.912705) (xy 57.217612 -513.936262) (xy 57.148077 -513.952132)
			(xy 57.077203 -513.960118) (xy 57.005881 -513.960118) (xy 56.935007 -513.952132) (xy 56.865472 -513.936262)
			(xy 56.798152 -513.912705) (xy 56.733893 -513.88176) (xy 56.673502 -513.843814) (xy 56.61774 -513.799345)
			(xy 56.567307 -513.748912) (xy 56.522838 -513.69315) (xy 56.484892 -513.632759) (xy 56.453947 -513.5685)
			(xy 56.43039 -513.50118) (xy 56.41452 -513.431645) (xy 56.406534 -513.360771) (xy 36.131362 -513.360771)
			(xy 36.071366 -513.406078) (xy 35.997482 -513.451825) (xy 35.919693 -513.490559) (xy 35.838661 -513.521951)
			(xy 35.755079 -513.545732) (xy 35.669659 -513.5617) (xy 35.58313 -513.569718) (xy 35.49623 -513.569718)
			(xy 35.409701 -513.5617) (xy 35.324281 -513.545732) (xy 35.240699 -513.521951) (xy 35.159667 -513.490559)
			(xy 35.081878 -513.451825) (xy 35.007994 -513.406078) (xy 34.938647 -513.353709) (xy 34.874427 -513.295165)
			(xy 34.815883 -513.230945) (xy 34.763514 -513.161598) (xy 34.717767 -513.087714) (xy 34.679033 -513.009925)
			(xy 34.647641 -512.928893) (xy 34.62386 -512.845311) (xy 34.607892 -512.759891) (xy 34.599874 -512.673362)
			(xy 31.399486 -512.673362) (xy 31.391468 -512.759891) (xy 31.3755 -512.845311) (xy 31.351719 -512.928893)
			(xy 31.320327 -513.009925) (xy 31.281593 -513.087714) (xy 31.235846 -513.161598) (xy 31.183477 -513.230945)
			(xy 31.124933 -513.295165) (xy 31.060713 -513.353709) (xy 30.991366 -513.406078) (xy 30.917482 -513.451825)
			(xy 30.839693 -513.490559) (xy 30.758661 -513.521951) (xy 30.675079 -513.545732) (xy 30.589659 -513.5617)
			(xy 30.50313 -513.569718) (xy 30.41623 -513.569718) (xy 30.329701 -513.5617) (xy 30.244281 -513.545732)
			(xy 30.160699 -513.521951) (xy 30.079667 -513.490559) (xy 30.001878 -513.451825) (xy 29.927994 -513.406078)
			(xy 29.858647 -513.353709) (xy 29.794427 -513.295165) (xy 29.735883 -513.230945) (xy 29.683514 -513.161598)
			(xy 29.637767 -513.087714) (xy 29.599033 -513.009925) (xy 29.567641 -512.928893) (xy 29.54386 -512.845311)
			(xy 29.527892 -512.759891) (xy 29.519874 -512.673362) (xy 0.509016 -512.673362) (xy 0.509016 -514.804305)
			(xy 1.150876 -514.804305) (xy 1.152892 -514.674692) (xy 1.162962 -514.545456) (xy 1.181047 -514.417095)
			(xy 1.207077 -514.290107) (xy 1.240952 -514.164983) (xy 1.28254 -514.042207) (xy 1.331681 -513.922254)
			(xy 1.388184 -513.805589) (xy 1.451831 -513.692661) (xy 1.522375 -513.583909) (xy 1.599544 -513.479753)
			(xy 1.683039 -513.380596) (xy 1.772537 -513.286822) (xy 1.867692 -513.198793) (xy 1.968135 -513.11685)
			(xy 2.073478 -513.041311) (xy 2.183314 -512.972466) (xy 2.297218 -512.910583) (xy 2.414748 -512.855902)
			(xy 2.535451 -512.808632) (xy 2.658859 -512.768959) (xy 2.784495 -512.737034) (xy 2.911872 -512.712982)
			(xy 3.040498 -512.696895) (xy 3.169876 -512.688836) (xy 3.23469 -512.688332) (xy 3.299504 -512.688836)
			(xy 3.428882 -512.696895) (xy 3.557508 -512.712982) (xy 3.684885 -512.737034) (xy 3.810521 -512.768959)
			(xy 3.933929 -512.808632) (xy 4.054632 -512.855902) (xy 4.172162 -512.910583) (xy 4.286066 -512.972466)
			(xy 4.395902 -513.041311) (xy 4.501245 -513.11685) (xy 4.601688 -513.198793) (xy 4.696843 -513.286822)
			(xy 4.786341 -513.380596) (xy 4.869836 -513.479753) (xy 4.947005 -513.583909) (xy 5.017549 -513.692661)
			(xy 5.081196 -513.805589) (xy 5.137699 -513.922254) (xy 5.18684 -514.042207) (xy 5.228428 -514.164983)
			(xy 5.262303 -514.290107) (xy 5.288333 -514.417095) (xy 5.306418 -514.545456) (xy 5.316488 -514.674692)
			(xy 5.318504 -514.804305) (xy 12.580876 -514.804305) (xy 12.582892 -514.674692) (xy 12.592962 -514.545456)
			(xy 12.611047 -514.417095) (xy 12.637077 -514.290107) (xy 12.670952 -514.164983) (xy 12.71254 -514.042207)
			(xy 12.761681 -513.922254) (xy 12.818184 -513.805589) (xy 12.881831 -513.692661) (xy 12.952375 -513.583909)
			(xy 13.029544 -513.479753) (xy 13.113039 -513.380596) (xy 13.202537 -513.286822) (xy 13.297692 -513.198793)
			(xy 13.398135 -513.11685) (xy 13.503478 -513.041311) (xy 13.613314 -512.972466) (xy 13.727218 -512.910583)
			(xy 13.844748 -512.855902) (xy 13.965451 -512.808632) (xy 14.088859 -512.768959) (xy 14.214495 -512.737034)
			(xy 14.341872 -512.712982) (xy 14.470498 -512.696895) (xy 14.599876 -512.688836) (xy 14.66469 -512.688332)
			(xy 14.729504 -512.688836) (xy 14.858882 -512.696895) (xy 14.987508 -512.712982) (xy 15.114885 -512.737034)
			(xy 15.240521 -512.768959) (xy 15.363929 -512.808632) (xy 15.484632 -512.855902) (xy 15.602162 -512.910583)
			(xy 15.716066 -512.972466) (xy 15.825902 -513.041311) (xy 15.931245 -513.11685) (xy 16.031688 -513.198793)
			(xy 16.126843 -513.286822) (xy 16.216341 -513.380596) (xy 16.299836 -513.479753) (xy 16.377005 -513.583909)
			(xy 16.447549 -513.692661) (xy 16.511196 -513.805589) (xy 16.567699 -513.922254) (xy 16.61684 -514.042207)
			(xy 16.658428 -514.164983) (xy 16.692303 -514.290107) (xy 16.718333 -514.417095) (xy 16.736418 -514.545456)
			(xy 16.746488 -514.674692) (xy 16.748504 -514.804305) (xy 16.742458 -514.933792) (xy 16.728374 -515.062653)
			(xy 16.706305 -515.190389) (xy 16.700846 -515.213362) (xy 29.519874 -515.213362) (xy 29.519874 -515.126462)
			(xy 29.527892 -515.039933) (xy 29.54386 -514.954513) (xy 29.567641 -514.870931) (xy 29.599033 -514.789899)
			(xy 29.637767 -514.71211) (xy 29.683514 -514.638226) (xy 29.735883 -514.568879) (xy 29.794427 -514.504659)
			(xy 29.858647 -514.446115) (xy 29.927994 -514.393746) (xy 30.001878 -514.347999) (xy 30.079667 -514.309265)
			(xy 30.160699 -514.277873) (xy 30.244281 -514.254092) (xy 30.329701 -514.238124) (xy 30.41623 -514.230106)
			(xy 30.45968 -514.229604) (xy 30.50313 -514.230106) (xy 30.589659 -514.238124) (xy 30.675079 -514.254092)
			(xy 30.758661 -514.277873) (xy 30.839693 -514.309265) (xy 30.917482 -514.347999) (xy 30.991366 -514.393746)
			(xy 31.060713 -514.446115) (xy 31.124933 -514.504659) (xy 31.183477 -514.568879) (xy 31.235846 -514.638226)
			(xy 31.281593 -514.71211) (xy 31.320327 -514.789899) (xy 31.351719 -514.870931) (xy 31.3755 -514.954513)
			(xy 31.391468 -515.039933) (xy 31.399486 -515.126462) (xy 31.399486 -515.213362) (xy 34.599874 -515.213362)
			(xy 34.599874 -515.126462) (xy 34.607892 -515.039933) (xy 34.62386 -514.954513) (xy 34.647641 -514.870931)
			(xy 34.679033 -514.789899) (xy 34.717767 -514.71211) (xy 34.763514 -514.638226) (xy 34.815883 -514.568879)
			(xy 34.874427 -514.504659) (xy 34.938647 -514.446115) (xy 35.007994 -514.393746) (xy 35.081878 -514.347999)
			(xy 35.159667 -514.309265) (xy 35.240699 -514.277873) (xy 35.324281 -514.254092) (xy 35.409701 -514.238124)
			(xy 35.49623 -514.230106) (xy 35.53968 -514.229604) (xy 35.58313 -514.230106) (xy 35.669659 -514.238124)
			(xy 35.755079 -514.254092) (xy 35.838661 -514.277873) (xy 35.919693 -514.309265) (xy 35.997482 -514.347999)
			(xy 36.071366 -514.393746) (xy 36.140713 -514.446115) (xy 36.204933 -514.504659) (xy 36.263477 -514.568879)
			(xy 36.315846 -514.638226) (xy 36.361593 -514.71211) (xy 36.400327 -514.789899) (xy 36.431719 -514.870931)
			(xy 36.4555 -514.954513) (xy 36.471468 -515.039933) (xy 36.479486 -515.126462) (xy 36.479486 -515.213362)
			(xy 36.471468 -515.299891) (xy 36.4555 -515.385311) (xy 36.431719 -515.468893) (xy 36.400327 -515.549925)
			(xy 36.361593 -515.627714) (xy 36.315846 -515.701598) (xy 36.263477 -515.770945) (xy 36.204933 -515.835165)
			(xy 36.140713 -515.893709) (xy 36.071366 -515.946078) (xy 35.997482 -515.991825) (xy 35.919693 -516.030559)
			(xy 35.917055 -516.031581) (xy 56.406534 -516.031581) (xy 56.406534 -515.960259) (xy 56.41452 -515.889385)
			(xy 56.43039 -515.81985) (xy 56.453947 -515.75253) (xy 56.484892 -515.688271) (xy 56.522838 -515.62788)
			(xy 56.567307 -515.572118) (xy 56.61774 -515.521685) (xy 56.673502 -515.477216) (xy 56.733893 -515.43927)
			(xy 56.798152 -515.408325) (xy 56.865472 -515.384768) (xy 56.935007 -515.368898) (xy 57.005881 -515.360912)
			(xy 57.041542 -515.360412) (xy 57.077203 -515.360912) (xy 57.148077 -515.368898) (xy 57.217612 -515.384768)
			(xy 57.284932 -515.408325) (xy 57.349191 -515.43927) (xy 57.409582 -515.477216) (xy 57.465344 -515.521685)
			(xy 57.515777 -515.572118) (xy 57.560246 -515.62788) (xy 57.598192 -515.688271) (xy 57.629137 -515.75253)
			(xy 57.652694 -515.81985) (xy 57.668564 -515.889385) (xy 57.67655 -515.960259) (xy 57.67655 -516.031581)
			(xy 58.938406 -516.031581) (xy 58.938406 -515.960259) (xy 58.946392 -515.889385) (xy 58.962262 -515.81985)
			(xy 58.985819 -515.75253) (xy 59.016764 -515.688271) (xy 59.05471 -515.62788) (xy 59.099179 -515.572118)
			(xy 59.149612 -515.521685) (xy 59.205374 -515.477216) (xy 59.265765 -515.43927) (xy 59.330024 -515.408325)
			(xy 59.397344 -515.384768) (xy 59.466879 -515.368898) (xy 59.537753 -515.360912) (xy 59.573414 -515.360412)
			(xy 59.609075 -515.360912) (xy 59.679949 -515.368898) (xy 59.749484 -515.384768) (xy 59.816804 -515.408325)
			(xy 59.881063 -515.43927) (xy 59.941454 -515.477216) (xy 59.997216 -515.521685) (xy 60.047649 -515.572118)
			(xy 60.092118 -515.62788) (xy 60.130064 -515.688271) (xy 60.161009 -515.75253) (xy 60.184566 -515.81985)
			(xy 60.200436 -515.889385) (xy 60.208422 -515.960259) (xy 60.208422 -516.031581) (xy 61.74282 -516.031581)
			(xy 61.74282 -515.960259) (xy 61.750806 -515.889385) (xy 61.766676 -515.81985) (xy 61.790233 -515.75253)
			(xy 61.821178 -515.688271) (xy 61.859124 -515.62788) (xy 61.903593 -515.572118) (xy 61.954026 -515.521685)
			(xy 62.009788 -515.477216) (xy 62.070179 -515.43927) (xy 62.134438 -515.408325) (xy 62.201758 -515.384768)
			(xy 62.271293 -515.368898) (xy 62.342167 -515.360912) (xy 62.377828 -515.360412) (xy 62.413489 -515.360912)
			(xy 62.484363 -515.368898) (xy 62.553898 -515.384768) (xy 62.621218 -515.408325) (xy 62.685477 -515.43927)
			(xy 62.745868 -515.477216) (xy 62.80163 -515.521685) (xy 62.852063 -515.572118) (xy 62.896532 -515.62788)
			(xy 62.934478 -515.688271) (xy 62.965423 -515.75253) (xy 62.98898 -515.81985) (xy 63.00485 -515.889385)
			(xy 63.012836 -515.960259) (xy 63.012836 -516.031581) (xy 64.98259 -516.031581) (xy 64.98259 -515.960259)
			(xy 64.990576 -515.889385) (xy 65.006446 -515.81985) (xy 65.030003 -515.75253) (xy 65.060948 -515.688271)
			(xy 65.098894 -515.62788) (xy 65.143363 -515.572118) (xy 65.193796 -515.521685) (xy 65.249558 -515.477216)
			(xy 65.309949 -515.43927) (xy 65.374208 -515.408325) (xy 65.441528 -515.384768) (xy 65.511063 -515.368898)
			(xy 65.581937 -515.360912) (xy 65.617598 -515.360412) (xy 65.653259 -515.360912) (xy 65.724133 -515.368898)
			(xy 65.793668 -515.384768) (xy 65.860988 -515.408325) (xy 65.925247 -515.43927) (xy 65.985638 -515.477216)
			(xy 66.0414 -515.521685) (xy 66.091833 -515.572118) (xy 66.136302 -515.62788) (xy 66.174248 -515.688271)
			(xy 66.205193 -515.75253) (xy 66.22875 -515.81985) (xy 66.24462 -515.889385) (xy 66.252606 -515.960259)
			(xy 66.252606 -516.031581) (xy 67.974202 -516.031581) (xy 67.974202 -515.960259) (xy 67.982188 -515.889385)
			(xy 67.998058 -515.81985) (xy 68.021615 -515.75253) (xy 68.05256 -515.688271) (xy 68.090506 -515.62788)
			(xy 68.134975 -515.572118) (xy 68.185408 -515.521685) (xy 68.24117 -515.477216) (xy 68.301561 -515.43927)
			(xy 68.36582 -515.408325) (xy 68.43314 -515.384768) (xy 68.502675 -515.368898) (xy 68.573549 -515.360912)
			(xy 68.60921 -515.360412) (xy 68.644871 -515.360912) (xy 68.715745 -515.368898) (xy 68.78528 -515.384768)
			(xy 68.8526 -515.408325) (xy 68.916859 -515.43927) (xy 68.97725 -515.477216) (xy 69.033012 -515.521685)
			(xy 69.083445 -515.572118) (xy 69.127914 -515.62788) (xy 69.16586 -515.688271) (xy 69.196805 -515.75253)
			(xy 69.220362 -515.81985) (xy 69.236232 -515.889385) (xy 69.244218 -515.960259) (xy 69.244218 -516.031581)
			(xy 69.236232 -516.102455) (xy 69.220362 -516.17199) (xy 69.196805 -516.23931) (xy 69.16586 -516.303569)
			(xy 69.127914 -516.36396) (xy 69.083445 -516.419722) (xy 69.033012 -516.470155) (xy 68.97725 -516.514624)
			(xy 68.916859 -516.55257) (xy 68.8526 -516.583515) (xy 68.78528 -516.607072) (xy 68.715745 -516.622942)
			(xy 68.644871 -516.630928) (xy 68.573549 -516.630928) (xy 68.502675 -516.622942) (xy 68.43314 -516.607072)
			(xy 68.36582 -516.583515) (xy 68.301561 -516.55257) (xy 68.24117 -516.514624) (xy 68.185408 -516.470155)
			(xy 68.134975 -516.419722) (xy 68.090506 -516.36396) (xy 68.05256 -516.303569) (xy 68.021615 -516.23931)
			(xy 67.998058 -516.17199) (xy 67.982188 -516.102455) (xy 67.974202 -516.031581) (xy 66.252606 -516.031581)
			(xy 66.24462 -516.102455) (xy 66.22875 -516.17199) (xy 66.205193 -516.23931) (xy 66.174248 -516.303569)
			(xy 66.136302 -516.36396) (xy 66.091833 -516.419722) (xy 66.0414 -516.470155) (xy 65.985638 -516.514624)
			(xy 65.925247 -516.55257) (xy 65.860988 -516.583515) (xy 65.793668 -516.607072) (xy 65.724133 -516.622942)
			(xy 65.653259 -516.630928) (xy 65.581937 -516.630928) (xy 65.511063 -516.622942) (xy 65.441528 -516.607072)
			(xy 65.374208 -516.583515) (xy 65.309949 -516.55257) (xy 65.249558 -516.514624) (xy 65.193796 -516.470155)
			(xy 65.143363 -516.419722) (xy 65.098894 -516.36396) (xy 65.060948 -516.303569) (xy 65.030003 -516.23931)
			(xy 65.006446 -516.17199) (xy 64.990576 -516.102455) (xy 64.98259 -516.031581) (xy 63.012836 -516.031581)
			(xy 63.00485 -516.102455) (xy 62.98898 -516.17199) (xy 62.965423 -516.23931) (xy 62.934478 -516.303569)
			(xy 62.896532 -516.36396) (xy 62.852063 -516.419722) (xy 62.80163 -516.470155) (xy 62.745868 -516.514624)
			(xy 62.685477 -516.55257) (xy 62.621218 -516.583515) (xy 62.553898 -516.607072) (xy 62.484363 -516.622942)
			(xy 62.413489 -516.630928) (xy 62.342167 -516.630928) (xy 62.271293 -516.622942) (xy 62.201758 -516.607072)
			(xy 62.134438 -516.583515) (xy 62.070179 -516.55257) (xy 62.009788 -516.514624) (xy 61.954026 -516.470155)
			(xy 61.903593 -516.419722) (xy 61.859124 -516.36396) (xy 61.821178 -516.303569) (xy 61.790233 -516.23931)
			(xy 61.766676 -516.17199) (xy 61.750806 -516.102455) (xy 61.74282 -516.031581) (xy 60.208422 -516.031581)
			(xy 60.200436 -516.102455) (xy 60.184566 -516.17199) (xy 60.161009 -516.23931) (xy 60.130064 -516.303569)
			(xy 60.092118 -516.36396) (xy 60.047649 -516.419722) (xy 59.997216 -516.470155) (xy 59.941454 -516.514624)
			(xy 59.881063 -516.55257) (xy 59.816804 -516.583515) (xy 59.749484 -516.607072) (xy 59.679949 -516.622942)
			(xy 59.609075 -516.630928) (xy 59.537753 -516.630928) (xy 59.466879 -516.622942) (xy 59.397344 -516.607072)
			(xy 59.330024 -516.583515) (xy 59.265765 -516.55257) (xy 59.205374 -516.514624) (xy 59.149612 -516.470155)
			(xy 59.099179 -516.419722) (xy 59.05471 -516.36396) (xy 59.016764 -516.303569) (xy 58.985819 -516.23931)
			(xy 58.962262 -516.17199) (xy 58.946392 -516.102455) (xy 58.938406 -516.031581) (xy 57.67655 -516.031581)
			(xy 57.668564 -516.102455) (xy 57.652694 -516.17199) (xy 57.629137 -516.23931) (xy 57.598192 -516.303569)
			(xy 57.560246 -516.36396) (xy 57.515777 -516.419722) (xy 57.465344 -516.470155) (xy 57.409582 -516.514624)
			(xy 57.349191 -516.55257) (xy 57.284932 -516.583515) (xy 57.217612 -516.607072) (xy 57.148077 -516.622942)
			(xy 57.077203 -516.630928) (xy 57.005881 -516.630928) (xy 56.935007 -516.622942) (xy 56.865472 -516.607072)
			(xy 56.798152 -516.583515) (xy 56.733893 -516.55257) (xy 56.673502 -516.514624) (xy 56.61774 -516.470155)
			(xy 56.567307 -516.419722) (xy 56.522838 -516.36396) (xy 56.484892 -516.303569) (xy 56.453947 -516.23931)
			(xy 56.43039 -516.17199) (xy 56.41452 -516.102455) (xy 56.406534 -516.031581) (xy 35.917055 -516.031581)
			(xy 35.838661 -516.061951) (xy 35.755079 -516.085732) (xy 35.669659 -516.1017) (xy 35.58313 -516.109718)
			(xy 35.49623 -516.109718) (xy 35.409701 -516.1017) (xy 35.324281 -516.085732) (xy 35.240699 -516.061951)
			(xy 35.159667 -516.030559) (xy 35.081878 -515.991825) (xy 35.007994 -515.946078) (xy 34.938647 -515.893709)
			(xy 34.874427 -515.835165) (xy 34.815883 -515.770945) (xy 34.763514 -515.701598) (xy 34.717767 -515.627714)
			(xy 34.679033 -515.549925) (xy 34.647641 -515.468893) (xy 34.62386 -515.385311) (xy 34.607892 -515.299891)
			(xy 34.599874 -515.213362) (xy 31.399486 -515.213362) (xy 31.391468 -515.299891) (xy 31.3755 -515.385311)
			(xy 31.351719 -515.468893) (xy 31.320327 -515.549925) (xy 31.281593 -515.627714) (xy 31.235846 -515.701598)
			(xy 31.183477 -515.770945) (xy 31.124933 -515.835165) (xy 31.060713 -515.893709) (xy 30.991366 -515.946078)
			(xy 30.917482 -515.991825) (xy 30.839693 -516.030559) (xy 30.758661 -516.061951) (xy 30.675079 -516.085732)
			(xy 30.589659 -516.1017) (xy 30.50313 -516.109718) (xy 30.41623 -516.109718) (xy 30.329701 -516.1017)
			(xy 30.244281 -516.085732) (xy 30.160699 -516.061951) (xy 30.079667 -516.030559) (xy 30.001878 -515.991825)
			(xy 29.927994 -515.946078) (xy 29.858647 -515.893709) (xy 29.794427 -515.835165) (xy 29.735883 -515.770945)
			(xy 29.683514 -515.701598) (xy 29.637767 -515.627714) (xy 29.599033 -515.549925) (xy 29.567641 -515.468893)
			(xy 29.54386 -515.385311) (xy 29.527892 -515.299891) (xy 29.519874 -515.213362) (xy 16.700846 -515.213362)
			(xy 16.676338 -515.316506) (xy 16.638589 -515.440516) (xy 16.593202 -515.561939) (xy 16.540355 -515.680306)
			(xy 16.480251 -515.795158) (xy 16.413123 -515.906051) (xy 16.339231 -516.012557) (xy 16.25886 -516.114263)
			(xy 16.172322 -516.210775) (xy 16.07995 -516.30172) (xy 15.982104 -516.386747) (xy 15.879161 -516.465527)
			(xy 15.771519 -516.537754) (xy 15.659595 -516.603149) (xy 15.543822 -516.66146) (xy 15.424648 -516.71246)
			(xy 15.302534 -516.755952) (xy 15.177951 -516.791769) (xy 15.051384 -516.819771) (xy 14.92332 -516.83985)
			(xy 14.794256 -516.851929) (xy 14.66469 -516.85596) (xy 14.535124 -516.851929) (xy 14.40606 -516.83985)
			(xy 14.277996 -516.819771) (xy 14.151429 -516.791769) (xy 14.026846 -516.755952) (xy 13.904732 -516.71246)
			(xy 13.785558 -516.66146) (xy 13.669785 -516.603149) (xy 13.557861 -516.537754) (xy 13.450219 -516.465527)
			(xy 13.347276 -516.386747) (xy 13.24943 -516.30172) (xy 13.157058 -516.210775) (xy 13.07052 -516.114263)
			(xy 12.990149 -516.012557) (xy 12.916257 -515.906051) (xy 12.849129 -515.795158) (xy 12.789025 -515.680306)
			(xy 12.736178 -515.561939) (xy 12.690791 -515.440516) (xy 12.653042 -515.316506) (xy 12.623075 -515.190389)
			(xy 12.601006 -515.062653) (xy 12.586922 -514.933792) (xy 12.580876 -514.804305) (xy 5.318504 -514.804305)
			(xy 5.312458 -514.933792) (xy 5.298374 -515.062653) (xy 5.276305 -515.190389) (xy 5.246338 -515.316506)
			(xy 5.208589 -515.440516) (xy 5.163202 -515.561939) (xy 5.110355 -515.680306) (xy 5.050251 -515.795158)
			(xy 4.983123 -515.906051) (xy 4.909231 -516.012557) (xy 4.82886 -516.114263) (xy 4.742322 -516.210775)
			(xy 4.64995 -516.30172) (xy 4.552104 -516.386747) (xy 4.449161 -516.465527) (xy 4.341519 -516.537754)
			(xy 4.229595 -516.603149) (xy 4.113822 -516.66146) (xy 3.994648 -516.71246) (xy 3.872534 -516.755952)
			(xy 3.747951 -516.791769) (xy 3.621384 -516.819771) (xy 3.49332 -516.83985) (xy 3.364256 -516.851929)
			(xy 3.23469 -516.85596) (xy 3.105124 -516.851929) (xy 2.97606 -516.83985) (xy 2.847996 -516.819771)
			(xy 2.721429 -516.791769) (xy 2.596846 -516.755952) (xy 2.474732 -516.71246) (xy 2.355558 -516.66146)
			(xy 2.239785 -516.603149) (xy 2.127861 -516.537754) (xy 2.020219 -516.465527) (xy 1.917276 -516.386747)
			(xy 1.81943 -516.30172) (xy 1.727058 -516.210775) (xy 1.64052 -516.114263) (xy 1.560149 -516.012557)
			(xy 1.486257 -515.906051) (xy 1.419129 -515.795158) (xy 1.359025 -515.680306) (xy 1.306178 -515.561939)
			(xy 1.260791 -515.440516) (xy 1.223042 -515.316506) (xy 1.193075 -515.190389) (xy 1.171006 -515.062653)
			(xy 1.156922 -514.933792) (xy 1.150876 -514.804305) (xy 0.509016 -514.804305) (xy 0.509016 -517.753362)
			(xy 29.519874 -517.753362) (xy 29.519874 -517.666462) (xy 29.527892 -517.579933) (xy 29.54386 -517.494513)
			(xy 29.567641 -517.410931) (xy 29.599033 -517.329899) (xy 29.637767 -517.25211) (xy 29.683514 -517.178226)
			(xy 29.735883 -517.108879) (xy 29.794427 -517.044659) (xy 29.858647 -516.986115) (xy 29.927994 -516.933746)
			(xy 30.001878 -516.887999) (xy 30.079667 -516.849265) (xy 30.160699 -516.817873) (xy 30.244281 -516.794092)
			(xy 30.329701 -516.778124) (xy 30.41623 -516.770106) (xy 30.45968 -516.769604) (xy 30.50313 -516.770106)
			(xy 30.589659 -516.778124) (xy 30.675079 -516.794092) (xy 30.758661 -516.817873) (xy 30.839693 -516.849265)
			(xy 30.917482 -516.887999) (xy 30.991366 -516.933746) (xy 31.060713 -516.986115) (xy 31.124933 -517.044659)
			(xy 31.183477 -517.108879) (xy 31.235846 -517.178226) (xy 31.281593 -517.25211) (xy 31.320327 -517.329899)
			(xy 31.351719 -517.410931) (xy 31.3755 -517.494513) (xy 31.391468 -517.579933) (xy 31.399486 -517.666462)
			(xy 31.399486 -517.753362) (xy 34.599874 -517.753362) (xy 34.599874 -517.666462) (xy 34.607892 -517.579933)
			(xy 34.62386 -517.494513) (xy 34.647641 -517.410931) (xy 34.679033 -517.329899) (xy 34.717767 -517.25211)
			(xy 34.763514 -517.178226) (xy 34.815883 -517.108879) (xy 34.874427 -517.044659) (xy 34.938647 -516.986115)
			(xy 35.007994 -516.933746) (xy 35.081878 -516.887999) (xy 35.159667 -516.849265) (xy 35.240699 -516.817873)
			(xy 35.324281 -516.794092) (xy 35.409701 -516.778124) (xy 35.49623 -516.770106) (xy 35.53968 -516.769604)
			(xy 35.58313 -516.770106) (xy 35.669659 -516.778124) (xy 35.755079 -516.794092) (xy 35.838661 -516.817873)
			(xy 35.919693 -516.849265) (xy 35.997482 -516.887999) (xy 36.071366 -516.933746) (xy 36.140713 -516.986115)
			(xy 36.204933 -517.044659) (xy 36.263477 -517.108879) (xy 36.315846 -517.178226) (xy 36.361593 -517.25211)
			(xy 36.400327 -517.329899) (xy 36.431719 -517.410931) (xy 36.4555 -517.494513) (xy 36.471468 -517.579933)
			(xy 36.479486 -517.666462) (xy 36.479486 -517.753362) (xy 36.471468 -517.839891) (xy 36.4555 -517.925311)
			(xy 36.431719 -518.008893) (xy 36.400327 -518.089925) (xy 36.361593 -518.167714) (xy 36.344981 -518.194544)
			(xy 51.322732 -518.194544) (xy 52.974748 -518.194544) (xy 52.974748 -518.699851) (xy 56.406534 -518.699851)
			(xy 56.406534 -518.628529) (xy 56.41452 -518.557655) (xy 56.43039 -518.48812) (xy 56.453947 -518.4208)
			(xy 56.484892 -518.356541) (xy 56.522838 -518.29615) (xy 56.567307 -518.240388) (xy 56.61774 -518.189955)
			(xy 56.673502 -518.145486) (xy 56.733893 -518.10754) (xy 56.798152 -518.076595) (xy 56.865472 -518.053038)
			(xy 56.935007 -518.037168) (xy 57.005881 -518.029182) (xy 57.041542 -518.028682) (xy 57.077203 -518.029182)
			(xy 57.148077 -518.037168) (xy 57.217612 -518.053038) (xy 57.284932 -518.076595) (xy 57.349191 -518.10754)
			(xy 57.409582 -518.145486) (xy 57.465344 -518.189955) (xy 57.515777 -518.240388) (xy 57.560246 -518.29615)
			(xy 57.598192 -518.356541) (xy 57.629137 -518.4208) (xy 57.652694 -518.48812) (xy 57.668564 -518.557655)
			(xy 57.67655 -518.628529) (xy 57.67655 -518.699851) (xy 58.938406 -518.699851) (xy 58.938406 -518.628529)
			(xy 58.946392 -518.557655) (xy 58.962262 -518.48812) (xy 58.985819 -518.4208) (xy 59.016764 -518.356541)
			(xy 59.05471 -518.29615) (xy 59.099179 -518.240388) (xy 59.149612 -518.189955) (xy 59.205374 -518.145486)
			(xy 59.265765 -518.10754) (xy 59.330024 -518.076595) (xy 59.397344 -518.053038) (xy 59.466879 -518.037168)
			(xy 59.537753 -518.029182) (xy 59.573414 -518.028682) (xy 59.609075 -518.029182) (xy 59.679949 -518.037168)
			(xy 59.749484 -518.053038) (xy 59.816804 -518.076595) (xy 59.881063 -518.10754) (xy 59.941454 -518.145486)
			(xy 59.997216 -518.189955) (xy 60.047649 -518.240388) (xy 60.092118 -518.29615) (xy 60.130064 -518.356541)
			(xy 60.161009 -518.4208) (xy 60.184566 -518.48812) (xy 60.200436 -518.557655) (xy 60.208422 -518.628529)
			(xy 60.208422 -518.699851) (xy 61.74282 -518.699851) (xy 61.74282 -518.628529) (xy 61.750806 -518.557655)
			(xy 61.766676 -518.48812) (xy 61.790233 -518.4208) (xy 61.821178 -518.356541) (xy 61.859124 -518.29615)
			(xy 61.903593 -518.240388) (xy 61.954026 -518.189955) (xy 62.009788 -518.145486) (xy 62.070179 -518.10754)
			(xy 62.134438 -518.076595) (xy 62.201758 -518.053038) (xy 62.271293 -518.037168) (xy 62.342167 -518.029182)
			(xy 62.377828 -518.028682) (xy 62.413489 -518.029182) (xy 62.484363 -518.037168) (xy 62.553898 -518.053038)
			(xy 62.621218 -518.076595) (xy 62.685477 -518.10754) (xy 62.745868 -518.145486) (xy 62.80163 -518.189955)
			(xy 62.852063 -518.240388) (xy 62.896532 -518.29615) (xy 62.934478 -518.356541) (xy 62.965423 -518.4208)
			(xy 62.98898 -518.48812) (xy 63.00485 -518.557655) (xy 63.012836 -518.628529) (xy 63.012836 -518.699851)
			(xy 64.98259 -518.699851) (xy 64.98259 -518.628529) (xy 64.990576 -518.557655) (xy 65.006446 -518.48812)
			(xy 65.030003 -518.4208) (xy 65.060948 -518.356541) (xy 65.098894 -518.29615) (xy 65.143363 -518.240388)
			(xy 65.193796 -518.189955) (xy 65.249558 -518.145486) (xy 65.309949 -518.10754) (xy 65.374208 -518.076595)
			(xy 65.441528 -518.053038) (xy 65.511063 -518.037168) (xy 65.581937 -518.029182) (xy 65.617598 -518.028682)
			(xy 65.653259 -518.029182) (xy 65.724133 -518.037168) (xy 65.793668 -518.053038) (xy 65.860988 -518.076595)
			(xy 65.925247 -518.10754) (xy 65.985638 -518.145486) (xy 66.0414 -518.189955) (xy 66.091833 -518.240388)
			(xy 66.136302 -518.29615) (xy 66.174248 -518.356541) (xy 66.205193 -518.4208) (xy 66.22875 -518.48812)
			(xy 66.24462 -518.557655) (xy 66.252606 -518.628529) (xy 66.252606 -518.699851) (xy 67.974202 -518.699851)
			(xy 67.974202 -518.628529) (xy 67.982188 -518.557655) (xy 67.998058 -518.48812) (xy 68.021615 -518.4208)
			(xy 68.05256 -518.356541) (xy 68.090506 -518.29615) (xy 68.134975 -518.240388) (xy 68.185408 -518.189955)
			(xy 68.24117 -518.145486) (xy 68.301561 -518.10754) (xy 68.36582 -518.076595) (xy 68.43314 -518.053038)
			(xy 68.502675 -518.037168) (xy 68.573549 -518.029182) (xy 68.60921 -518.028682) (xy 68.644871 -518.029182)
			(xy 68.715745 -518.037168) (xy 68.78528 -518.053038) (xy 68.8526 -518.076595) (xy 68.916859 -518.10754)
			(xy 68.97725 -518.145486) (xy 69.033012 -518.189955) (xy 69.083445 -518.240388) (xy 69.127914 -518.29615)
			(xy 69.16586 -518.356541) (xy 69.196805 -518.4208) (xy 69.220362 -518.48812) (xy 69.236232 -518.557655)
			(xy 69.244218 -518.628529) (xy 69.244218 -518.699851) (xy 69.236232 -518.770725) (xy 69.220362 -518.84026)
			(xy 69.196805 -518.90758) (xy 69.16586 -518.971839) (xy 69.127914 -519.03223) (xy 69.083445 -519.087992)
			(xy 69.071384 -519.100053) (xy 72.999096 -519.100053) (xy 73.001098 -518.899925) (xy 73.011106 -518.700037)
			(xy 73.029103 -518.50071) (xy 73.055061 -518.302262) (xy 73.088938 -518.105012) (xy 73.13068 -517.909275)
			(xy 73.180219 -517.715365) (xy 73.237477 -517.523592) (xy 73.302362 -517.334263) (xy 73.37477 -517.147683)
			(xy 73.454586 -516.964148) (xy 73.54168 -516.783954) (xy 73.635914 -516.607389) (xy 73.737137 -516.434736)
			(xy 73.845187 -516.266271) (xy 73.95989 -516.102263) (xy 74.081064 -515.942976) (xy 74.208513 -515.788665)
			(xy 74.342034 -515.639577) (xy 74.481414 -515.49595) (xy 74.626428 -515.358014) (xy 74.776845 -515.225991)
			(xy 74.932423 -515.100092) (xy 75.092915 -514.980518) (xy 75.258061 -514.867462) (xy 75.427599 -514.761103)
			(xy 75.601257 -514.661612) (xy 75.778756 -514.569149) (xy 75.959812 -514.483862) (xy 76.144136 -514.405887)
			(xy 76.331432 -514.33535) (xy 76.5214 -514.272362) (xy 76.713736 -514.217025) (xy 76.908132 -514.169428)
			(xy 77.104277 -514.129647) (xy 77.301856 -514.097745) (xy 77.500553 -514.073774) (xy 77.700051 -514.057772)
			(xy 77.900029 -514.049765) (xy 78.000098 -514.049264) (xy 78.100167 -514.049765) (xy 78.300145 -514.057772)
			(xy 78.499643 -514.073774) (xy 78.69834 -514.097745) (xy 78.895919 -514.129647) (xy 79.092064 -514.169428)
			(xy 79.28646 -514.217025) (xy 79.478796 -514.272362) (xy 79.668764 -514.33535) (xy 79.85606 -514.405887)
			(xy 80.040384 -514.483862) (xy 80.22144 -514.569149) (xy 80.398939 -514.661612) (xy 80.572597 -514.761103)
			(xy 80.742135 -514.867462) (xy 80.907281 -514.980518) (xy 81.067773 -515.100092) (xy 81.223351 -515.225991)
			(xy 81.373768 -515.358014) (xy 81.518782 -515.49595) (xy 81.658162 -515.639577) (xy 81.791683 -515.788665)
			(xy 81.919132 -515.942976) (xy 82.040306 -516.102263) (xy 82.155009 -516.266271) (xy 82.263059 -516.434736)
			(xy 82.364282 -516.607389) (xy 82.458516 -516.783954) (xy 82.542919 -516.95858) (xy 85.959455 -516.95858)
			(xy 85.963416 -516.845132) (xy 85.975282 -516.732236) (xy 85.994994 -516.620443) (xy 86.022457 -516.510297)
			(xy 86.057535 -516.402336) (xy 86.10006 -516.297084) (xy 86.149823 -516.195055) (xy 86.206581 -516.096746)
			(xy 86.27006 -516.002636) (xy 86.339948 -515.913183) (xy 86.415906 -515.828823) (xy 86.497564 -515.749967)
			(xy 86.584523 -515.676999) (xy 86.676361 -515.610275) (xy 86.772629 -515.55012) (xy 86.872859 -515.496827)
			(xy 86.976563 -515.450655) (xy 87.083234 -515.41183) (xy 87.192354 -515.38054) (xy 87.303391 -515.356938)
			(xy 87.415804 -515.34114) (xy 87.529045 -515.333221) (xy 87.585804 -515.332726) (xy 87.642563 -515.333221)
			(xy 87.755804 -515.34114) (xy 87.868217 -515.356938) (xy 87.979254 -515.38054) (xy 88.088374 -515.41183)
			(xy 88.195045 -515.450655) (xy 88.298749 -515.496827) (xy 88.398979 -515.55012) (xy 88.495247 -515.610275)
			(xy 88.587085 -515.676999) (xy 88.674044 -515.749967) (xy 88.755702 -515.828823) (xy 88.83166 -515.913183)
			(xy 88.901548 -516.002636) (xy 88.965027 -516.096746) (xy 89.021785 -516.195055) (xy 89.071548 -516.297084)
			(xy 89.114073 -516.402336) (xy 89.149151 -516.510297) (xy 89.176614 -516.620443) (xy 89.196326 -516.732236)
			(xy 89.208192 -516.845132) (xy 89.212154 -516.95858) (xy 89.208192 -517.072028) (xy 89.196326 -517.184924)
			(xy 89.176614 -517.296717) (xy 89.149151 -517.406863) (xy 89.114073 -517.514824) (xy 89.071548 -517.620076)
			(xy 89.021785 -517.722105) (xy 88.965027 -517.820414) (xy 88.901548 -517.914524) (xy 88.83166 -518.003977)
			(xy 88.755702 -518.088337) (xy 88.674044 -518.167193) (xy 88.587085 -518.240161) (xy 88.495247 -518.306885)
			(xy 88.398979 -518.36704) (xy 88.298749 -518.420333) (xy 88.195045 -518.466505) (xy 88.088374 -518.50533)
			(xy 87.979254 -518.53662) (xy 87.868217 -518.560222) (xy 87.755804 -518.57602) (xy 87.642563 -518.583939)
			(xy 87.529045 -518.583939) (xy 87.415804 -518.57602) (xy 87.303391 -518.560222) (xy 87.192354 -518.53662)
			(xy 87.083234 -518.50533) (xy 86.976563 -518.466505) (xy 86.872859 -518.420333) (xy 86.772629 -518.36704)
			(xy 86.676361 -518.306885) (xy 86.584523 -518.240161) (xy 86.497564 -518.167193) (xy 86.415906 -518.088337)
			(xy 86.339948 -518.003977) (xy 86.27006 -517.914524) (xy 86.206581 -517.820414) (xy 86.149823 -517.722105)
			(xy 86.10006 -517.620076) (xy 86.057535 -517.514824) (xy 86.022457 -517.406863) (xy 85.994994 -517.296717)
			(xy 85.975282 -517.184924) (xy 85.963416 -517.072028) (xy 85.959455 -516.95858) (xy 82.542919 -516.95858)
			(xy 82.54561 -516.964148) (xy 82.625426 -517.147683) (xy 82.697834 -517.334263) (xy 82.762719 -517.523592)
			(xy 82.819977 -517.715365) (xy 82.869516 -517.909275) (xy 82.911258 -518.105012) (xy 82.945135 -518.302262)
			(xy 82.971093 -518.50071) (xy 82.98909 -518.700037) (xy 82.999098 -518.899925) (xy 83.0011 -519.100053)
			(xy 82.995094 -519.300101) (xy 82.981089 -519.499749) (xy 82.959107 -519.698676) (xy 82.929183 -519.896565)
			(xy 82.891366 -520.093098) (xy 82.845717 -520.28796) (xy 82.792307 -520.48084) (xy 82.731223 -520.671429)
			(xy 82.662563 -520.859421) (xy 82.586436 -521.044516) (xy 82.502965 -521.226416) (xy 82.412282 -521.404832)
			(xy 82.314534 -521.579476) (xy 82.209877 -521.750069) (xy 82.098478 -521.916339) (xy 81.980516 -522.078018)
			(xy 81.85618 -522.234849) (xy 81.725668 -522.386579) (xy 81.589191 -522.532966) (xy 81.446965 -522.673775)
			(xy 81.29922 -522.808782) (xy 81.146192 -522.937769) (xy 80.988125 -523.06053) (xy 80.825274 -523.176868)
			(xy 80.657898 -523.286598) (xy 80.486266 -523.389543) (xy 80.310652 -523.485539) (xy 80.131339 -523.574432)
			(xy 79.948612 -523.656079) (xy 79.762765 -523.730351) (xy 79.574095 -523.797127) (xy 79.382905 -523.856301)
			(xy 79.1895 -523.907778) (xy 78.994191 -523.951476) (xy 78.797289 -523.987324) (xy 78.599111 -524.015266)
			(xy 78.399974 -524.035257) (xy 78.200196 -524.047264) (xy 78.000098 -524.051269) (xy 77.8 -524.047264)
			(xy 77.600222 -524.035257) (xy 77.401085 -524.015266) (xy 77.202907 -523.987324) (xy 77.006005 -523.951476)
			(xy 76.810696 -523.907778) (xy 76.617291 -523.856301) (xy 76.426101 -523.797127) (xy 76.237431 -523.730351)
			(xy 76.051584 -523.656079) (xy 75.868857 -523.574432) (xy 75.689544 -523.485539) (xy 75.51393 -523.389543)
			(xy 75.342298 -523.286598) (xy 75.174922 -523.176868) (xy 75.012071 -523.06053) (xy 74.854004 -522.937769)
			(xy 74.700976 -522.808782) (xy 74.553231 -522.673775) (xy 74.411005 -522.532966) (xy 74.274528 -522.386579)
			(xy 74.144016 -522.234849) (xy 74.01968 -522.078018) (xy 73.901718 -521.916339) (xy 73.790319 -521.750069)
			(xy 73.685662 -521.579476) (xy 73.587914 -521.404832) (xy 73.497231 -521.226416) (xy 73.41376 -521.044516)
			(xy 73.337633 -520.859421) (xy 73.268973 -520.671429) (xy 73.207889 -520.48084) (xy 73.154479 -520.28796)
			(xy 73.10883 -520.093098) (xy 73.071013 -519.896565) (xy 73.041089 -519.698676) (xy 73.019107 -519.499749)
			(xy 73.005102 -519.300101) (xy 72.999096 -519.100053) (xy 69.071384 -519.100053) (xy 69.033012 -519.138425)
			(xy 68.97725 -519.182894) (xy 68.916859 -519.22084) (xy 68.8526 -519.251785) (xy 68.78528 -519.275342)
			(xy 68.715745 -519.291212) (xy 68.644871 -519.299198) (xy 68.573549 -519.299198) (xy 68.502675 -519.291212)
			(xy 68.43314 -519.275342) (xy 68.36582 -519.251785) (xy 68.301561 -519.22084) (xy 68.24117 -519.182894)
			(xy 68.185408 -519.138425) (xy 68.134975 -519.087992) (xy 68.090506 -519.03223) (xy 68.05256 -518.971839)
			(xy 68.021615 -518.90758) (xy 67.998058 -518.84026) (xy 67.982188 -518.770725) (xy 67.974202 -518.699851)
			(xy 66.252606 -518.699851) (xy 66.24462 -518.770725) (xy 66.22875 -518.84026) (xy 66.205193 -518.90758)
			(xy 66.174248 -518.971839) (xy 66.136302 -519.03223) (xy 66.091833 -519.087992) (xy 66.0414 -519.138425)
			(xy 65.985638 -519.182894) (xy 65.925247 -519.22084) (xy 65.860988 -519.251785) (xy 65.793668 -519.275342)
			(xy 65.724133 -519.291212) (xy 65.653259 -519.299198) (xy 65.581937 -519.299198) (xy 65.511063 -519.291212)
			(xy 65.441528 -519.275342) (xy 65.374208 -519.251785) (xy 65.309949 -519.22084) (xy 65.249558 -519.182894)
			(xy 65.193796 -519.138425) (xy 65.143363 -519.087992) (xy 65.098894 -519.03223) (xy 65.060948 -518.971839)
			(xy 65.030003 -518.90758) (xy 65.006446 -518.84026) (xy 64.990576 -518.770725) (xy 64.98259 -518.699851)
			(xy 63.012836 -518.699851) (xy 63.00485 -518.770725) (xy 62.98898 -518.84026) (xy 62.965423 -518.90758)
			(xy 62.934478 -518.971839) (xy 62.896532 -519.03223) (xy 62.852063 -519.087992) (xy 62.80163 -519.138425)
			(xy 62.745868 -519.182894) (xy 62.685477 -519.22084) (xy 62.621218 -519.251785) (xy 62.553898 -519.275342)
			(xy 62.484363 -519.291212) (xy 62.413489 -519.299198) (xy 62.342167 -519.299198) (xy 62.271293 -519.291212)
			(xy 62.201758 -519.275342) (xy 62.134438 -519.251785) (xy 62.070179 -519.22084) (xy 62.009788 -519.182894)
			(xy 61.954026 -519.138425) (xy 61.903593 -519.087992) (xy 61.859124 -519.03223) (xy 61.821178 -518.971839)
			(xy 61.790233 -518.90758) (xy 61.766676 -518.84026) (xy 61.750806 -518.770725) (xy 61.74282 -518.699851)
			(xy 60.208422 -518.699851) (xy 60.200436 -518.770725) (xy 60.184566 -518.84026) (xy 60.161009 -518.90758)
			(xy 60.130064 -518.971839) (xy 60.092118 -519.03223) (xy 60.047649 -519.087992) (xy 59.997216 -519.138425)
			(xy 59.941454 -519.182894) (xy 59.881063 -519.22084) (xy 59.816804 -519.251785) (xy 59.749484 -519.275342)
			(xy 59.679949 -519.291212) (xy 59.609075 -519.299198) (xy 59.537753 -519.299198) (xy 59.466879 -519.291212)
			(xy 59.397344 -519.275342) (xy 59.330024 -519.251785) (xy 59.265765 -519.22084) (xy 59.205374 -519.182894)
			(xy 59.149612 -519.138425) (xy 59.099179 -519.087992) (xy 59.05471 -519.03223) (xy 59.016764 -518.971839)
			(xy 58.985819 -518.90758) (xy 58.962262 -518.84026) (xy 58.946392 -518.770725) (xy 58.938406 -518.699851)
			(xy 57.67655 -518.699851) (xy 57.668564 -518.770725) (xy 57.652694 -518.84026) (xy 57.629137 -518.90758)
			(xy 57.598192 -518.971839) (xy 57.560246 -519.03223) (xy 57.515777 -519.087992) (xy 57.465344 -519.138425)
			(xy 57.409582 -519.182894) (xy 57.349191 -519.22084) (xy 57.284932 -519.251785) (xy 57.217612 -519.275342)
			(xy 57.148077 -519.291212) (xy 57.077203 -519.299198) (xy 57.005881 -519.299198) (xy 56.935007 -519.291212)
			(xy 56.865472 -519.275342) (xy 56.798152 -519.251785) (xy 56.733893 -519.22084) (xy 56.673502 -519.182894)
			(xy 56.61774 -519.138425) (xy 56.567307 -519.087992) (xy 56.522838 -519.03223) (xy 56.484892 -518.971839)
			(xy 56.453947 -518.90758) (xy 56.43039 -518.84026) (xy 56.41452 -518.770725) (xy 56.406534 -518.699851)
			(xy 52.974748 -518.699851) (xy 52.974748 -519.84656) (xy 51.322732 -519.84656) (xy 51.322732 -518.194544)
			(xy 36.344981 -518.194544) (xy 36.315846 -518.241598) (xy 36.263477 -518.310945) (xy 36.204933 -518.375165)
			(xy 36.140713 -518.433709) (xy 36.071366 -518.486078) (xy 35.997482 -518.531825) (xy 35.919693 -518.570559)
			(xy 35.838661 -518.601951) (xy 35.755079 -518.625732) (xy 35.669659 -518.6417) (xy 35.58313 -518.649718)
			(xy 35.49623 -518.649718) (xy 35.409701 -518.6417) (xy 35.324281 -518.625732) (xy 35.240699 -518.601951)
			(xy 35.159667 -518.570559) (xy 35.081878 -518.531825) (xy 35.007994 -518.486078) (xy 34.938647 -518.433709)
			(xy 34.874427 -518.375165) (xy 34.815883 -518.310945) (xy 34.763514 -518.241598) (xy 34.717767 -518.167714)
			(xy 34.679033 -518.089925) (xy 34.647641 -518.008893) (xy 34.62386 -517.925311) (xy 34.607892 -517.839891)
			(xy 34.599874 -517.753362) (xy 31.399486 -517.753362) (xy 31.391468 -517.839891) (xy 31.3755 -517.925311)
			(xy 31.351719 -518.008893) (xy 31.320327 -518.089925) (xy 31.281593 -518.167714) (xy 31.235846 -518.241598)
			(xy 31.183477 -518.310945) (xy 31.124933 -518.375165) (xy 31.060713 -518.433709) (xy 30.991366 -518.486078)
			(xy 30.917482 -518.531825) (xy 30.839693 -518.570559) (xy 30.758661 -518.601951) (xy 30.675079 -518.625732)
			(xy 30.589659 -518.6417) (xy 30.50313 -518.649718) (xy 30.41623 -518.649718) (xy 30.329701 -518.6417)
			(xy 30.244281 -518.625732) (xy 30.160699 -518.601951) (xy 30.079667 -518.570559) (xy 30.001878 -518.531825)
			(xy 29.927994 -518.486078) (xy 29.858647 -518.433709) (xy 29.794427 -518.375165) (xy 29.735883 -518.310945)
			(xy 29.683514 -518.241598) (xy 29.637767 -518.167714) (xy 29.599033 -518.089925) (xy 29.567641 -518.008893)
			(xy 29.54386 -517.925311) (xy 29.527892 -517.839891) (xy 29.519874 -517.753362) (xy 0.509016 -517.753362)
			(xy 0.509016 -520.293362) (xy 29.519874 -520.293362) (xy 29.519874 -520.206462) (xy 29.527892 -520.119933)
			(xy 29.54386 -520.034513) (xy 29.567641 -519.950931) (xy 29.599033 -519.869899) (xy 29.637767 -519.79211)
			(xy 29.683514 -519.718226) (xy 29.735883 -519.648879) (xy 29.794427 -519.584659) (xy 29.858647 -519.526115)
			(xy 29.927994 -519.473746) (xy 30.001878 -519.427999) (xy 30.079667 -519.389265) (xy 30.160699 -519.357873)
			(xy 30.244281 -519.334092) (xy 30.329701 -519.318124) (xy 30.41623 -519.310106) (xy 30.45968 -519.309604)
			(xy 30.50313 -519.310106) (xy 30.589659 -519.318124) (xy 30.675079 -519.334092) (xy 30.758661 -519.357873)
			(xy 30.839693 -519.389265) (xy 30.917482 -519.427999) (xy 30.991366 -519.473746) (xy 31.060713 -519.526115)
			(xy 31.124933 -519.584659) (xy 31.183477 -519.648879) (xy 31.235846 -519.718226) (xy 31.281593 -519.79211)
			(xy 31.320327 -519.869899) (xy 31.351719 -519.950931) (xy 31.3755 -520.034513) (xy 31.391468 -520.119933)
			(xy 31.399486 -520.206462) (xy 31.399486 -520.293362) (xy 34.599874 -520.293362) (xy 34.599874 -520.206462)
			(xy 34.607892 -520.119933) (xy 34.62386 -520.034513) (xy 34.647641 -519.950931) (xy 34.679033 -519.869899)
			(xy 34.717767 -519.79211) (xy 34.763514 -519.718226) (xy 34.815883 -519.648879) (xy 34.874427 -519.584659)
			(xy 34.938647 -519.526115) (xy 35.007994 -519.473746) (xy 35.081878 -519.427999) (xy 35.159667 -519.389265)
			(xy 35.240699 -519.357873) (xy 35.324281 -519.334092) (xy 35.409701 -519.318124) (xy 35.49623 -519.310106)
			(xy 35.53968 -519.309604) (xy 35.58313 -519.310106) (xy 35.669659 -519.318124) (xy 35.755079 -519.334092)
			(xy 35.838661 -519.357873) (xy 35.919693 -519.389265) (xy 35.997482 -519.427999) (xy 36.071366 -519.473746)
			(xy 36.140713 -519.526115) (xy 36.204933 -519.584659) (xy 36.263477 -519.648879) (xy 36.315846 -519.718226)
			(xy 36.361593 -519.79211) (xy 36.400327 -519.869899) (xy 36.431719 -519.950931) (xy 36.4555 -520.034513)
			(xy 36.471468 -520.119933) (xy 36.479486 -520.206462) (xy 36.479486 -520.293362) (xy 36.471468 -520.379891)
			(xy 36.4555 -520.465311) (xy 36.431719 -520.548893) (xy 36.400327 -520.629925) (xy 36.361593 -520.707714)
			(xy 36.315846 -520.781598) (xy 36.263477 -520.850945) (xy 36.204933 -520.915165) (xy 36.140713 -520.973709)
			(xy 36.071366 -521.026078) (xy 35.998089 -521.071449) (xy 56.406534 -521.071449) (xy 56.406534 -521.000127)
			(xy 56.41452 -520.929253) (xy 56.43039 -520.859718) (xy 56.453947 -520.792398) (xy 56.484892 -520.728139)
			(xy 56.522838 -520.667748) (xy 56.567307 -520.611986) (xy 56.61774 -520.561553) (xy 56.673502 -520.517084)
			(xy 56.733893 -520.479138) (xy 56.798152 -520.448193) (xy 56.865472 -520.424636) (xy 56.935007 -520.408766)
			(xy 57.005881 -520.40078) (xy 57.041542 -520.40028) (xy 57.077203 -520.40078) (xy 57.148077 -520.408766)
			(xy 57.217612 -520.424636) (xy 57.284932 -520.448193) (xy 57.349191 -520.479138) (xy 57.409582 -520.517084)
			(xy 57.465344 -520.561553) (xy 57.515777 -520.611986) (xy 57.560246 -520.667748) (xy 57.598192 -520.728139)
			(xy 57.629137 -520.792398) (xy 57.652694 -520.859718) (xy 57.668564 -520.929253) (xy 57.67655 -521.000127)
			(xy 57.67655 -521.071449) (xy 58.938406 -521.071449) (xy 58.938406 -521.000127) (xy 58.946392 -520.929253)
			(xy 58.962262 -520.859718) (xy 58.985819 -520.792398) (xy 59.016764 -520.728139) (xy 59.05471 -520.667748)
			(xy 59.099179 -520.611986) (xy 59.149612 -520.561553) (xy 59.205374 -520.517084) (xy 59.265765 -520.479138)
			(xy 59.330024 -520.448193) (xy 59.397344 -520.424636) (xy 59.466879 -520.408766) (xy 59.537753 -520.40078)
			(xy 59.573414 -520.40028) (xy 59.609075 -520.40078) (xy 59.679949 -520.408766) (xy 59.749484 -520.424636)
			(xy 59.816804 -520.448193) (xy 59.881063 -520.479138) (xy 59.941454 -520.517084) (xy 59.997216 -520.561553)
			(xy 60.047649 -520.611986) (xy 60.092118 -520.667748) (xy 60.130064 -520.728139) (xy 60.161009 -520.792398)
			(xy 60.184566 -520.859718) (xy 60.200436 -520.929253) (xy 60.208422 -521.000127) (xy 60.208422 -521.071449)
			(xy 61.74282 -521.071449) (xy 61.74282 -521.000127) (xy 61.750806 -520.929253) (xy 61.766676 -520.859718)
			(xy 61.790233 -520.792398) (xy 61.821178 -520.728139) (xy 61.859124 -520.667748) (xy 61.903593 -520.611986)
			(xy 61.954026 -520.561553) (xy 62.009788 -520.517084) (xy 62.070179 -520.479138) (xy 62.134438 -520.448193)
			(xy 62.201758 -520.424636) (xy 62.271293 -520.408766) (xy 62.342167 -520.40078) (xy 62.377828 -520.40028)
			(xy 62.413489 -520.40078) (xy 62.484363 -520.408766) (xy 62.553898 -520.424636) (xy 62.621218 -520.448193)
			(xy 62.685477 -520.479138) (xy 62.745868 -520.517084) (xy 62.80163 -520.561553) (xy 62.852063 -520.611986)
			(xy 62.896532 -520.667748) (xy 62.934478 -520.728139) (xy 62.965423 -520.792398) (xy 62.98898 -520.859718)
			(xy 63.00485 -520.929253) (xy 63.012836 -521.000127) (xy 63.012836 -521.071449) (xy 64.98259 -521.071449)
			(xy 64.98259 -521.000127) (xy 64.990576 -520.929253) (xy 65.006446 -520.859718) (xy 65.030003 -520.792398)
			(xy 65.060948 -520.728139) (xy 65.098894 -520.667748) (xy 65.143363 -520.611986) (xy 65.193796 -520.561553)
			(xy 65.249558 -520.517084) (xy 65.309949 -520.479138) (xy 65.374208 -520.448193) (xy 65.441528 -520.424636)
			(xy 65.511063 -520.408766) (xy 65.581937 -520.40078) (xy 65.617598 -520.40028) (xy 65.653259 -520.40078)
			(xy 65.724133 -520.408766) (xy 65.793668 -520.424636) (xy 65.860988 -520.448193) (xy 65.925247 -520.479138)
			(xy 65.985638 -520.517084) (xy 66.0414 -520.561553) (xy 66.091833 -520.611986) (xy 66.136302 -520.667748)
			(xy 66.174248 -520.728139) (xy 66.205193 -520.792398) (xy 66.22875 -520.859718) (xy 66.24462 -520.929253)
			(xy 66.252606 -521.000127) (xy 66.252606 -521.071449) (xy 67.974202 -521.071449) (xy 67.974202 -521.000127)
			(xy 67.982188 -520.929253) (xy 67.998058 -520.859718) (xy 68.021615 -520.792398) (xy 68.05256 -520.728139)
			(xy 68.090506 -520.667748) (xy 68.134975 -520.611986) (xy 68.185408 -520.561553) (xy 68.24117 -520.517084)
			(xy 68.301561 -520.479138) (xy 68.36582 -520.448193) (xy 68.43314 -520.424636) (xy 68.502675 -520.408766)
			(xy 68.573549 -520.40078) (xy 68.60921 -520.40028) (xy 68.644871 -520.40078) (xy 68.715745 -520.408766)
			(xy 68.78528 -520.424636) (xy 68.8526 -520.448193) (xy 68.916859 -520.479138) (xy 68.97725 -520.517084)
			(xy 69.033012 -520.561553) (xy 69.083445 -520.611986) (xy 69.127914 -520.667748) (xy 69.16586 -520.728139)
			(xy 69.196805 -520.792398) (xy 69.220362 -520.859718) (xy 69.236232 -520.929253) (xy 69.244218 -521.000127)
			(xy 69.244218 -521.071449) (xy 69.236232 -521.142323) (xy 69.220362 -521.211858) (xy 69.196805 -521.279178)
			(xy 69.16586 -521.343437) (xy 69.127914 -521.403828) (xy 69.083445 -521.45959) (xy 69.033012 -521.510023)
			(xy 68.97725 -521.554492) (xy 68.916859 -521.592438) (xy 68.8526 -521.623383) (xy 68.78528 -521.64694)
			(xy 68.715745 -521.66281) (xy 68.644871 -521.670796) (xy 68.573549 -521.670796) (xy 68.502675 -521.66281)
			(xy 68.43314 -521.64694) (xy 68.36582 -521.623383) (xy 68.301561 -521.592438) (xy 68.24117 -521.554492)
			(xy 68.185408 -521.510023) (xy 68.134975 -521.45959) (xy 68.090506 -521.403828) (xy 68.05256 -521.343437)
			(xy 68.021615 -521.279178) (xy 67.998058 -521.211858) (xy 67.982188 -521.142323) (xy 67.974202 -521.071449)
			(xy 66.252606 -521.071449) (xy 66.24462 -521.142323) (xy 66.22875 -521.211858) (xy 66.205193 -521.279178)
			(xy 66.174248 -521.343437) (xy 66.136302 -521.403828) (xy 66.091833 -521.45959) (xy 66.0414 -521.510023)
			(xy 65.985638 -521.554492) (xy 65.925247 -521.592438) (xy 65.860988 -521.623383) (xy 65.793668 -521.64694)
			(xy 65.724133 -521.66281) (xy 65.653259 -521.670796) (xy 65.581937 -521.670796) (xy 65.511063 -521.66281)
			(xy 65.441528 -521.64694) (xy 65.374208 -521.623383) (xy 65.309949 -521.592438) (xy 65.249558 -521.554492)
			(xy 65.193796 -521.510023) (xy 65.143363 -521.45959) (xy 65.098894 -521.403828) (xy 65.060948 -521.343437)
			(xy 65.030003 -521.279178) (xy 65.006446 -521.211858) (xy 64.990576 -521.142323) (xy 64.98259 -521.071449)
			(xy 63.012836 -521.071449) (xy 63.00485 -521.142323) (xy 62.98898 -521.211858) (xy 62.965423 -521.279178)
			(xy 62.934478 -521.343437) (xy 62.896532 -521.403828) (xy 62.852063 -521.45959) (xy 62.80163 -521.510023)
			(xy 62.745868 -521.554492) (xy 62.685477 -521.592438) (xy 62.621218 -521.623383) (xy 62.553898 -521.64694)
			(xy 62.484363 -521.66281) (xy 62.413489 -521.670796) (xy 62.342167 -521.670796) (xy 62.271293 -521.66281)
			(xy 62.201758 -521.64694) (xy 62.134438 -521.623383) (xy 62.070179 -521.592438) (xy 62.009788 -521.554492)
			(xy 61.954026 -521.510023) (xy 61.903593 -521.45959) (xy 61.859124 -521.403828) (xy 61.821178 -521.343437)
			(xy 61.790233 -521.279178) (xy 61.766676 -521.211858) (xy 61.750806 -521.142323) (xy 61.74282 -521.071449)
			(xy 60.208422 -521.071449) (xy 60.200436 -521.142323) (xy 60.184566 -521.211858) (xy 60.161009 -521.279178)
			(xy 60.130064 -521.343437) (xy 60.092118 -521.403828) (xy 60.047649 -521.45959) (xy 59.997216 -521.510023)
			(xy 59.941454 -521.554492) (xy 59.881063 -521.592438) (xy 59.816804 -521.623383) (xy 59.749484 -521.64694)
			(xy 59.679949 -521.66281) (xy 59.609075 -521.670796) (xy 59.537753 -521.670796) (xy 59.466879 -521.66281)
			(xy 59.397344 -521.64694) (xy 59.330024 -521.623383) (xy 59.265765 -521.592438) (xy 59.205374 -521.554492)
			(xy 59.149612 -521.510023) (xy 59.099179 -521.45959) (xy 59.05471 -521.403828) (xy 59.016764 -521.343437)
			(xy 58.985819 -521.279178) (xy 58.962262 -521.211858) (xy 58.946392 -521.142323) (xy 58.938406 -521.071449)
			(xy 57.67655 -521.071449) (xy 57.668564 -521.142323) (xy 57.652694 -521.211858) (xy 57.629137 -521.279178)
			(xy 57.598192 -521.343437) (xy 57.560246 -521.403828) (xy 57.515777 -521.45959) (xy 57.465344 -521.510023)
			(xy 57.409582 -521.554492) (xy 57.349191 -521.592438) (xy 57.284932 -521.623383) (xy 57.217612 -521.64694)
			(xy 57.148077 -521.66281) (xy 57.077203 -521.670796) (xy 57.005881 -521.670796) (xy 56.935007 -521.66281)
			(xy 56.865472 -521.64694) (xy 56.798152 -521.623383) (xy 56.733893 -521.592438) (xy 56.673502 -521.554492)
			(xy 56.61774 -521.510023) (xy 56.567307 -521.45959) (xy 56.522838 -521.403828) (xy 56.484892 -521.343437)
			(xy 56.453947 -521.279178) (xy 56.43039 -521.211858) (xy 56.41452 -521.142323) (xy 56.406534 -521.071449)
			(xy 35.998089 -521.071449) (xy 35.997482 -521.071825) (xy 35.919693 -521.110559) (xy 35.838661 -521.141951)
			(xy 35.755079 -521.165732) (xy 35.669659 -521.1817) (xy 35.58313 -521.189718) (xy 35.49623 -521.189718)
			(xy 35.409701 -521.1817) (xy 35.324281 -521.165732) (xy 35.240699 -521.141951) (xy 35.159667 -521.110559)
			(xy 35.081878 -521.071825) (xy 35.007994 -521.026078) (xy 34.938647 -520.973709) (xy 34.874427 -520.915165)
			(xy 34.815883 -520.850945) (xy 34.763514 -520.781598) (xy 34.717767 -520.707714) (xy 34.679033 -520.629925)
			(xy 34.647641 -520.548893) (xy 34.62386 -520.465311) (xy 34.607892 -520.379891) (xy 34.599874 -520.293362)
			(xy 31.399486 -520.293362) (xy 31.391468 -520.379891) (xy 31.3755 -520.465311) (xy 31.351719 -520.548893)
			(xy 31.320327 -520.629925) (xy 31.281593 -520.707714) (xy 31.235846 -520.781598) (xy 31.183477 -520.850945)
			(xy 31.124933 -520.915165) (xy 31.060713 -520.973709) (xy 30.991366 -521.026078) (xy 30.917482 -521.071825)
			(xy 30.839693 -521.110559) (xy 30.758661 -521.141951) (xy 30.675079 -521.165732) (xy 30.589659 -521.1817)
			(xy 30.50313 -521.189718) (xy 30.41623 -521.189718) (xy 30.329701 -521.1817) (xy 30.244281 -521.165732)
			(xy 30.160699 -521.141951) (xy 30.079667 -521.110559) (xy 30.001878 -521.071825) (xy 29.927994 -521.026078)
			(xy 29.858647 -520.973709) (xy 29.794427 -520.915165) (xy 29.735883 -520.850945) (xy 29.683514 -520.781598)
			(xy 29.637767 -520.707714) (xy 29.599033 -520.629925) (xy 29.567641 -520.548893) (xy 29.54386 -520.465311)
			(xy 29.527892 -520.379891) (xy 29.519874 -520.293362) (xy 0.509016 -520.293362) (xy 0.509016 -520.29614)
			(xy 3.678936 -520.29614) (xy 5.330444 -520.29614) (xy 5.330444 -521.162449) (xy 6.21918 -521.162449)
			(xy 6.21918 -521.081339) (xy 6.22713 -521.00062) (xy 6.242953 -520.921069) (xy 6.266498 -520.843453)
			(xy 6.297537 -520.768517) (xy 6.335772 -520.696985) (xy 6.380834 -520.629545) (xy 6.432289 -520.566846)
			(xy 6.489642 -520.509493) (xy 6.552341 -520.458038) (xy 6.619781 -520.412976) (xy 6.691313 -520.374741)
			(xy 6.766249 -520.343702) (xy 6.843865 -520.320157) (xy 6.923416 -520.304334) (xy 7.004135 -520.296384)
			(xy 7.04469 -520.295886) (xy 7.085245 -520.296384) (xy 7.165964 -520.304334) (xy 7.245515 -520.320157)
			(xy 7.323131 -520.343702) (xy 7.398067 -520.374741) (xy 7.469599 -520.412976) (xy 7.537039 -520.458038)
			(xy 7.599738 -520.509493) (xy 7.657091 -520.566846) (xy 7.708546 -520.629545) (xy 7.753608 -520.696985)
			(xy 7.791843 -520.768517) (xy 7.822882 -520.843453) (xy 7.846427 -520.921069) (xy 7.86225 -521.00062)
			(xy 7.8702 -521.081339) (xy 7.8702 -521.162449) (xy 11.29918 -521.162449) (xy 11.29918 -521.081339)
			(xy 11.30713 -521.00062) (xy 11.322953 -520.921069) (xy 11.346498 -520.843453) (xy 11.377537 -520.768517)
			(xy 11.415772 -520.696985) (xy 11.460834 -520.629545) (xy 11.512289 -520.566846) (xy 11.569642 -520.509493)
			(xy 11.632341 -520.458038) (xy 11.699781 -520.412976) (xy 11.771313 -520.374741) (xy 11.846249 -520.343702)
			(xy 11.923865 -520.320157) (xy 12.003416 -520.304334) (xy 12.084135 -520.296384) (xy 12.12469 -520.295886)
			(xy 12.165245 -520.296384) (xy 12.245964 -520.304334) (xy 12.325515 -520.320157) (xy 12.403131 -520.343702)
			(xy 12.478067 -520.374741) (xy 12.549599 -520.412976) (xy 12.617039 -520.458038) (xy 12.679738 -520.509493)
			(xy 12.737091 -520.566846) (xy 12.788546 -520.629545) (xy 12.833608 -520.696985) (xy 12.871843 -520.768517)
			(xy 12.902882 -520.843453) (xy 12.926427 -520.921069) (xy 12.94225 -521.00062) (xy 12.9502 -521.081339)
			(xy 12.9502 -521.162449) (xy 12.94225 -521.243168) (xy 12.926427 -521.322719) (xy 12.902882 -521.400335)
			(xy 12.871843 -521.475271) (xy 12.833608 -521.546803) (xy 12.788546 -521.614243) (xy 12.737091 -521.676942)
			(xy 12.679738 -521.734295) (xy 12.617039 -521.78575) (xy 12.549599 -521.830812) (xy 12.478067 -521.869047)
			(xy 12.403131 -521.900086) (xy 12.325515 -521.923631) (xy 12.245964 -521.939454) (xy 12.165245 -521.947404)
			(xy 12.084135 -521.947404) (xy 12.003416 -521.939454) (xy 11.923865 -521.923631) (xy 11.846249 -521.900086)
			(xy 11.771313 -521.869047) (xy 11.699781 -521.830812) (xy 11.632341 -521.78575) (xy 11.569642 -521.734295)
			(xy 11.512289 -521.676942) (xy 11.460834 -521.614243) (xy 11.415772 -521.546803) (xy 11.377537 -521.475271)
			(xy 11.346498 -521.400335) (xy 11.322953 -521.322719) (xy 11.30713 -521.243168) (xy 11.29918 -521.162449)
			(xy 7.8702 -521.162449) (xy 7.86225 -521.243168) (xy 7.846427 -521.322719) (xy 7.822882 -521.400335)
			(xy 7.791843 -521.475271) (xy 7.753608 -521.546803) (xy 7.708546 -521.614243) (xy 7.657091 -521.676942)
			(xy 7.599738 -521.734295) (xy 7.537039 -521.78575) (xy 7.469599 -521.830812) (xy 7.398067 -521.869047)
			(xy 7.323131 -521.900086) (xy 7.245515 -521.923631) (xy 7.165964 -521.939454) (xy 7.085245 -521.947404)
			(xy 7.004135 -521.947404) (xy 6.923416 -521.939454) (xy 6.843865 -521.923631) (xy 6.766249 -521.900086)
			(xy 6.691313 -521.869047) (xy 6.619781 -521.830812) (xy 6.552341 -521.78575) (xy 6.489642 -521.734295)
			(xy 6.432289 -521.676942) (xy 6.380834 -521.614243) (xy 6.335772 -521.546803) (xy 6.297537 -521.475271)
			(xy 6.266498 -521.400335) (xy 6.242953 -521.322719) (xy 6.22713 -521.243168) (xy 6.21918 -521.162449)
			(xy 5.330444 -521.162449) (xy 5.330444 -521.947648) (xy 3.678936 -521.947648) (xy 3.678936 -520.29614)
			(xy 0.509016 -520.29614) (xy 0.509016 -522.833362) (xy 29.519874 -522.833362) (xy 29.519874 -522.746462)
			(xy 29.527892 -522.659933) (xy 29.54386 -522.574513) (xy 29.567641 -522.490931) (xy 29.599033 -522.409899)
			(xy 29.637767 -522.33211) (xy 29.683514 -522.258226) (xy 29.735883 -522.188879) (xy 29.794427 -522.124659)
			(xy 29.858647 -522.066115) (xy 29.927994 -522.013746) (xy 30.001878 -521.967999) (xy 30.079667 -521.929265)
			(xy 30.160699 -521.897873) (xy 30.244281 -521.874092) (xy 30.329701 -521.858124) (xy 30.41623 -521.850106)
			(xy 30.45968 -521.849604) (xy 30.50313 -521.850106) (xy 30.589659 -521.858124) (xy 30.675079 -521.874092)
			(xy 30.758661 -521.897873) (xy 30.839693 -521.929265) (xy 30.917482 -521.967999) (xy 30.991366 -522.013746)
			(xy 31.060713 -522.066115) (xy 31.124933 -522.124659) (xy 31.183477 -522.188879) (xy 31.235846 -522.258226)
			(xy 31.281593 -522.33211) (xy 31.320327 -522.409899) (xy 31.351719 -522.490931) (xy 31.3755 -522.574513)
			(xy 31.391468 -522.659933) (xy 31.399486 -522.746462) (xy 31.399486 -522.833362) (xy 34.599874 -522.833362)
			(xy 34.599874 -522.746462) (xy 34.607892 -522.659933) (xy 34.62386 -522.574513) (xy 34.647641 -522.490931)
			(xy 34.679033 -522.409899) (xy 34.717767 -522.33211) (xy 34.763514 -522.258226) (xy 34.815883 -522.188879)
			(xy 34.874427 -522.124659) (xy 34.938647 -522.066115) (xy 35.007994 -522.013746) (xy 35.081878 -521.967999)
			(xy 35.159667 -521.929265) (xy 35.240699 -521.897873) (xy 35.324281 -521.874092) (xy 35.409701 -521.858124)
			(xy 35.49623 -521.850106) (xy 35.53968 -521.849604) (xy 35.58313 -521.850106) (xy 35.669659 -521.858124)
			(xy 35.755079 -521.874092) (xy 35.838661 -521.897873) (xy 35.919693 -521.929265) (xy 35.997482 -521.967999)
			(xy 36.071366 -522.013746) (xy 36.140713 -522.066115) (xy 36.204933 -522.124659) (xy 36.263477 -522.188879)
			(xy 36.315846 -522.258226) (xy 36.361593 -522.33211) (xy 36.400327 -522.409899) (xy 36.431719 -522.490931)
			(xy 36.4555 -522.574513) (xy 36.471468 -522.659933) (xy 36.479486 -522.746462) (xy 36.479486 -522.833362)
			(xy 36.471468 -522.919891) (xy 36.4555 -523.005311) (xy 36.447235 -523.034361) (xy 56.406534 -523.034361)
			(xy 56.406534 -522.963039) (xy 56.41452 -522.892165) (xy 56.43039 -522.82263) (xy 56.453947 -522.75531)
			(xy 56.484892 -522.691051) (xy 56.522838 -522.63066) (xy 56.567307 -522.574898) (xy 56.61774 -522.524465)
			(xy 56.673502 -522.479996) (xy 56.733893 -522.44205) (xy 56.798152 -522.411105) (xy 56.865472 -522.387548)
			(xy 56.935007 -522.371678) (xy 57.005881 -522.363692) (xy 57.041542 -522.363192) (xy 57.077203 -522.363692)
			(xy 57.148077 -522.371678) (xy 57.217612 -522.387548) (xy 57.284932 -522.411105) (xy 57.349191 -522.44205)
			(xy 57.409582 -522.479996) (xy 57.465344 -522.524465) (xy 57.515777 -522.574898) (xy 57.560246 -522.63066)
			(xy 57.598192 -522.691051) (xy 57.629137 -522.75531) (xy 57.652694 -522.82263) (xy 57.668564 -522.892165)
			(xy 57.67655 -522.963039) (xy 57.67655 -523.034361) (xy 58.938406 -523.034361) (xy 58.938406 -522.963039)
			(xy 58.946392 -522.892165) (xy 58.962262 -522.82263) (xy 58.985819 -522.75531) (xy 59.016764 -522.691051)
			(xy 59.05471 -522.63066) (xy 59.099179 -522.574898) (xy 59.149612 -522.524465) (xy 59.205374 -522.479996)
			(xy 59.265765 -522.44205) (xy 59.330024 -522.411105) (xy 59.397344 -522.387548) (xy 59.466879 -522.371678)
			(xy 59.537753 -522.363692) (xy 59.573414 -522.363192) (xy 59.609075 -522.363692) (xy 59.679949 -522.371678)
			(xy 59.749484 -522.387548) (xy 59.816804 -522.411105) (xy 59.881063 -522.44205) (xy 59.941454 -522.479996)
			(xy 59.997216 -522.524465) (xy 60.047649 -522.574898) (xy 60.092118 -522.63066) (xy 60.130064 -522.691051)
			(xy 60.161009 -522.75531) (xy 60.184566 -522.82263) (xy 60.200436 -522.892165) (xy 60.208422 -522.963039)
			(xy 60.208422 -523.034361) (xy 61.74282 -523.034361) (xy 61.74282 -522.963039) (xy 61.750806 -522.892165)
			(xy 61.766676 -522.82263) (xy 61.790233 -522.75531) (xy 61.821178 -522.691051) (xy 61.859124 -522.63066)
			(xy 61.903593 -522.574898) (xy 61.954026 -522.524465) (xy 62.009788 -522.479996) (xy 62.070179 -522.44205)
			(xy 62.134438 -522.411105) (xy 62.201758 -522.387548) (xy 62.271293 -522.371678) (xy 62.342167 -522.363692)
			(xy 62.377828 -522.363192) (xy 62.413489 -522.363692) (xy 62.484363 -522.371678) (xy 62.553898 -522.387548)
			(xy 62.621218 -522.411105) (xy 62.685477 -522.44205) (xy 62.745868 -522.479996) (xy 62.80163 -522.524465)
			(xy 62.852063 -522.574898) (xy 62.896532 -522.63066) (xy 62.934478 -522.691051) (xy 62.965423 -522.75531)
			(xy 62.98898 -522.82263) (xy 63.00485 -522.892165) (xy 63.012836 -522.963039) (xy 63.012836 -523.034361)
			(xy 64.98259 -523.034361) (xy 64.98259 -522.963039) (xy 64.990576 -522.892165) (xy 65.006446 -522.82263)
			(xy 65.030003 -522.75531) (xy 65.060948 -522.691051) (xy 65.098894 -522.63066) (xy 65.143363 -522.574898)
			(xy 65.193796 -522.524465) (xy 65.249558 -522.479996) (xy 65.309949 -522.44205) (xy 65.374208 -522.411105)
			(xy 65.441528 -522.387548) (xy 65.511063 -522.371678) (xy 65.581937 -522.363692) (xy 65.617598 -522.363192)
			(xy 65.653259 -522.363692) (xy 65.724133 -522.371678) (xy 65.793668 -522.387548) (xy 65.860988 -522.411105)
			(xy 65.925247 -522.44205) (xy 65.985638 -522.479996) (xy 66.0414 -522.524465) (xy 66.091833 -522.574898)
			(xy 66.136302 -522.63066) (xy 66.174248 -522.691051) (xy 66.205193 -522.75531) (xy 66.22875 -522.82263)
			(xy 66.24462 -522.892165) (xy 66.252606 -522.963039) (xy 66.252606 -523.034361) (xy 67.974202 -523.034361)
			(xy 67.974202 -522.963039) (xy 67.982188 -522.892165) (xy 67.998058 -522.82263) (xy 68.021615 -522.75531)
			(xy 68.05256 -522.691051) (xy 68.090506 -522.63066) (xy 68.134975 -522.574898) (xy 68.185408 -522.524465)
			(xy 68.24117 -522.479996) (xy 68.301561 -522.44205) (xy 68.36582 -522.411105) (xy 68.43314 -522.387548)
			(xy 68.502675 -522.371678) (xy 68.573549 -522.363692) (xy 68.60921 -522.363192) (xy 68.644871 -522.363692)
			(xy 68.715745 -522.371678) (xy 68.78528 -522.387548) (xy 68.8526 -522.411105) (xy 68.916859 -522.44205)
			(xy 68.97725 -522.479996) (xy 69.033012 -522.524465) (xy 69.083445 -522.574898) (xy 69.127914 -522.63066)
			(xy 69.16586 -522.691051) (xy 69.196805 -522.75531) (xy 69.220362 -522.82263) (xy 69.236232 -522.892165)
			(xy 69.244218 -522.963039) (xy 69.244218 -523.034361) (xy 69.236232 -523.105235) (xy 69.220362 -523.17477)
			(xy 69.196805 -523.24209) (xy 69.16586 -523.306349) (xy 69.127914 -523.36674) (xy 69.083445 -523.422502)
			(xy 69.033012 -523.472935) (xy 68.97725 -523.517404) (xy 68.916859 -523.55535) (xy 68.8526 -523.586295)
			(xy 68.78528 -523.609852) (xy 68.715745 -523.625722) (xy 68.644871 -523.633708) (xy 68.573549 -523.633708)
			(xy 68.502675 -523.625722) (xy 68.43314 -523.609852) (xy 68.36582 -523.586295) (xy 68.301561 -523.55535)
			(xy 68.24117 -523.517404) (xy 68.185408 -523.472935) (xy 68.134975 -523.422502) (xy 68.090506 -523.36674)
			(xy 68.05256 -523.306349) (xy 68.021615 -523.24209) (xy 67.998058 -523.17477) (xy 67.982188 -523.105235)
			(xy 67.974202 -523.034361) (xy 66.252606 -523.034361) (xy 66.24462 -523.105235) (xy 66.22875 -523.17477)
			(xy 66.205193 -523.24209) (xy 66.174248 -523.306349) (xy 66.136302 -523.36674) (xy 66.091833 -523.422502)
			(xy 66.0414 -523.472935) (xy 65.985638 -523.517404) (xy 65.925247 -523.55535) (xy 65.860988 -523.586295)
			(xy 65.793668 -523.609852) (xy 65.724133 -523.625722) (xy 65.653259 -523.633708) (xy 65.581937 -523.633708)
			(xy 65.511063 -523.625722) (xy 65.441528 -523.609852) (xy 65.374208 -523.586295) (xy 65.309949 -523.55535)
			(xy 65.249558 -523.517404) (xy 65.193796 -523.472935) (xy 65.143363 -523.422502) (xy 65.098894 -523.36674)
			(xy 65.060948 -523.306349) (xy 65.030003 -523.24209) (xy 65.006446 -523.17477) (xy 64.990576 -523.105235)
			(xy 64.98259 -523.034361) (xy 63.012836 -523.034361) (xy 63.00485 -523.105235) (xy 62.98898 -523.17477)
			(xy 62.965423 -523.24209) (xy 62.934478 -523.306349) (xy 62.896532 -523.36674) (xy 62.852063 -523.422502)
			(xy 62.80163 -523.472935) (xy 62.745868 -523.517404) (xy 62.685477 -523.55535) (xy 62.621218 -523.586295)
			(xy 62.553898 -523.609852) (xy 62.484363 -523.625722) (xy 62.413489 -523.633708) (xy 62.342167 -523.633708)
			(xy 62.271293 -523.625722) (xy 62.201758 -523.609852) (xy 62.134438 -523.586295) (xy 62.070179 -523.55535)
			(xy 62.009788 -523.517404) (xy 61.954026 -523.472935) (xy 61.903593 -523.422502) (xy 61.859124 -523.36674)
			(xy 61.821178 -523.306349) (xy 61.790233 -523.24209) (xy 61.766676 -523.17477) (xy 61.750806 -523.105235)
			(xy 61.74282 -523.034361) (xy 60.208422 -523.034361) (xy 60.200436 -523.105235) (xy 60.184566 -523.17477)
			(xy 60.161009 -523.24209) (xy 60.130064 -523.306349) (xy 60.092118 -523.36674) (xy 60.047649 -523.422502)
			(xy 59.997216 -523.472935) (xy 59.941454 -523.517404) (xy 59.881063 -523.55535) (xy 59.816804 -523.586295)
			(xy 59.749484 -523.609852) (xy 59.679949 -523.625722) (xy 59.609075 -523.633708) (xy 59.537753 -523.633708)
			(xy 59.466879 -523.625722) (xy 59.397344 -523.609852) (xy 59.330024 -523.586295) (xy 59.265765 -523.55535)
			(xy 59.205374 -523.517404) (xy 59.149612 -523.472935) (xy 59.099179 -523.422502) (xy 59.05471 -523.36674)
			(xy 59.016764 -523.306349) (xy 58.985819 -523.24209) (xy 58.962262 -523.17477) (xy 58.946392 -523.105235)
			(xy 58.938406 -523.034361) (xy 57.67655 -523.034361) (xy 57.668564 -523.105235) (xy 57.652694 -523.17477)
			(xy 57.629137 -523.24209) (xy 57.598192 -523.306349) (xy 57.560246 -523.36674) (xy 57.515777 -523.422502)
			(xy 57.465344 -523.472935) (xy 57.409582 -523.517404) (xy 57.349191 -523.55535) (xy 57.284932 -523.586295)
			(xy 57.217612 -523.609852) (xy 57.148077 -523.625722) (xy 57.077203 -523.633708) (xy 57.005881 -523.633708)
			(xy 56.935007 -523.625722) (xy 56.865472 -523.609852) (xy 56.798152 -523.586295) (xy 56.733893 -523.55535)
			(xy 56.673502 -523.517404) (xy 56.61774 -523.472935) (xy 56.567307 -523.422502) (xy 56.522838 -523.36674)
			(xy 56.484892 -523.306349) (xy 56.453947 -523.24209) (xy 56.43039 -523.17477) (xy 56.41452 -523.105235)
			(xy 56.406534 -523.034361) (xy 36.447235 -523.034361) (xy 36.431719 -523.088893) (xy 36.400327 -523.169925)
			(xy 36.361593 -523.247714) (xy 36.315846 -523.321598) (xy 36.263477 -523.390945) (xy 36.204933 -523.455165)
			(xy 36.140713 -523.513709) (xy 36.071366 -523.566078) (xy 35.997482 -523.611825) (xy 35.919693 -523.650559)
			(xy 35.838661 -523.681951) (xy 35.755079 -523.705732) (xy 35.669659 -523.7217) (xy 35.58313 -523.729718)
			(xy 35.49623 -523.729718) (xy 35.409701 -523.7217) (xy 35.324281 -523.705732) (xy 35.240699 -523.681951)
			(xy 35.159667 -523.650559) (xy 35.081878 -523.611825) (xy 35.007994 -523.566078) (xy 34.938647 -523.513709)
			(xy 34.874427 -523.455165) (xy 34.815883 -523.390945) (xy 34.763514 -523.321598) (xy 34.717767 -523.247714)
			(xy 34.679033 -523.169925) (xy 34.647641 -523.088893) (xy 34.62386 -523.005311) (xy 34.607892 -522.919891)
			(xy 34.599874 -522.833362) (xy 31.399486 -522.833362) (xy 31.391468 -522.919891) (xy 31.3755 -523.005311)
			(xy 31.351719 -523.088893) (xy 31.320327 -523.169925) (xy 31.281593 -523.247714) (xy 31.235846 -523.321598)
			(xy 31.183477 -523.390945) (xy 31.124933 -523.455165) (xy 31.060713 -523.513709) (xy 30.991366 -523.566078)
			(xy 30.917482 -523.611825) (xy 30.839693 -523.650559) (xy 30.758661 -523.681951) (xy 30.675079 -523.705732)
			(xy 30.589659 -523.7217) (xy 30.50313 -523.729718) (xy 30.41623 -523.729718) (xy 30.329701 -523.7217)
			(xy 30.244281 -523.705732) (xy 30.160699 -523.681951) (xy 30.079667 -523.650559) (xy 30.001878 -523.611825)
			(xy 29.927994 -523.566078) (xy 29.858647 -523.513709) (xy 29.794427 -523.455165) (xy 29.735883 -523.390945)
			(xy 29.683514 -523.321598) (xy 29.637767 -523.247714) (xy 29.599033 -523.169925) (xy 29.567641 -523.088893)
			(xy 29.54386 -523.005311) (xy 29.527892 -522.919891) (xy 29.519874 -522.833362) (xy 0.509016 -522.833362)
			(xy 0.509016 -523.702449) (xy 4.94918 -523.702449) (xy 4.94918 -523.621339) (xy 4.95713 -523.54062)
			(xy 4.972953 -523.461069) (xy 4.996498 -523.383453) (xy 5.027537 -523.308517) (xy 5.065772 -523.236985)
			(xy 5.110834 -523.169545) (xy 5.162289 -523.106846) (xy 5.219642 -523.049493) (xy 5.282341 -522.998038)
			(xy 5.349781 -522.952976) (xy 5.421313 -522.914741) (xy 5.496249 -522.883702) (xy 5.573865 -522.860157)
			(xy 5.653416 -522.844334) (xy 5.734135 -522.836384) (xy 5.77469 -522.835886) (xy 5.815245 -522.836384)
			(xy 5.895964 -522.844334) (xy 5.975515 -522.860157) (xy 6.053131 -522.883702) (xy 6.128067 -522.914741)
			(xy 6.199599 -522.952976) (xy 6.267039 -522.998038) (xy 6.329738 -523.049493) (xy 6.387091 -523.106846)
			(xy 6.438546 -523.169545) (xy 6.483608 -523.236985) (xy 6.521843 -523.308517) (xy 6.552882 -523.383453)
			(xy 6.576427 -523.461069) (xy 6.59225 -523.54062) (xy 6.6002 -523.621339) (xy 6.6002 -523.702449)
			(xy 7.48918 -523.702449) (xy 7.48918 -523.621339) (xy 7.49713 -523.54062) (xy 7.512953 -523.461069)
			(xy 7.536498 -523.383453) (xy 7.567537 -523.308517) (xy 7.605772 -523.236985) (xy 7.650834 -523.169545)
			(xy 7.702289 -523.106846) (xy 7.759642 -523.049493) (xy 7.822341 -522.998038) (xy 7.889781 -522.952976)
			(xy 7.961313 -522.914741) (xy 8.036249 -522.883702) (xy 8.113865 -522.860157) (xy 8.193416 -522.844334)
			(xy 8.274135 -522.836384) (xy 8.31469 -522.835886) (xy 8.355245 -522.836384) (xy 8.435964 -522.844334)
			(xy 8.515515 -522.860157) (xy 8.593131 -522.883702) (xy 8.668067 -522.914741) (xy 8.739599 -522.952976)
			(xy 8.807039 -522.998038) (xy 8.869738 -523.049493) (xy 8.927091 -523.106846) (xy 8.978546 -523.169545)
			(xy 9.023608 -523.236985) (xy 9.061843 -523.308517) (xy 9.092882 -523.383453) (xy 9.116427 -523.461069)
			(xy 9.13225 -523.54062) (xy 9.1402 -523.621339) (xy 9.1402 -523.702449) (xy 10.02918 -523.702449)
			(xy 10.02918 -523.621339) (xy 10.03713 -523.54062) (xy 10.052953 -523.461069) (xy 10.076498 -523.383453)
			(xy 10.107537 -523.308517) (xy 10.145772 -523.236985) (xy 10.190834 -523.169545) (xy 10.242289 -523.106846)
			(xy 10.299642 -523.049493) (xy 10.362341 -522.998038) (xy 10.429781 -522.952976) (xy 10.501313 -522.914741)
			(xy 10.576249 -522.883702) (xy 10.653865 -522.860157) (xy 10.733416 -522.844334) (xy 10.814135 -522.836384)
			(xy 10.85469 -522.835886) (xy 10.895245 -522.836384) (xy 10.975964 -522.844334) (xy 11.055515 -522.860157)
			(xy 11.133131 -522.883702) (xy 11.208067 -522.914741) (xy 11.279599 -522.952976) (xy 11.347039 -522.998038)
			(xy 11.409738 -523.049493) (xy 11.467091 -523.106846) (xy 11.518546 -523.169545) (xy 11.563608 -523.236985)
			(xy 11.601843 -523.308517) (xy 11.632882 -523.383453) (xy 11.656427 -523.461069) (xy 11.67225 -523.54062)
			(xy 11.6802 -523.621339) (xy 11.6802 -523.702449) (xy 12.56918 -523.702449) (xy 12.56918 -523.621339)
			(xy 12.57713 -523.54062) (xy 12.592953 -523.461069) (xy 12.616498 -523.383453) (xy 12.647537 -523.308517)
			(xy 12.685772 -523.236985) (xy 12.730834 -523.169545) (xy 12.782289 -523.106846) (xy 12.839642 -523.049493)
			(xy 12.902341 -522.998038) (xy 12.969781 -522.952976) (xy 13.041313 -522.914741) (xy 13.116249 -522.883702)
			(xy 13.193865 -522.860157) (xy 13.273416 -522.844334) (xy 13.354135 -522.836384) (xy 13.39469 -522.835886)
			(xy 13.435245 -522.836384) (xy 13.515964 -522.844334) (xy 13.595515 -522.860157) (xy 13.673131 -522.883702)
			(xy 13.748067 -522.914741) (xy 13.819599 -522.952976) (xy 13.887039 -522.998038) (xy 13.949738 -523.049493)
			(xy 14.007091 -523.106846) (xy 14.058546 -523.169545) (xy 14.103608 -523.236985) (xy 14.141843 -523.308517)
			(xy 14.172882 -523.383453) (xy 14.196427 -523.461069) (xy 14.21225 -523.54062) (xy 14.214486 -523.563323)
			(xy 19.66595 -523.563323) (xy 19.67204 -523.492415) (xy 19.686173 -523.422664) (xy 19.708166 -523.354978)
			(xy 19.73773 -523.290241) (xy 19.774482 -523.229295) (xy 19.817941 -523.172936) (xy 19.867541 -523.121899)
			(xy 19.922636 -523.076848) (xy 19.982507 -523.038372) (xy 20.046374 -523.00697) (xy 20.113403 -522.983054)
			(xy 20.182723 -522.966935) (xy 20.253428 -522.958822) (xy 20.289012 -522.958314) (xy 20.324596 -522.958822)
			(xy 20.395301 -522.966935) (xy 20.464621 -522.983054) (xy 20.53165 -523.00697) (xy 20.595517 -523.038372)
			(xy 20.655388 -523.076848) (xy 20.710483 -523.121899) (xy 20.760083 -523.172936) (xy 20.803542 -523.229295)
			(xy 20.840294 -523.290241) (xy 20.869858 -523.354978) (xy 20.891851 -523.422664) (xy 20.905984 -523.492415)
			(xy 20.912074 -523.563323) (xy 20.910042 -523.634462) (xy 20.899914 -523.704907) (xy 20.881821 -523.773737)
			(xy 20.856001 -523.840057) (xy 20.822788 -523.903001) (xy 20.782618 -523.961749) (xy 20.736012 -524.015535)
			(xy 20.683579 -524.063657) (xy 20.626002 -524.105489) (xy 20.564032 -524.140485) (xy 20.498477 -524.168189)
			(xy 20.430191 -524.18824) (xy 20.360065 -524.200376) (xy 20.289012 -524.204439) (xy 20.217959 -524.200376)
			(xy 20.147833 -524.18824) (xy 20.079547 -524.168189) (xy 20.013992 -524.140485) (xy 19.952022 -524.105489)
			(xy 19.894445 -524.063657) (xy 19.842012 -524.015535) (xy 19.795406 -523.961749) (xy 19.755236 -523.903001)
			(xy 19.722023 -523.840057) (xy 19.696203 -523.773737) (xy 19.67811 -523.704907) (xy 19.667982 -523.634462)
			(xy 19.66595 -523.563323) (xy 14.214486 -523.563323) (xy 14.2202 -523.621339) (xy 14.2202 -523.702449)
			(xy 14.21225 -523.783168) (xy 14.196427 -523.862719) (xy 14.172882 -523.940335) (xy 14.141843 -524.015271)
			(xy 14.103608 -524.086803) (xy 14.058546 -524.154243) (xy 14.007091 -524.216942) (xy 13.949738 -524.274295)
			(xy 13.887039 -524.32575) (xy 13.819599 -524.370812) (xy 13.784442 -524.389604) (xy 29.519372 -524.389604)
			(xy 31.399988 -524.389604) (xy 31.399988 -525.373362) (xy 34.599874 -525.373362) (xy 34.599874 -525.286462)
			(xy 34.607892 -525.199933) (xy 34.62386 -525.114513) (xy 34.647641 -525.030931) (xy 34.679033 -524.949899)
			(xy 34.717767 -524.87211) (xy 34.763514 -524.798226) (xy 34.815883 -524.728879) (xy 34.874427 -524.664659)
			(xy 34.938647 -524.606115) (xy 35.007994 -524.553746) (xy 35.081878 -524.507999) (xy 35.159667 -524.469265)
			(xy 35.240699 -524.437873) (xy 35.324281 -524.414092) (xy 35.409701 -524.398124) (xy 35.49623 -524.390106)
			(xy 35.53968 -524.389604) (xy 35.58313 -524.390106) (xy 35.669659 -524.398124) (xy 35.755079 -524.414092)
			(xy 35.838661 -524.437873) (xy 35.919693 -524.469265) (xy 35.997482 -524.507999) (xy 36.071366 -524.553746)
			(xy 36.140713 -524.606115) (xy 36.204933 -524.664659) (xy 36.263477 -524.728879) (xy 36.315846 -524.798226)
			(xy 36.361593 -524.87211) (xy 36.400327 -524.949899) (xy 36.431719 -525.030931) (xy 36.4555 -525.114513)
			(xy 36.467343 -525.177867) (xy 56.406534 -525.177867) (xy 56.406534 -525.106545) (xy 56.41452 -525.035671)
			(xy 56.43039 -524.966136) (xy 56.453947 -524.898816) (xy 56.484892 -524.834557) (xy 56.522838 -524.774166)
			(xy 56.567307 -524.718404) (xy 56.61774 -524.667971) (xy 56.673502 -524.623502) (xy 56.733893 -524.585556)
			(xy 56.798152 -524.554611) (xy 56.865472 -524.531054) (xy 56.935007 -524.515184) (xy 57.005881 -524.507198)
			(xy 57.041542 -524.506698) (xy 57.077203 -524.507198) (xy 57.148077 -524.515184) (xy 57.217612 -524.531054)
			(xy 57.284932 -524.554611) (xy 57.349191 -524.585556) (xy 57.409582 -524.623502) (xy 57.465344 -524.667971)
			(xy 57.515777 -524.718404) (xy 57.560246 -524.774166) (xy 57.598192 -524.834557) (xy 57.629137 -524.898816)
			(xy 57.652694 -524.966136) (xy 57.668564 -525.035671) (xy 57.67655 -525.106545) (xy 57.67655 -525.177867)
			(xy 58.938406 -525.177867) (xy 58.938406 -525.106545) (xy 58.946392 -525.035671) (xy 58.962262 -524.966136)
			(xy 58.985819 -524.898816) (xy 59.016764 -524.834557) (xy 59.05471 -524.774166) (xy 59.099179 -524.718404)
			(xy 59.149612 -524.667971) (xy 59.205374 -524.623502) (xy 59.265765 -524.585556) (xy 59.330024 -524.554611)
			(xy 59.397344 -524.531054) (xy 59.466879 -524.515184) (xy 59.537753 -524.507198) (xy 59.573414 -524.506698)
			(xy 59.609075 -524.507198) (xy 59.679949 -524.515184) (xy 59.749484 -524.531054) (xy 59.816804 -524.554611)
			(xy 59.881063 -524.585556) (xy 59.941454 -524.623502) (xy 59.997216 -524.667971) (xy 60.047649 -524.718404)
			(xy 60.092118 -524.774166) (xy 60.130064 -524.834557) (xy 60.161009 -524.898816) (xy 60.184566 -524.966136)
			(xy 60.200436 -525.035671) (xy 60.208422 -525.106545) (xy 60.208422 -525.177867) (xy 61.74282 -525.177867)
			(xy 61.74282 -525.106545) (xy 61.750806 -525.035671) (xy 61.766676 -524.966136) (xy 61.790233 -524.898816)
			(xy 61.821178 -524.834557) (xy 61.859124 -524.774166) (xy 61.903593 -524.718404) (xy 61.954026 -524.667971)
			(xy 62.009788 -524.623502) (xy 62.070179 -524.585556) (xy 62.134438 -524.554611) (xy 62.201758 -524.531054)
			(xy 62.271293 -524.515184) (xy 62.342167 -524.507198) (xy 62.377828 -524.506698) (xy 62.413489 -524.507198)
			(xy 62.484363 -524.515184) (xy 62.553898 -524.531054) (xy 62.621218 -524.554611) (xy 62.685477 -524.585556)
			(xy 62.745868 -524.623502) (xy 62.80163 -524.667971) (xy 62.852063 -524.718404) (xy 62.896532 -524.774166)
			(xy 62.934478 -524.834557) (xy 62.965423 -524.898816) (xy 62.98898 -524.966136) (xy 63.00485 -525.035671)
			(xy 63.012836 -525.106545) (xy 63.012836 -525.177867) (xy 64.98259 -525.177867) (xy 64.98259 -525.106545)
			(xy 64.990576 -525.035671) (xy 65.006446 -524.966136) (xy 65.030003 -524.898816) (xy 65.060948 -524.834557)
			(xy 65.098894 -524.774166) (xy 65.143363 -524.718404) (xy 65.193796 -524.667971) (xy 65.249558 -524.623502)
			(xy 65.309949 -524.585556) (xy 65.374208 -524.554611) (xy 65.441528 -524.531054) (xy 65.511063 -524.515184)
			(xy 65.581937 -524.507198) (xy 65.617598 -524.506698) (xy 65.653259 -524.507198) (xy 65.724133 -524.515184)
			(xy 65.793668 -524.531054) (xy 65.860988 -524.554611) (xy 65.925247 -524.585556) (xy 65.985638 -524.623502)
			(xy 66.0414 -524.667971) (xy 66.091833 -524.718404) (xy 66.136302 -524.774166) (xy 66.174248 -524.834557)
			(xy 66.205193 -524.898816) (xy 66.22875 -524.966136) (xy 66.24462 -525.035671) (xy 66.252606 -525.106545)
			(xy 66.252606 -525.177867) (xy 67.974202 -525.177867) (xy 67.974202 -525.106545) (xy 67.982188 -525.035671)
			(xy 67.998058 -524.966136) (xy 68.021615 -524.898816) (xy 68.05256 -524.834557) (xy 68.090506 -524.774166)
			(xy 68.134975 -524.718404) (xy 68.185408 -524.667971) (xy 68.24117 -524.623502) (xy 68.301561 -524.585556)
			(xy 68.36582 -524.554611) (xy 68.43314 -524.531054) (xy 68.502675 -524.515184) (xy 68.573549 -524.507198)
			(xy 68.60921 -524.506698) (xy 68.644871 -524.507198) (xy 68.715745 -524.515184) (xy 68.78528 -524.531054)
			(xy 68.8526 -524.554611) (xy 68.916859 -524.585556) (xy 68.97725 -524.623502) (xy 69.033012 -524.667971)
			(xy 69.083445 -524.718404) (xy 69.127914 -524.774166) (xy 69.16586 -524.834557) (xy 69.196805 -524.898816)
			(xy 69.220362 -524.966136) (xy 69.236232 -525.035671) (xy 69.244218 -525.106545) (xy 69.244218 -525.177867)
			(xy 69.236232 -525.248741) (xy 69.220362 -525.318276) (xy 69.196805 -525.385596) (xy 69.16586 -525.449855)
			(xy 69.127914 -525.510246) (xy 69.083445 -525.566008) (xy 69.033012 -525.616441) (xy 68.97725 -525.66091)
			(xy 68.916859 -525.698856) (xy 68.8526 -525.729801) (xy 68.78528 -525.753358) (xy 68.715745 -525.769228)
			(xy 68.644871 -525.777214) (xy 68.573549 -525.777214) (xy 68.502675 -525.769228) (xy 68.43314 -525.753358)
			(xy 68.36582 -525.729801) (xy 68.301561 -525.698856) (xy 68.24117 -525.66091) (xy 68.185408 -525.616441)
			(xy 68.134975 -525.566008) (xy 68.090506 -525.510246) (xy 68.05256 -525.449855) (xy 68.021615 -525.385596)
			(xy 67.998058 -525.318276) (xy 67.982188 -525.248741) (xy 67.974202 -525.177867) (xy 66.252606 -525.177867)
			(xy 66.24462 -525.248741) (xy 66.22875 -525.318276) (xy 66.205193 -525.385596) (xy 66.174248 -525.449855)
			(xy 66.136302 -525.510246) (xy 66.091833 -525.566008) (xy 66.0414 -525.616441) (xy 65.985638 -525.66091)
			(xy 65.925247 -525.698856) (xy 65.860988 -525.729801) (xy 65.793668 -525.753358) (xy 65.724133 -525.769228)
			(xy 65.653259 -525.777214) (xy 65.581937 -525.777214) (xy 65.511063 -525.769228) (xy 65.441528 -525.753358)
			(xy 65.374208 -525.729801) (xy 65.309949 -525.698856) (xy 65.249558 -525.66091) (xy 65.193796 -525.616441)
			(xy 65.143363 -525.566008) (xy 65.098894 -525.510246) (xy 65.060948 -525.449855) (xy 65.030003 -525.385596)
			(xy 65.006446 -525.318276) (xy 64.990576 -525.248741) (xy 64.98259 -525.177867) (xy 63.012836 -525.177867)
			(xy 63.00485 -525.248741) (xy 62.98898 -525.318276) (xy 62.965423 -525.385596) (xy 62.934478 -525.449855)
			(xy 62.896532 -525.510246) (xy 62.852063 -525.566008) (xy 62.80163 -525.616441) (xy 62.745868 -525.66091)
			(xy 62.685477 -525.698856) (xy 62.621218 -525.729801) (xy 62.553898 -525.753358) (xy 62.484363 -525.769228)
			(xy 62.413489 -525.777214) (xy 62.342167 -525.777214) (xy 62.271293 -525.769228) (xy 62.201758 -525.753358)
			(xy 62.134438 -525.729801) (xy 62.070179 -525.698856) (xy 62.009788 -525.66091) (xy 61.954026 -525.616441)
			(xy 61.903593 -525.566008) (xy 61.859124 -525.510246) (xy 61.821178 -525.449855) (xy 61.790233 -525.385596)
			(xy 61.766676 -525.318276) (xy 61.750806 -525.248741) (xy 61.74282 -525.177867) (xy 60.208422 -525.177867)
			(xy 60.200436 -525.248741) (xy 60.184566 -525.318276) (xy 60.161009 -525.385596) (xy 60.130064 -525.449855)
			(xy 60.092118 -525.510246) (xy 60.047649 -525.566008) (xy 59.997216 -525.616441) (xy 59.941454 -525.66091)
			(xy 59.881063 -525.698856) (xy 59.816804 -525.729801) (xy 59.749484 -525.753358) (xy 59.679949 -525.769228)
			(xy 59.609075 -525.777214) (xy 59.537753 -525.777214) (xy 59.466879 -525.769228) (xy 59.397344 -525.753358)
			(xy 59.330024 -525.729801) (xy 59.265765 -525.698856) (xy 59.205374 -525.66091) (xy 59.149612 -525.616441)
			(xy 59.099179 -525.566008) (xy 59.05471 -525.510246) (xy 59.016764 -525.449855) (xy 58.985819 -525.385596)
			(xy 58.962262 -525.318276) (xy 58.946392 -525.248741) (xy 58.938406 -525.177867) (xy 57.67655 -525.177867)
			(xy 57.668564 -525.248741) (xy 57.652694 -525.318276) (xy 57.629137 -525.385596) (xy 57.598192 -525.449855)
			(xy 57.560246 -525.510246) (xy 57.515777 -525.566008) (xy 57.465344 -525.616441) (xy 57.409582 -525.66091)
			(xy 57.349191 -525.698856) (xy 57.284932 -525.729801) (xy 57.217612 -525.753358) (xy 57.148077 -525.769228)
			(xy 57.077203 -525.777214) (xy 57.005881 -525.777214) (xy 56.935007 -525.769228) (xy 56.865472 -525.753358)
			(xy 56.798152 -525.729801) (xy 56.733893 -525.698856) (xy 56.673502 -525.66091) (xy 56.61774 -525.616441)
			(xy 56.567307 -525.566008) (xy 56.522838 -525.510246) (xy 56.484892 -525.449855) (xy 56.453947 -525.385596)
			(xy 56.43039 -525.318276) (xy 56.41452 -525.248741) (xy 56.406534 -525.177867) (xy 36.467343 -525.177867)
			(xy 36.471468 -525.199933) (xy 36.479486 -525.286462) (xy 36.479486 -525.373362) (xy 36.471468 -525.459891)
			(xy 36.4555 -525.545311) (xy 36.431719 -525.628893) (xy 36.400327 -525.709925) (xy 36.361593 -525.787714)
			(xy 36.315846 -525.861598) (xy 36.263477 -525.930945) (xy 36.204933 -525.995165) (xy 36.140713 -526.053709)
			(xy 36.071366 -526.106078) (xy 35.997482 -526.151825) (xy 35.919693 -526.190559) (xy 35.838661 -526.221951)
			(xy 35.755079 -526.245732) (xy 35.669659 -526.2617) (xy 35.58313 -526.269718) (xy 35.49623 -526.269718)
			(xy 35.409701 -526.2617) (xy 35.324281 -526.245732) (xy 35.240699 -526.221951) (xy 35.159667 -526.190559)
			(xy 35.081878 -526.151825) (xy 35.007994 -526.106078) (xy 34.938647 -526.053709) (xy 34.874427 -525.995165)
			(xy 34.815883 -525.930945) (xy 34.763514 -525.861598) (xy 34.717767 -525.787714) (xy 34.679033 -525.709925)
			(xy 34.647641 -525.628893) (xy 34.62386 -525.545311) (xy 34.607892 -525.459891) (xy 34.599874 -525.373362)
			(xy 31.399988 -525.373362) (xy 31.399988 -526.27022) (xy 29.519372 -526.27022) (xy 29.519372 -524.389604)
			(xy 13.784442 -524.389604) (xy 13.748067 -524.409047) (xy 13.673131 -524.440086) (xy 13.595515 -524.463631)
			(xy 13.515964 -524.479454) (xy 13.435245 -524.487404) (xy 13.354135 -524.487404) (xy 13.273416 -524.479454)
			(xy 13.193865 -524.463631) (xy 13.116249 -524.440086) (xy 13.041313 -524.409047) (xy 12.969781 -524.370812)
			(xy 12.902341 -524.32575) (xy 12.839642 -524.274295) (xy 12.782289 -524.216942) (xy 12.730834 -524.154243)
			(xy 12.685772 -524.086803) (xy 12.647537 -524.015271) (xy 12.616498 -523.940335) (xy 12.592953 -523.862719)
			(xy 12.57713 -523.783168) (xy 12.56918 -523.702449) (xy 11.6802 -523.702449) (xy 11.67225 -523.783168)
			(xy 11.656427 -523.862719) (xy 11.632882 -523.940335) (xy 11.601843 -524.015271) (xy 11.563608 -524.086803)
			(xy 11.518546 -524.154243) (xy 11.467091 -524.216942) (xy 11.409738 -524.274295) (xy 11.347039 -524.32575)
			(xy 11.279599 -524.370812) (xy 11.208067 -524.409047) (xy 11.133131 -524.440086) (xy 11.055515 -524.463631)
			(xy 10.975964 -524.479454) (xy 10.895245 -524.487404) (xy 10.814135 -524.487404) (xy 10.733416 -524.479454)
			(xy 10.653865 -524.463631) (xy 10.576249 -524.440086) (xy 10.501313 -524.409047) (xy 10.429781 -524.370812)
			(xy 10.362341 -524.32575) (xy 10.299642 -524.274295) (xy 10.242289 -524.216942) (xy 10.190834 -524.154243)
			(xy 10.145772 -524.086803) (xy 10.107537 -524.015271) (xy 10.076498 -523.940335) (xy 10.052953 -523.862719)
			(xy 10.03713 -523.783168) (xy 10.02918 -523.702449) (xy 9.1402 -523.702449) (xy 9.13225 -523.783168)
			(xy 9.116427 -523.862719) (xy 9.092882 -523.940335) (xy 9.061843 -524.015271) (xy 9.023608 -524.086803)
			(xy 8.978546 -524.154243) (xy 8.927091 -524.216942) (xy 8.869738 -524.274295) (xy 8.807039 -524.32575)
			(xy 8.739599 -524.370812) (xy 8.668067 -524.409047) (xy 8.593131 -524.440086) (xy 8.515515 -524.463631)
			(xy 8.435964 -524.479454) (xy 8.355245 -524.487404) (xy 8.274135 -524.487404) (xy 8.193416 -524.479454)
			(xy 8.113865 -524.463631) (xy 8.036249 -524.440086) (xy 7.961313 -524.409047) (xy 7.889781 -524.370812)
			(xy 7.822341 -524.32575) (xy 7.759642 -524.274295) (xy 7.702289 -524.216942) (xy 7.650834 -524.154243)
			(xy 7.605772 -524.086803) (xy 7.567537 -524.015271) (xy 7.536498 -523.940335) (xy 7.512953 -523.862719)
			(xy 7.49713 -523.783168) (xy 7.48918 -523.702449) (xy 6.6002 -523.702449) (xy 6.59225 -523.783168)
			(xy 6.576427 -523.862719) (xy 6.552882 -523.940335) (xy 6.521843 -524.015271) (xy 6.483608 -524.086803)
			(xy 6.438546 -524.154243) (xy 6.387091 -524.216942) (xy 6.329738 -524.274295) (xy 6.267039 -524.32575)
			(xy 6.199599 -524.370812) (xy 6.128067 -524.409047) (xy 6.053131 -524.440086) (xy 5.975515 -524.463631)
			(xy 5.895964 -524.479454) (xy 5.815245 -524.487404) (xy 5.734135 -524.487404) (xy 5.653416 -524.479454)
			(xy 5.573865 -524.463631) (xy 5.496249 -524.440086) (xy 5.421313 -524.409047) (xy 5.349781 -524.370812)
			(xy 5.282341 -524.32575) (xy 5.219642 -524.274295) (xy 5.162289 -524.216942) (xy 5.110834 -524.154243)
			(xy 5.065772 -524.086803) (xy 5.027537 -524.015271) (xy 4.996498 -523.940335) (xy 4.972953 -523.862719)
			(xy 4.95713 -523.783168) (xy 4.94918 -523.702449) (xy 0.509016 -523.702449) (xy 0.509016 -524.500094)
			(xy 0.509529 -524.54588) (xy 0.517978 -524.637062) (xy 0.534804 -524.727075) (xy 0.559864 -524.815152)
			(xy 0.592944 -524.900541) (xy 0.633761 -524.982513) (xy 0.681968 -525.06037) (xy 0.737153 -525.133446)
			(xy 0.798845 -525.201119) (xy 0.866518 -525.262811) (xy 0.939594 -525.317996) (xy 1.017451 -525.366203)
			(xy 1.099423 -525.40702) (xy 1.184812 -525.4401) (xy 1.272889 -525.46516) (xy 1.362902 -525.481986)
			(xy 1.454084 -525.490435) (xy 1.49987 -525.490948) (xy 23.50008 -525.490948) (xy 23.563202 -525.491433)
			(xy 23.689196 -525.499359) (xy 23.814444 -525.515182) (xy 23.93845 -525.538839) (xy 24.060727 -525.570236)
			(xy 24.180791 -525.60925) (xy 24.298167 -525.655726) (xy 24.412394 -525.709482) (xy 24.523019 -525.770304)
			(xy 24.629607 -525.837954) (xy 24.731736 -525.912163) (xy 24.829004 -525.992639) (xy 24.921025 -526.079064)
			(xy 25.007438 -526.171097) (xy 25.087902 -526.268376) (xy 25.162097 -526.370515) (xy 25.229732 -526.477111)
			(xy 25.29054 -526.587745) (xy 25.34428 -526.701979) (xy 25.390741 -526.819362) (xy 25.429739 -526.93943)
			(xy 25.46112 -527.061711) (xy 25.48476 -527.185721) (xy 25.500566 -527.310971) (xy 25.508475 -527.436966)
			(xy 25.508966 -527.500088) (xy 25.508966 -528.500086) (xy 25.509507 -528.545875) (xy 25.517982 -528.637061)
			(xy 25.534832 -528.727076) (xy 25.559914 -528.815153) (xy 25.593014 -528.90054) (xy 25.633851 -528.98251)
			(xy 25.682074 -529.060363) (xy 25.737274 -529.133435) (xy 25.79898 -529.201104) (xy 25.866665 -529.262792)
			(xy 25.939752 -529.317973) (xy 26.017618 -529.366176) (xy 26.099598 -529.406991) (xy 26.184994 -529.440069)
			(xy 26.273077 -529.465128) (xy 26.363097 -529.481954) (xy 26.454285 -529.490405) (xy 26.500074 -529.49094)
		)
		(stroke
			(width 0)
			(type solid)
		)
		(fill yes)
		(layer "B.Cu")
		(net "GND")
	)
	(gr_line
		(start 3.189224 -348.146878)
		(end 3.216402 -348.092522)
		(stroke
			(width 0.0635)
			(type default)
		)
		(layer "B.Cu")
	)
	(gr_line
		(start 3.189224 -348.146878)
		(end 3.245866 -348.317312)
		(stroke
			(width 0.0635)
			(type default)
		)
		(layer "B.Cu")
	)
	(gr_line
		(start 3.245866 -348.317312)
		(end 3.949954 -348.669864)
		(stroke
			(width 0.0635)
			(type default)
		)
		(layer "B.Cu")
	)
	(gr_line
		(start 7.36473 -409.699968)
		(end 8.193278 -409.699968)
		(stroke
			(width 0.0635)
			(type default)
		)
		(layer "B.Cu")
	)
	(gr_line
		(start 7.487412 -188.547756)
		(end 7.511034 -188.500766)
		(stroke
			(width 0.0635)
			(type default)
		)
		(layer "B.Cu")
	)
	(gr_line
		(start 7.51713 -188.488828)
		(end 7.57428 -188.375036)
		(stroke
			(width 0.0635)
			(type default)
		)
		(layer "B.Cu")
	)
	(gr_line
		(start 7.57428 -188.375036)
		(end 7.744714 -188.317886)
		(stroke
			(width 0.0635)
			(type default)
		)
		(layer "B.Cu")
	)
	(gr_line
		(start 7.744714 -188.317886)
		(end 8.448802 -188.670438)
		(stroke
			(width 0.0635)
			(type default)
		)
		(layer "B.Cu")
	)
	(gr_line
		(start 8.193278 -409.699968)
		(end 9.438894 -408.454352)
		(stroke
			(width 0.0635)
			(type default)
		)
		(layer "B.Cu")
	)
	(gr_line
		(start 9.166098 -357.59771)
		(end 9.350248 -357.78186)
		(stroke
			(width 0.0635)
			(type default)
		)
		(layer "B.Cu")
	)
	(gr_line
		(start 9.166098 -357.21671)
		(end 9.166098 -357.59771)
		(stroke
			(width 0.0635)
			(type default)
		)
		(layer "B.Cu")
	)
	(gr_line
		(start 9.166098 -357.21671)
		(end 9.350248 -357.03256)
		(stroke
			(width 0.0635)
			(type default)
		)
		(layer "B.Cu")
	)
	(gr_line
		(start 9.166098 -356.466902)
		(end 9.350248 -356.651052)
		(stroke
			(width 0.0635)
			(type default)
		)
		(layer "B.Cu")
	)
	(gr_line
		(start 9.166098 -356.085902)
		(end 9.166098 -356.466902)
		(stroke
			(width 0.0635)
			(type default)
		)
		(layer "B.Cu")
	)
	(gr_line
		(start 9.166098 -356.085902)
		(end 9.350248 -355.901752)
		(stroke
			(width 0.0635)
			(type default)
		)
		(layer "B.Cu")
	)
	(gr_line
		(start 9.166098 -355.336094)
		(end 9.350248 -355.520244)
		(stroke
			(width 0.0635)
			(type default)
		)
		(layer "B.Cu")
	)
	(gr_line
		(start 9.166098 -354.955094)
		(end 9.166098 -355.336094)
		(stroke
			(width 0.0635)
			(type default)
		)
		(layer "B.Cu")
	)
	(gr_line
		(start 9.166098 -354.955094)
		(end 9.350248 -354.770944)
		(stroke
			(width 0.0635)
			(type default)
		)
		(layer "B.Cu")
	)
	(gr_line
		(start 9.166098 -354.205286)
		(end 9.350248 -354.389436)
		(stroke
			(width 0.0635)
			(type default)
		)
		(layer "B.Cu")
	)
	(gr_line
		(start 9.166098 -353.824286)
		(end 9.166098 -354.205286)
		(stroke
			(width 0.0635)
			(type default)
		)
		(layer "B.Cu")
	)
	(gr_line
		(start 9.166098 -353.824286)
		(end 9.350248 -353.640136)
		(stroke
			(width 0.0635)
			(type default)
		)
		(layer "B.Cu")
	)
	(gr_line
		(start 9.166098 -353.074478)
		(end 9.350248 -353.258628)
		(stroke
			(width 0.0635)
			(type default)
		)
		(layer "B.Cu")
	)
	(gr_line
		(start 9.166098 -352.693478)
		(end 9.166098 -353.074478)
		(stroke
			(width 0.0635)
			(type default)
		)
		(layer "B.Cu")
	)
	(gr_line
		(start 9.166098 -352.693478)
		(end 9.350248 -352.509328)
		(stroke
			(width 0.0635)
			(type default)
		)
		(layer "B.Cu")
	)
	(gr_line
		(start 9.95045 -406.205944)
		(end 10.115804 -406.371298)
		(stroke
			(width 0.0635)
			(type default)
		)
		(layer "B.Cu")
	)
	(gr_line
		(start 9.95045 -405.824944)
		(end 9.95045 -406.205944)
		(stroke
			(width 0.0635)
			(type default)
		)
		(layer "B.Cu")
	)
	(gr_line
		(start 9.95045 -405.824944)
		(end 10.115804 -405.65959)
		(stroke
			(width 0.0635)
			(type default)
		)
		(layer "B.Cu")
	)
	(gr_line
		(start 9.95045 -405.112728)
		(end 10.115804 -405.278082)
		(stroke
			(width 0.0635)
			(type default)
		)
		(layer "B.Cu")
	)
	(gr_line
		(start 9.95045 -404.731728)
		(end 9.95045 -405.112728)
		(stroke
			(width 0.0635)
			(type default)
		)
		(layer "B.Cu")
	)
	(gr_line
		(start 9.95045 -404.731728)
		(end 10.115804 -404.566374)
		(stroke
			(width 0.0635)
			(type default)
		)
		(layer "B.Cu")
	)
	(gr_line
		(start 9.95045 -404.019512)
		(end 10.115804 -404.184866)
		(stroke
			(width 0.0635)
			(type default)
		)
		(layer "B.Cu")
	)
	(gr_line
		(start 9.95045 -403.638512)
		(end 9.95045 -404.019512)
		(stroke
			(width 0.0635)
			(type default)
		)
		(layer "B.Cu")
	)
	(gr_line
		(start 9.95045 -403.638512)
		(end 10.115804 -403.473158)
		(stroke
			(width 0.0635)
			(type default)
		)
		(layer "B.Cu")
	)
	(gr_line
		(start 9.95045 -402.926296)
		(end 10.115804 -403.09165)
		(stroke
			(width 0.0635)
			(type default)
		)
		(layer "B.Cu")
	)
	(gr_line
		(start 9.95045 -402.545296)
		(end 9.95045 -402.926296)
		(stroke
			(width 0.0635)
			(type default)
		)
		(layer "B.Cu")
	)
	(gr_line
		(start 9.95045 -402.545296)
		(end 10.115804 -402.379942)
		(stroke
			(width 0.0635)
			(type default)
		)
		(layer "B.Cu")
	)
	(gr_line
		(start 9.95045 -401.83308)
		(end 10.115804 -401.998434)
		(stroke
			(width 0.0635)
			(type default)
		)
		(layer "B.Cu")
	)
	(gr_line
		(start 9.95045 -401.45208)
		(end 9.95045 -401.83308)
		(stroke
			(width 0.0635)
			(type default)
		)
		(layer "B.Cu")
	)
	(gr_line
		(start 9.95045 -401.45208)
		(end 10.115804 -401.286726)
		(stroke
			(width 0.0635)
			(type default)
		)
		(layer "B.Cu")
	)
	(gr_line
		(start 9.95045 -400.739864)
		(end 10.115804 -400.905218)
		(stroke
			(width 0.0635)
			(type default)
		)
		(layer "B.Cu")
	)
	(gr_line
		(start 9.95045 -400.358864)
		(end 9.95045 -400.739864)
		(stroke
			(width 0.0635)
			(type default)
		)
		(layer "B.Cu")
	)
	(gr_line
		(start 9.95045 -400.358864)
		(end 10.115804 -400.19351)
		(stroke
			(width 0.0635)
			(type default)
		)
		(layer "B.Cu")
	)
	(gr_line
		(start 9.95045 -399.646648)
		(end 10.115804 -399.812002)
		(stroke
			(width 0.0635)
			(type default)
		)
		(layer "B.Cu")
	)
	(gr_line
		(start 9.95045 -399.265648)
		(end 9.95045 -399.646648)
		(stroke
			(width 0.0635)
			(type default)
		)
		(layer "B.Cu")
	)
	(gr_line
		(start 9.95045 -399.265648)
		(end 10.115804 -399.100294)
		(stroke
			(width 0.0635)
			(type default)
		)
		(layer "B.Cu")
	)
	(gr_line
		(start 9.95045 -398.553432)
		(end 10.115804 -398.718786)
		(stroke
			(width 0.0635)
			(type default)
		)
		(layer "B.Cu")
	)
	(gr_line
		(start 9.95045 -398.172432)
		(end 9.95045 -398.553432)
		(stroke
			(width 0.0635)
			(type default)
		)
		(layer "B.Cu")
	)
	(gr_line
		(start 9.95045 -398.172432)
		(end 10.115804 -398.007078)
		(stroke
			(width 0.0635)
			(type default)
		)
		(layer "B.Cu")
	)
	(gr_line
		(start 9.95045 -397.460216)
		(end 10.115804 -397.62557)
		(stroke
			(width 0.0635)
			(type default)
		)
		(layer "B.Cu")
	)
	(gr_line
		(start 9.95045 -397.079216)
		(end 9.95045 -397.460216)
		(stroke
			(width 0.0635)
			(type default)
		)
		(layer "B.Cu")
	)
	(gr_line
		(start 9.95045 -397.079216)
		(end 10.115804 -396.913862)
		(stroke
			(width 0.0635)
			(type default)
		)
		(layer "B.Cu")
	)
	(gr_line
		(start 9.95045 -396.367)
		(end 10.115804 -396.532354)
		(stroke
			(width 0.0635)
			(type default)
		)
		(layer "B.Cu")
	)
	(gr_line
		(start 9.95045 -395.986)
		(end 9.95045 -396.367)
		(stroke
			(width 0.0635)
			(type default)
		)
		(layer "B.Cu")
	)
	(gr_line
		(start 9.95045 -395.986)
		(end 10.115804 -395.820646)
		(stroke
			(width 0.0635)
			(type default)
		)
		(layer "B.Cu")
	)
	(gr_line
		(start 9.95045 -395.273784)
		(end 10.115804 -395.439138)
		(stroke
			(width 0.0635)
			(type default)
		)
		(layer "B.Cu")
	)
	(gr_line
		(start 9.95045 -394.892784)
		(end 9.95045 -395.273784)
		(stroke
			(width 0.0635)
			(type default)
		)
		(layer "B.Cu")
	)
	(gr_line
		(start 9.95045 -394.892784)
		(end 10.115804 -394.72743)
		(stroke
			(width 0.0635)
			(type default)
		)
		(layer "B.Cu")
	)
	(gr_line
		(start 9.95045 -394.180568)
		(end 10.115804 -394.345922)
		(stroke
			(width 0.0635)
			(type default)
		)
		(layer "B.Cu")
	)
	(gr_line
		(start 9.95045 -393.799568)
		(end 9.95045 -394.180568)
		(stroke
			(width 0.0635)
			(type default)
		)
		(layer "B.Cu")
	)
	(gr_line
		(start 9.95045 -393.799568)
		(end 10.115804 -393.634214)
		(stroke
			(width 0.0635)
			(type default)
		)
		(layer "B.Cu")
	)
	(gr_line
		(start 9.95045 -393.087352)
		(end 10.115804 -393.252706)
		(stroke
			(width 0.0635)
			(type default)
		)
		(layer "B.Cu")
	)
	(gr_line
		(start 9.95045 -392.706352)
		(end 9.95045 -393.087352)
		(stroke
			(width 0.0635)
			(type default)
		)
		(layer "B.Cu")
	)
	(gr_line
		(start 9.95045 -392.706352)
		(end 10.115804 -392.540998)
		(stroke
			(width 0.0635)
			(type default)
		)
		(layer "B.Cu")
	)
	(gr_line
		(start 11.718036 -156.025342)
		(end 11.947398 -156.254704)
		(stroke
			(width 0.0635)
			(type default)
		)
		(layer "B.Cu")
	)
	(gr_line
		(start 11.718036 -155.644342)
		(end 11.718036 -156.025342)
		(stroke
			(width 0.0635)
			(type default)
		)
		(layer "B.Cu")
	)
	(gr_line
		(start 11.718036 -155.644342)
		(end 11.947398 -155.41498)
		(stroke
			(width 0.0635)
			(type default)
		)
		(layer "B.Cu")
	)
	(gr_line
		(start 11.718036 -154.80411)
		(end 11.947398 -155.033472)
		(stroke
			(width 0.0635)
			(type default)
		)
		(layer "B.Cu")
	)
	(gr_line
		(start 11.718036 -154.42311)
		(end 11.718036 -154.80411)
		(stroke
			(width 0.0635)
			(type default)
		)
		(layer "B.Cu")
	)
	(gr_line
		(start 11.718036 -154.42311)
		(end 11.947398 -154.193748)
		(stroke
			(width 0.0635)
			(type default)
		)
		(layer "B.Cu")
	)
	(gr_line
		(start 11.718036 -153.582878)
		(end 11.947398 -153.81224)
		(stroke
			(width 0.0635)
			(type default)
		)
		(layer "B.Cu")
	)
	(gr_line
		(start 11.718036 -153.201878)
		(end 11.718036 -153.582878)
		(stroke
			(width 0.0635)
			(type default)
		)
		(layer "B.Cu")
	)
	(gr_line
		(start 11.718036 -153.201878)
		(end 11.947398 -152.972516)
		(stroke
			(width 0.0635)
			(type default)
		)
		(layer "B.Cu")
	)
	(gr_line
		(start 11.718036 -152.361646)
		(end 11.947398 -152.591008)
		(stroke
			(width 0.0635)
			(type default)
		)
		(layer "B.Cu")
	)
	(gr_line
		(start 11.718036 -151.980646)
		(end 11.718036 -152.361646)
		(stroke
			(width 0.0635)
			(type default)
		)
		(layer "B.Cu")
	)
	(gr_line
		(start 11.718036 -151.980646)
		(end 11.947398 -151.751284)
		(stroke
			(width 0.0635)
			(type default)
		)
		(layer "B.Cu")
	)
	(gr_line
		(start 11.718036 -151.140414)
		(end 11.947398 -151.369776)
		(stroke
			(width 0.0635)
			(type default)
		)
		(layer "B.Cu")
	)
	(gr_line
		(start 11.718036 -150.759414)
		(end 11.718036 -151.140414)
		(stroke
			(width 0.0635)
			(type default)
		)
		(layer "B.Cu")
	)
	(gr_line
		(start 11.718036 -150.759414)
		(end 11.947398 -150.530052)
		(stroke
			(width 0.0635)
			(type default)
		)
		(layer "B.Cu")
	)
	(gr_line
		(start 11.718036 -149.919182)
		(end 11.947398 -150.148544)
		(stroke
			(width 0.0635)
			(type default)
		)
		(layer "B.Cu")
	)
	(gr_line
		(start 11.718036 -149.538182)
		(end 11.718036 -149.919182)
		(stroke
			(width 0.0635)
			(type default)
		)
		(layer "B.Cu")
	)
	(gr_line
		(start 11.718036 -149.538182)
		(end 11.947398 -149.30882)
		(stroke
			(width 0.0635)
			(type default)
		)
		(layer "B.Cu")
	)
	(gr_line
		(start 11.718036 -148.69795)
		(end 11.947398 -148.927312)
		(stroke
			(width 0.0635)
			(type default)
		)
		(layer "B.Cu")
	)
	(gr_line
		(start 11.718036 -148.31695)
		(end 11.718036 -148.69795)
		(stroke
			(width 0.0635)
			(type default)
		)
		(layer "B.Cu")
	)
	(gr_line
		(start 11.718036 -148.31695)
		(end 11.947398 -148.087588)
		(stroke
			(width 0.0635)
			(type default)
		)
		(layer "B.Cu")
	)
	(gr_line
		(start 11.920474 -139.639802)
		(end 12.07008 -139.789408)
		(stroke
			(width 0.0635)
			(type default)
		)
		(layer "B.Cu")
	)
	(gr_line
		(start 11.920474 -139.258802)
		(end 11.920474 -139.639802)
		(stroke
			(width 0.0635)
			(type default)
		)
		(layer "B.Cu")
	)
	(gr_line
		(start 11.920474 -139.258802)
		(end 12.07008 -139.109196)
		(stroke
			(width 0.0635)
			(type default)
		)
		(layer "B.Cu")
	)
	(gr_line
		(start 11.920474 -138.578082)
		(end 12.07008 -138.727688)
		(stroke
			(width 0.0635)
			(type default)
		)
		(layer "B.Cu")
	)
	(gr_line
		(start 11.920474 -138.197082)
		(end 11.920474 -138.578082)
		(stroke
			(width 0.0635)
			(type default)
		)
		(layer "B.Cu")
	)
	(gr_line
		(start 11.920474 -138.197082)
		(end 12.07008 -138.047476)
		(stroke
			(width 0.0635)
			(type default)
		)
		(layer "B.Cu")
	)
	(gr_line
		(start 11.920474 -137.516362)
		(end 12.07008 -137.665968)
		(stroke
			(width 0.0635)
			(type default)
		)
		(layer "B.Cu")
	)
	(gr_line
		(start 11.920474 -137.135362)
		(end 11.920474 -137.516362)
		(stroke
			(width 0.0635)
			(type default)
		)
		(layer "B.Cu")
	)
	(gr_line
		(start 11.920474 -137.135362)
		(end 12.07008 -136.985756)
		(stroke
			(width 0.0635)
			(type default)
		)
		(layer "B.Cu")
	)
	(gr_line
		(start 11.920474 -136.454642)
		(end 12.07008 -136.604248)
		(stroke
			(width 0.0635)
			(type default)
		)
		(layer "B.Cu")
	)
	(gr_line
		(start 11.920474 -136.073642)
		(end 11.920474 -136.454642)
		(stroke
			(width 0.0635)
			(type default)
		)
		(layer "B.Cu")
	)
	(gr_line
		(start 11.920474 -136.073642)
		(end 12.07008 -135.924036)
		(stroke
			(width 0.0635)
			(type default)
		)
		(layer "B.Cu")
	)
	(gr_line
		(start 12.680442 -134.404862)
		(end 12.680442 -134.690612)
		(stroke
			(width 0.0635)
			(type default)
		)
		(layer "B.Cu")
	)
	(gr_line
		(start 12.680442 -134.404862)
		(end 12.949936 -134.135368)
		(stroke
			(width 0.0635)
			(type default)
		)
		(layer "B.Cu")
	)
	(gr_line
		(start 12.949936 -134.135368)
		(end 13.235686 -134.135368)
		(stroke
			(width 0.0635)
			(type default)
		)
		(layer "B.Cu")
	)
	(gr_line
		(start 13.22705 -130.775964)
		(end 13.2842 -130.60553)
		(stroke
			(width 0.0635)
			(type default)
		)
		(layer "B.Cu")
	)
	(gr_line
		(start 13.22705 -130.775964)
		(end 13.71473 -131.750054)
		(stroke
			(width 0.0635)
			(type default)
		)
		(layer "B.Cu")
	)
	(gr_line
		(start 13.39215 -130.551428)
		(end 13.398246 -130.54838)
		(stroke
			(width 0.0635)
			(type default)
		)
		(layer "B.Cu")
	)
	(gr_line
		(start 13.398246 -130.54838)
		(end 13.457428 -130.518662)
		(stroke
			(width 0.0635)
			(type default)
		)
		(layer "B.Cu")
	)
	(gr_line
		(start 13.457428 -130.518662)
		(end 13.494766 -130.48107)
		(stroke
			(width 0.0635)
			(type default)
		)
		(layer "B.Cu")
	)
	(gr_line
		(start 13.505434 -133.57987)
		(end 13.505434 -133.86562)
		(stroke
			(width 0.0635)
			(type default)
		)
		(layer "B.Cu")
	)
	(gr_line
		(start 13.505434 -133.57987)
		(end 13.774928 -133.310376)
		(stroke
			(width 0.0635)
			(type default)
		)
		(layer "B.Cu")
	)
	(gr_line
		(start 13.774928 -133.310376)
		(end 14.060678 -133.310376)
		(stroke
			(width 0.0635)
			(type default)
		)
		(layer "B.Cu")
	)
	(gr_line
		(start 0 -524.500094)
		(end 0 -5.500116)
		(stroke
			(width 1.016)
			(type default)
		)
		(layer "In1.Cu")
	)
	(gr_arc
		(start 0 -524.500094)
		(mid 0.439393 -525.560749)
		(end 1.500124 -525.999964)
		(stroke
			(width 1.016)
			(type default)
		)
		(layer "In1.Cu")
	)
	(gr_poly
		(pts
			(xy 101.000052 -529.49094) (xy 101.055822 -529.490433) (xy 101.167051 -529.482101) (xy 101.277346 -529.46548)
			(xy 101.38609 -529.440662) (xy 101.492675 -529.407788) (xy 101.596506 -529.367039) (xy 101.697001 -529.318645)
			(xy 101.793598 -529.262876) (xy 101.885758 -529.200044) (xy 101.972964 -529.130501) (xy 102.054729 -529.054635)
			(xy 102.130596 -528.97287) (xy 102.20014 -528.885664) (xy 102.262972 -528.793505) (xy 102.318742 -528.696908)
			(xy 102.367136 -528.596413) (xy 102.407885 -528.492583) (xy 102.44076 -528.385998) (xy 102.465578 -528.277253)
			(xy 102.4822 -528.166959) (xy 102.490533 -528.05573) (xy 102.491032 -527.99996) (xy 102.491032 -1.999996)
			(xy 102.490523 -1.944227) (xy 102.482188 -1.833002) (xy 102.465563 -1.72271) (xy 102.440743 -1.613969)
			(xy 102.407866 -1.507387) (xy 102.367116 -1.40356) (xy 102.31872 -1.303069) (xy 102.26295 -1.206475)
			(xy 102.200118 -1.11432) (xy 102.130574 -1.027117) (xy 102.054708 -0.945356) (xy 101.972944 -0.869492)
			(xy 101.885739 -0.799951) (xy 101.793581 -0.737122) (xy 101.696985 -0.681355) (xy 101.596492 -0.632964)
			(xy 101.492664 -0.592217) (xy 101.386081 -0.559343) (xy 101.277339 -0.534527) (xy 101.167047 -0.517907)
			(xy 101.055821 -0.509575) (xy 101.000052 -0.509016) (xy 26.500074 -0.509016) (xy 26.454278 -0.509546)
			(xy 26.363077 -0.517999) (xy 26.273045 -0.534832) (xy 26.184949 -0.559899) (xy 26.099543 -0.592988)
			(xy 26.017554 -0.633817) (xy 25.939682 -0.682036) (xy 25.866592 -0.737234) (xy 25.798906 -0.798941)
			(xy 25.737202 -0.86663) (xy 25.682007 -0.939724) (xy 25.633792 -1.017598) (xy 25.592968 -1.099589)
			(xy 25.559883 -1.184997) (xy 25.53482 -1.273093) (xy 25.517992 -1.363126) (xy 25.509543 -1.454328)
			(xy 25.508966 -1.500124) (xy 25.508966 -2.500122) (xy 25.50847 -2.563238) (xy 25.500544 -2.689221)
			(xy 25.484723 -2.814458) (xy 25.461069 -2.938455) (xy 25.429676 -3.060721) (xy 25.390668 -3.180775)
			(xy 25.344199 -3.298143) (xy 25.290452 -3.412362) (xy 25.229639 -3.52298) (xy 25.162 -3.629561) (xy 25.087803 -3.731685)
			(xy 25.007339 -3.828949) (xy 24.920927 -3.920968) (xy 24.828907 -4.00738) (xy 24.731644 -4.087844)
			(xy 24.62952 -4.162041) (xy 24.522938 -4.22968) (xy 24.41232 -4.290493) (xy 24.298101 -4.34424) (xy 24.180733 -4.390709)
			(xy 24.060679 -4.429717) (xy 23.938413 -4.46111) (xy 23.814416 -4.484763) (xy 23.689179 -4.500584)
			(xy 23.563196 -4.50851) (xy 23.50008 -4.509008) (xy 1.500124 -4.509008) (xy 1.454327 -4.509537) (xy 1.363123 -4.517988)
			(xy 1.273088 -4.534819) (xy 1.18499 -4.559885) (xy 1.099581 -4.592972) (xy 1.017589 -4.6338) (xy 0.939714 -4.682018)
			(xy 0.86662 -4.737216) (xy 0.798931 -4.798923) (xy 0.737224 -4.866612) (xy 0.682026 -4.939706) (xy 0.633808 -5.017581)
			(xy 0.59298 -5.099573) (xy 0.559893 -5.184982) (xy 0.534827 -5.27308) (xy 0.517996 -5.363115) (xy 0.509545 -5.454319)
			(xy 0.509016 -5.500116) (xy 0.509016 -6.91007) (xy 39.818063 -6.91007) (xy 39.82207 -6.794046) (xy 39.834072 -6.678574)
			(xy 39.854012 -6.564206) (xy 39.881795 -6.451486) (xy 39.917289 -6.340952) (xy 39.960324 -6.233129)
			(xy 40.010695 -6.128532) (xy 40.068162 -6.02766) (xy 40.132452 -5.930993) (xy 40.203257 -5.838992)
			(xy 40.280241 -5.752095) (xy 40.363037 -5.670716) (xy 40.45125 -5.595243) (xy 40.54446 -5.526036)
			(xy 40.642223 -5.463424) (xy 40.744072 -5.407707) (xy 40.849522 -5.359149) (xy 40.958071 -5.317981)
			(xy 41.069202 -5.284401) (xy 41.182385 -5.258568) (xy 41.29708 -5.240605) (xy 41.412742 -5.230597)
			(xy 41.528818 -5.228594) (xy 41.644756 -5.234603) (xy 41.760003 -5.248596) (xy 41.874009 -5.270507)
			(xy 41.986233 -5.300232) (xy 42.096139 -5.337628) (xy 42.203202 -5.382517) (xy 42.306914 -5.434686)
			(xy 42.406779 -5.493886) (xy 42.502322 -5.559835) (xy 42.593088 -5.632218) (xy 42.678643 -5.710691)
			(xy 42.758581 -5.794879) (xy 42.83252 -5.884381) (xy 42.900108 -5.978772) (xy 42.961022 -6.0776)
			(xy 43.014974 -6.180396) (xy 43.061704 -6.286669) (xy 43.100992 -6.395913) (xy 43.132649 -6.507606)
			(xy 43.156525 -6.621218) (xy 43.172506 -6.736206) (xy 43.180515 -6.852023) (xy 43.181016 -6.91007)
			(xy 43.180515 -6.968117) (xy 43.172506 -7.083934) (xy 43.156525 -7.198922) (xy 43.132649 -7.312534)
			(xy 43.100992 -7.424227) (xy 43.061704 -7.533471) (xy 43.014974 -7.639744) (xy 42.961022 -7.74254)
			(xy 42.900108 -7.841368) (xy 42.83252 -7.935759) (xy 42.758581 -8.025261) (xy 42.678643 -8.109449)
			(xy 42.593088 -8.187922) (xy 42.502604 -8.26008) (xy 93.154506 -8.26008) (xy 93.158522 -8.14381)
			(xy 93.170549 -8.028095) (xy 93.190531 -7.913485) (xy 93.218373 -7.800526) (xy 93.253942 -7.689758)
			(xy 93.297068 -7.581707) (xy 93.347545 -7.476889) (xy 93.405134 -7.375804) (xy 93.46956 -7.278932)
			(xy 93.540515 -7.186736) (xy 93.617662 -7.099655) (xy 93.700633 -7.018104) (xy 93.789033 -6.942472)
			(xy 93.88244 -6.873118) (xy 93.980409 -6.810375) (xy 94.082473 -6.754539) (xy 94.188147 -6.705878)
			(xy 94.296926 -6.664624) (xy 94.408291 -6.630973) (xy 94.521714 -6.605085) (xy 94.636651 -6.587084)
			(xy 94.752557 -6.577055) (xy 94.868879 -6.575047) (xy 94.985062 -6.581069) (xy 95.100553 -6.595092)
			(xy 95.214801 -6.61705) (xy 95.327262 -6.646837) (xy 95.4374 -6.684312) (xy 95.54469 -6.729297) (xy 95.648621 -6.781576)
			(xy 95.748697 -6.840901) (xy 95.844443 -6.906989) (xy 95.9354 -6.979525) (xy 96.021136 -7.058164)
			(xy 96.101243 -7.14253) (xy 96.175339 -7.232222) (xy 96.243069 -7.326812) (xy 96.304113 -7.42585)
			(xy 96.358178 -7.528863) (xy 96.405008 -7.63536) (xy 96.444379 -7.744835) (xy 96.476103 -7.856765)
			(xy 96.500029 -7.970617) (xy 96.516043 -8.085849) (xy 96.52407 -8.201911) (xy 96.524572 -8.26008)
			(xy 96.52407 -8.318249) (xy 96.516043 -8.434311) (xy 96.500029 -8.549543) (xy 96.476103 -8.663395)
			(xy 96.444379 -8.775325) (xy 96.405008 -8.8848) (xy 96.358178 -8.991297) (xy 96.304113 -9.09431)
			(xy 96.243069 -9.193348) (xy 96.175339 -9.287938) (xy 96.101243 -9.37763) (xy 96.021136 -9.461996)
			(xy 95.9354 -9.540635) (xy 95.844443 -9.613171) (xy 95.748697 -9.679259) (xy 95.648621 -9.738584)
			(xy 95.54469 -9.790863) (xy 95.4374 -9.835848) (xy 95.327262 -9.873323) (xy 95.214801 -9.90311) (xy 95.100553 -9.925068)
			(xy 94.985062 -9.939091) (xy 94.868879 -9.945113) (xy 94.752557 -9.943105) (xy 94.636651 -9.933076)
			(xy 94.521714 -9.915075) (xy 94.408291 -9.889187) (xy 94.296926 -9.855536) (xy 94.188147 -9.814282)
			(xy 94.082473 -9.765621) (xy 93.980409 -9.709785) (xy 93.88244 -9.647042) (xy 93.789033 -9.577688)
			(xy 93.700633 -9.502056) (xy 93.617662 -9.420505) (xy 93.540515 -9.333424) (xy 93.46956 -9.241228)
			(xy 93.405134 -9.144356) (xy 93.347545 -9.043271) (xy 93.297068 -8.938453) (xy 93.253942 -8.830402)
			(xy 93.218373 -8.719634) (xy 93.190531 -8.606675) (xy 93.170549 -8.492065) (xy 93.158522 -8.37635)
			(xy 93.154506 -8.26008) (xy 42.502604 -8.26008) (xy 42.502322 -8.260305) (xy 42.406779 -8.326254)
			(xy 42.306914 -8.385454) (xy 42.203202 -8.437623) (xy 42.096139 -8.482512) (xy 41.986233 -8.519908)
			(xy 41.874009 -8.549633) (xy 41.760003 -8.571544) (xy 41.644756 -8.585537) (xy 41.528818 -8.591546)
			(xy 41.412742 -8.589543) (xy 41.29708 -8.579535) (xy 41.182385 -8.561572) (xy 41.069202 -8.535739)
			(xy 40.958071 -8.502159) (xy 40.849522 -8.460991) (xy 40.744072 -8.412433) (xy 40.642223 -8.356716)
			(xy 40.54446 -8.294104) (xy 40.45125 -8.224897) (xy 40.363037 -8.149424) (xy 40.280241 -8.068045)
			(xy 40.203257 -7.981148) (xy 40.132452 -7.889147) (xy 40.068162 -7.79248) (xy 40.010695 -7.691608)
			(xy 39.960324 -7.587011) (xy 39.917289 -7.479188) (xy 39.881795 -7.368654) (xy 39.854012 -7.255934)
			(xy 39.834072 -7.141566) (xy 39.82207 -7.026094) (xy 39.818063 -6.91007) (xy 0.509016 -6.91007) (xy 0.509016 -15.228062)
			(xy 1.150624 -15.228062) (xy 1.154655 -15.098496) (xy 1.166734 -14.969432) (xy 1.186813 -14.841368)
			(xy 1.214815 -14.714801) (xy 1.250632 -14.590218) (xy 1.294124 -14.468104) (xy 1.345124 -14.34893)
			(xy 1.403435 -14.233157) (xy 1.46883 -14.121233) (xy 1.541057 -14.013591) (xy 1.619837 -13.910648)
			(xy 1.704864 -13.812802) (xy 1.795809 -13.72043) (xy 1.892321 -13.633892) (xy 1.994027 -13.553521)
			(xy 2.100533 -13.479629) (xy 2.211426 -13.412501) (xy 2.326278 -13.352397) (xy 2.444645 -13.29955)
			(xy 2.566068 -13.254163) (xy 2.690078 -13.216414) (xy 2.816195 -13.186447) (xy 2.943931 -13.164378)
			(xy 3.072792 -13.150294) (xy 3.202279 -13.144248) (xy 3.331892 -13.146264) (xy 3.461128 -13.156334)
			(xy 3.589489 -13.174419) (xy 3.716477 -13.200449) (xy 3.841601 -13.234324) (xy 3.964377 -13.275912)
			(xy 4.08433 -13.325053) (xy 4.200995 -13.381556) (xy 4.313923 -13.445203) (xy 4.422675 -13.515747)
			(xy 4.526831 -13.592916) (xy 4.625988 -13.676411) (xy 4.719762 -13.765909) (xy 4.807791 -13.861064)
			(xy 4.889734 -13.961507) (xy 4.965273 -14.06685) (xy 5.034118 -14.176686) (xy 5.096001 -14.29059)
			(xy 5.150682 -14.40812) (xy 5.197952 -14.528823) (xy 5.237625 -14.652231) (xy 5.26955 -14.777867)
			(xy 5.293602 -14.905244) (xy 5.309689 -15.03387) (xy 5.317748 -15.163248) (xy 5.318252 -15.228062)
			(xy 12.580624 -15.228062) (xy 12.584655 -15.098496) (xy 12.596734 -14.969432) (xy 12.616813 -14.841368)
			(xy 12.644815 -14.714801) (xy 12.680632 -14.590218) (xy 12.724124 -14.468104) (xy 12.775124 -14.34893)
			(xy 12.833435 -14.233157) (xy 12.89883 -14.121233) (xy 12.971057 -14.013591) (xy 13.049837 -13.910648)
			(xy 13.134864 -13.812802) (xy 13.225809 -13.72043) (xy 13.322321 -13.633892) (xy 13.424027 -13.553521)
			(xy 13.530533 -13.479629) (xy 13.641426 -13.412501) (xy 13.756278 -13.352397) (xy 13.874645 -13.29955)
			(xy 13.996068 -13.254163) (xy 14.120078 -13.216414) (xy 14.246195 -13.186447) (xy 14.373931 -13.164378)
			(xy 14.502792 -13.150294) (xy 14.632279 -13.144248) (xy 14.761892 -13.146264) (xy 14.891128 -13.156334)
			(xy 15.019489 -13.174419) (xy 15.146477 -13.200449) (xy 15.271601 -13.234324) (xy 15.394377 -13.275912)
			(xy 15.51433 -13.325053) (xy 15.630995 -13.381556) (xy 15.743923 -13.445203) (xy 15.852675 -13.515747)
			(xy 15.956831 -13.592916) (xy 16.055988 -13.676411) (xy 16.149762 -13.765909) (xy 16.237791 -13.861064)
			(xy 16.319734 -13.961507) (xy 16.395273 -14.06685) (xy 16.464118 -14.176686) (xy 16.526001 -14.29059)
			(xy 16.580682 -14.40812) (xy 16.627952 -14.528823) (xy 16.667625 -14.652231) (xy 16.69955 -14.777867)
			(xy 16.723602 -14.905244) (xy 16.739689 -15.03387) (xy 16.747748 -15.163248) (xy 16.748252 -15.228062)
			(xy 16.747748 -15.292876) (xy 16.739689 -15.422254) (xy 16.723602 -15.55088) (xy 16.69955 -15.678257)
			(xy 16.667625 -15.803893) (xy 16.627952 -15.927301) (xy 16.580682 -16.048004) (xy 16.526001 -16.165534)
			(xy 16.464118 -16.279438) (xy 16.395273 -16.389274) (xy 16.319734 -16.494617) (xy 16.237791 -16.59506)
			(xy 16.149762 -16.690215) (xy 16.055988 -16.779713) (xy 15.956831 -16.863208) (xy 15.852675 -16.940377)
			(xy 15.743923 -17.010921) (xy 15.630995 -17.074568) (xy 15.51433 -17.131071) (xy 15.394377 -17.180212)
			(xy 15.271601 -17.2218) (xy 15.146477 -17.255675) (xy 15.019489 -17.281705) (xy 14.891128 -17.29979)
			(xy 14.761892 -17.30986) (xy 14.632279 -17.311876) (xy 14.502792 -17.30583) (xy 14.373931 -17.291746)
			(xy 14.246195 -17.269677) (xy 14.120078 -17.23971) (xy 13.996068 -17.201961) (xy 13.874645 -17.156574)
			(xy 13.756278 -17.103727) (xy 13.641426 -17.043623) (xy 13.530533 -16.976495) (xy 13.424027 -16.902603)
			(xy 13.322321 -16.822232) (xy 13.225809 -16.735694) (xy 13.134864 -16.643322) (xy 13.049837 -16.545476)
			(xy 12.971057 -16.442533) (xy 12.89883 -16.334891) (xy 12.833435 -16.222967) (xy 12.775124 -16.107194)
			(xy 12.724124 -15.98802) (xy 12.680632 -15.865906) (xy 12.644815 -15.741323) (xy 12.616813 -15.614756)
			(xy 12.596734 -15.486692) (xy 12.584655 -15.357628) (xy 12.580624 -15.228062) (xy 5.318252 -15.228062)
			(xy 5.317748 -15.292876) (xy 5.309689 -15.422254) (xy 5.293602 -15.55088) (xy 5.26955 -15.678257)
			(xy 5.237625 -15.803893) (xy 5.197952 -15.927301) (xy 5.150682 -16.048004) (xy 5.096001 -16.165534)
			(xy 5.034118 -16.279438) (xy 4.965273 -16.389274) (xy 4.889734 -16.494617) (xy 4.807791 -16.59506)
			(xy 4.719762 -16.690215) (xy 4.625988 -16.779713) (xy 4.526831 -16.863208) (xy 4.422675 -16.940377)
			(xy 4.313923 -17.010921) (xy 4.200995 -17.074568) (xy 4.08433 -17.131071) (xy 3.964377 -17.180212)
			(xy 3.841601 -17.2218) (xy 3.716477 -17.255675) (xy 3.589489 -17.281705) (xy 3.461128 -17.29979)
			(xy 3.331892 -17.30986) (xy 3.202279 -17.311876) (xy 3.072792 -17.30583) (xy 2.943931 -17.291746)
			(xy 2.816195 -17.269677) (xy 2.690078 -17.23971) (xy 2.566068 -17.201961) (xy 2.444645 -17.156574)
			(xy 2.326278 -17.103727) (xy 2.211426 -17.043623) (xy 2.100533 -16.976495) (xy 1.994027 -16.902603)
			(xy 1.892321 -16.822232) (xy 1.795809 -16.735694) (xy 1.704864 -16.643322) (xy 1.619837 -16.545476)
			(xy 1.541057 -16.442533) (xy 1.46883 -16.334891) (xy 1.403435 -16.222967) (xy 1.345124 -16.107194)
			(xy 1.294124 -15.98802) (xy 1.250632 -15.865906) (xy 1.214815 -15.741323) (xy 1.186813 -15.614756)
			(xy 1.166734 -15.486692) (xy 1.154655 -15.357628) (xy 1.150624 -15.228062) (xy 0.509016 -15.228062)
			(xy 0.509016 -20.01012) (xy 86.877404 -20.01012) (xy 86.881424 -19.819469) (xy 86.893478 -19.629156)
			(xy 86.913544 -19.439521) (xy 86.941587 -19.2509) (xy 86.977556 -19.06363) (xy 87.021388 -18.878042)
			(xy 87.073005 -18.694467) (xy 87.132315 -18.513231) (xy 87.199213 -18.334656) (xy 87.273579 -18.159061)
			(xy 87.355281 -17.986756) (xy 87.444175 -17.818049) (xy 87.540101 -17.653239) (xy 87.64289 -17.49262)
			(xy 87.752359 -17.336477) (xy 87.868313 -17.185088) (xy 87.990547 -17.038721) (xy 88.118841 -16.897637)
			(xy 88.252969 -16.762088) (xy 88.392693 -16.632313) (xy 88.537763 -16.508543) (xy 88.687921 -16.391)
			(xy 88.842902 -16.279891) (xy 89.002429 -16.175414) (xy 89.166218 -16.077755) (xy 89.333978 -15.987088)
			(xy 89.505412 -15.903574) (xy 89.680214 -15.827361) (xy 89.858073 -15.758585) (xy 90.038674 -15.697367)
			(xy 90.221694 -15.643818) (xy 90.40681 -15.598032) (xy 90.593691 -15.56009) (xy 90.782006 -15.530061)
			(xy 90.971419 -15.507996) (xy 91.161593 -15.493937) (xy 91.352192 -15.487907) (xy 91.542875 -15.489917)
			(xy 91.733304 -15.499964) (xy 91.92314 -15.51803) (xy 92.112046 -15.544083) (xy 92.299685 -15.578076)
			(xy 92.485725 -15.619949) (xy 92.669834 -15.669628) (xy 92.851685 -15.727024) (xy 93.030955 -15.792035)
			(xy 93.207325 -15.864546) (xy 93.380481 -15.944427) (xy 93.550116 -16.031537) (xy 93.715928 -16.125721)
			(xy 93.877622 -16.226812) (xy 94.03491 -16.334628) (xy 94.187513 -16.44898) (xy 94.335161 -16.569663)
			(xy 94.477589 -16.696464) (xy 94.614545 -16.829155) (xy 94.745786 -16.967503) (xy 94.871078 -17.11126)
			(xy 94.990198 -17.260171) (xy 95.102934 -17.413972) (xy 95.209087 -17.572388) (xy 95.308467 -17.735139)
			(xy 95.400897 -17.901934) (xy 95.486214 -18.072478) (xy 95.564266 -18.246466) (xy 95.634913 -18.423591)
			(xy 95.698031 -18.603536) (xy 95.753507 -18.785982) (xy 95.801242 -18.970605) (xy 95.841152 -19.157075)
			(xy 95.873165 -19.345063) (xy 95.897225 -19.534233) (xy 95.913288 -19.724249) (xy 95.921327 -19.914773)
			(xy 95.92183 -20.01012) (xy 95.921327 -20.105467) (xy 95.913288 -20.295991) (xy 95.897225 -20.486007)
			(xy 95.873165 -20.675177) (xy 95.841152 -20.863165) (xy 95.801242 -21.049635) (xy 95.753507 -21.234258)
			(xy 95.698031 -21.416704) (xy 95.634913 -21.596649) (xy 95.564266 -21.773774) (xy 95.486214 -21.947762)
			(xy 95.400897 -22.118306) (xy 95.308467 -22.285101) (xy 95.209087 -22.447852) (xy 95.102934 -22.606268)
			(xy 94.990198 -22.760069) (xy 94.871078 -22.90898) (xy 94.745786 -23.052737) (xy 94.614545 -23.191085)
			(xy 94.477589 -23.323776) (xy 94.335161 -23.450577) (xy 94.187513 -23.57126) (xy 94.03491 -23.685612)
			(xy 93.877622 -23.793428) (xy 93.715928 -23.894519) (xy 93.550116 -23.988703) (xy 93.380481 -24.075813)
			(xy 93.207325 -24.155694) (xy 93.030955 -24.228205) (xy 92.851685 -24.293216) (xy 92.669834 -24.350612)
			(xy 92.485725 -24.400291) (xy 92.299685 -24.442164) (xy 92.112046 -24.476157) (xy 91.92314 -24.50221)
			(xy 91.733304 -24.520276) (xy 91.542875 -24.530323) (xy 91.352192 -24.532333) (xy 91.161593 -24.526303)
			(xy 90.971419 -24.512244) (xy 90.782006 -24.490179) (xy 90.593691 -24.46015) (xy 90.40681 -24.422208)
			(xy 90.221694 -24.376422) (xy 90.038674 -24.322873) (xy 89.858073 -24.261655) (xy 89.680214 -24.192879)
			(xy 89.505412 -24.116666) (xy 89.333978 -24.033152) (xy 89.166218 -23.942485) (xy 89.002429 -23.844826)
			(xy 88.842902 -23.740349) (xy 88.687921 -23.62924) (xy 88.537763 -23.511697) (xy 88.392693 -23.387927)
			(xy 88.252969 -23.258152) (xy 88.118841 -23.122603) (xy 87.990547 -22.981519) (xy 87.868313 -22.835152)
			(xy 87.752359 -22.683763) (xy 87.64289 -22.52762) (xy 87.540101 -22.367001) (xy 87.444175 -22.202191)
			(xy 87.355281 -22.033484) (xy 87.273579 -21.861179) (xy 87.199213 -21.685584) (xy 87.132315 -21.507009)
			(xy 87.073005 -21.325773) (xy 87.021388 -21.142198) (xy 86.977556 -20.95661) (xy 86.941587 -20.76934)
			(xy 86.913544 -20.580719) (xy 86.893478 -20.391084) (xy 86.881424 -20.200771) (xy 86.877404 -20.01012)
			(xy 0.509016 -20.01012) (xy 0.509016 -29.19984) (xy 14.086591 -29.19984) (xy 14.090616 -29.057648)
			(xy 14.102679 -28.915912) (xy 14.122742 -28.775086) (xy 14.15074 -28.63562) (xy 14.186584 -28.497961)
			(xy 14.230158 -28.362551) (xy 14.281323 -28.229823) (xy 14.339916 -28.100202) (xy 14.405747 -27.974104)
			(xy 14.478608 -27.851932) (xy 14.558263 -27.734078) (xy 14.644459 -27.620919) (xy 14.736918 -27.512817)
			(xy 14.835346 -27.41012) (xy 14.939425 -27.313156) (xy 15.048824 -27.222236) (xy 15.163192 -27.13765)
			(xy 15.282161 -27.05967) (xy 15.405352 -26.988546) (xy 15.532369 -26.924505) (xy 15.662806 -26.867753)
			(xy 15.796245 -26.818471) (xy 15.932258 -26.776817) (xy 16.07041 -26.742925) (xy 16.210259 -26.716904)
			(xy 16.351355 -26.698836) (xy 16.493247 -26.688779) (xy 16.635482 -26.686766) (xy 16.777602 -26.692803)
			(xy 16.919153 -26.706871) (xy 17.059682 -26.728925) (xy 17.198737 -26.758894) (xy 17.335875 -26.796682)
			(xy 17.470655 -26.842168) (xy 17.602646 -26.895206) (xy 17.731425 -26.955627) (xy 17.856579 -27.023236)
			(xy 17.977707 -27.097818) (xy 18.094423 -27.179134) (xy 18.206351 -27.266922) (xy 18.313133 -27.360902)
			(xy 18.414427 -27.460772) (xy 18.509908 -27.566214) (xy 18.599272 -27.676888) (xy 18.68223 -27.792441)
			(xy 18.758519 -27.912502) (xy 18.827893 -28.036687) (xy 18.89013 -28.164598) (xy 18.945031 -28.295825)
			(xy 18.992419 -28.429948) (xy 19.032144 -28.566537) (xy 19.064077 -28.705155) (xy 19.088118 -28.845357)
			(xy 19.104187 -28.986695) (xy 19.112235 -29.128716) (xy 19.112738 -29.19984) (xy 19.112235 -29.270964)
			(xy 19.104187 -29.412985) (xy 19.088118 -29.554323) (xy 19.064077 -29.694525) (xy 19.032144 -29.833143)
			(xy 18.992419 -29.969732) (xy 18.945031 -30.103855) (xy 18.89013 -30.235082) (xy 18.827893 -30.362993)
			(xy 18.758519 -30.487178) (xy 18.68223 -30.607239) (xy 18.599272 -30.722792) (xy 18.509908 -30.833466)
			(xy 18.414427 -30.938908) (xy 18.313133 -31.038778) (xy 18.206351 -31.132758) (xy 18.094423 -31.220546)
			(xy 17.977707 -31.301862) (xy 17.856579 -31.376444) (xy 17.731425 -31.444053) (xy 17.602646 -31.504474)
			(xy 17.470655 -31.557512) (xy 17.335875 -31.602998) (xy 17.198737 -31.640786) (xy 17.059682 -31.670755)
			(xy 16.919153 -31.692809) (xy 16.777602 -31.706877) (xy 16.635482 -31.712914) (xy 16.493247 -31.710901)
			(xy 16.351355 -31.700844) (xy 16.210259 -31.682776) (xy 16.07041 -31.656755) (xy 15.932258 -31.622863)
			(xy 15.796245 -31.581209) (xy 15.662806 -31.531927) (xy 15.532369 -31.475175) (xy 15.405352 -31.411134)
			(xy 15.282161 -31.34001) (xy 15.163192 -31.26203) (xy 15.048824 -31.177444) (xy 14.939425 -31.086524)
			(xy 14.835346 -30.98956) (xy 14.736918 -30.886863) (xy 14.644459 -30.778761) (xy 14.558263 -30.665602)
			(xy 14.478608 -30.547748) (xy 14.405747 -30.425576) (xy 14.339916 -30.299478) (xy 14.281323 -30.169857)
			(xy 14.230158 -30.037129) (xy 14.186584 -29.901719) (xy 14.15074 -29.76406) (xy 14.122742 -29.624594)
			(xy 14.102679 -29.483768) (xy 14.090616 -29.342032) (xy 14.086591 -29.19984) (xy 0.509016 -29.19984)
			(xy 0.509016 -32.29991) (xy 75.486519 -32.29991) (xy 75.490544 -32.157718) (xy 75.502607 -32.015982)
			(xy 75.52267 -31.875156) (xy 75.550668 -31.73569) (xy 75.586512 -31.598031) (xy 75.630086 -31.462621)
			(xy 75.681251 -31.329893) (xy 75.739844 -31.200272) (xy 75.805675 -31.074174) (xy 75.878536 -30.952002)
			(xy 75.958191 -30.834148) (xy 76.044387 -30.720989) (xy 76.136846 -30.612887) (xy 76.235274 -30.51019)
			(xy 76.339353 -30.413226) (xy 76.448752 -30.322306) (xy 76.56312 -30.23772) (xy 76.682089 -30.15974)
			(xy 76.80528 -30.088616) (xy 76.932297 -30.024575) (xy 77.062734 -29.967823) (xy 77.196173 -29.918541)
			(xy 77.332186 -29.876887) (xy 77.470338 -29.842995) (xy 77.610187 -29.816974) (xy 77.751283 -29.798906)
			(xy 77.893175 -29.788849) (xy 78.03541 -29.786836) (xy 78.17753 -29.792873) (xy 78.319081 -29.806941)
			(xy 78.45961 -29.828995) (xy 78.598665 -29.858964) (xy 78.735803 -29.896752) (xy 78.870583 -29.942238)
			(xy 79.002574 -29.995276) (xy 79.131353 -30.055697) (xy 79.256507 -30.123306) (xy 79.377635 -30.197888)
			(xy 79.494351 -30.279204) (xy 79.606279 -30.366992) (xy 79.713061 -30.460972) (xy 79.814355 -30.560842)
			(xy 79.909836 -30.666284) (xy 79.9992 -30.776958) (xy 80.082158 -30.892511) (xy 80.158447 -31.012572)
			(xy 80.227821 -31.136757) (xy 80.290058 -31.264668) (xy 80.344959 -31.395895) (xy 80.392347 -31.530018)
			(xy 80.432072 -31.666607) (xy 80.464005 -31.805225) (xy 80.488046 -31.945427) (xy 80.504115 -32.086765)
			(xy 80.512163 -32.228786) (xy 80.512666 -32.29991) (xy 80.512163 -32.371034) (xy 80.504115 -32.513055)
			(xy 80.488046 -32.654393) (xy 80.464005 -32.794595) (xy 80.432072 -32.933213) (xy 80.392347 -33.069802)
			(xy 80.344959 -33.203925) (xy 80.290058 -33.335152) (xy 80.227821 -33.463063) (xy 80.158447 -33.587248)
			(xy 80.082158 -33.707309) (xy 79.9992 -33.822862) (xy 79.909836 -33.933536) (xy 79.814355 -34.038978)
			(xy 79.713061 -34.138848) (xy 79.606279 -34.232828) (xy 79.494351 -34.320616) (xy 79.377635 -34.401932)
			(xy 79.256507 -34.476514) (xy 79.131353 -34.544123) (xy 79.002574 -34.604544) (xy 78.870583 -34.657582)
			(xy 78.735803 -34.703068) (xy 78.598665 -34.740856) (xy 78.45961 -34.770825) (xy 78.319081 -34.792879)
			(xy 78.17753 -34.806947) (xy 78.03541 -34.812984) (xy 77.893175 -34.810971) (xy 77.751283 -34.800914)
			(xy 77.610187 -34.782846) (xy 77.470338 -34.756825) (xy 77.332186 -34.722933) (xy 77.196173 -34.681279)
			(xy 77.062734 -34.631997) (xy 76.932297 -34.575245) (xy 76.80528 -34.511204) (xy 76.682089 -34.44008)
			(xy 76.56312 -34.3621) (xy 76.448752 -34.277514) (xy 76.339353 -34.186594) (xy 76.235274 -34.08963)
			(xy 76.136846 -33.986933) (xy 76.044387 -33.878831) (xy 75.958191 -33.765672) (xy 75.878536 -33.647818)
			(xy 75.805675 -33.525646) (xy 75.739844 -33.399548) (xy 75.681251 -33.269927) (xy 75.630086 -33.137199)
			(xy 75.586512 -33.001789) (xy 75.550668 -32.86413) (xy 75.52267 -32.724664) (xy 75.502607 -32.583838)
			(xy 75.490544 -32.442102) (xy 75.486519 -32.29991) (xy 0.509016 -32.29991) (xy 0.509016 -46.221904)
			(xy 1.150624 -46.221904) (xy 1.154655 -46.092338) (xy 1.166734 -45.963274) (xy 1.186813 -45.83521)
			(xy 1.214815 -45.708643) (xy 1.250632 -45.58406) (xy 1.294124 -45.461946) (xy 1.345124 -45.342772)
			(xy 1.403435 -45.226999) (xy 1.46883 -45.115075) (xy 1.541057 -45.007433) (xy 1.619837 -44.90449)
			(xy 1.704864 -44.806644) (xy 1.795809 -44.714272) (xy 1.892321 -44.627734) (xy 1.994027 -44.547363)
			(xy 2.100533 -44.473471) (xy 2.211426 -44.406343) (xy 2.326278 -44.346239) (xy 2.444645 -44.293392)
			(xy 2.566068 -44.248005) (xy 2.690078 -44.210256) (xy 2.816195 -44.180289) (xy 2.943931 -44.15822)
			(xy 3.072792 -44.144136) (xy 3.202279 -44.13809) (xy 3.331892 -44.140106) (xy 3.461128 -44.150176)
			(xy 3.589489 -44.168261) (xy 3.716477 -44.194291) (xy 3.841601 -44.228166) (xy 3.964377 -44.269754)
			(xy 4.08433 -44.318895) (xy 4.200995 -44.375398) (xy 4.313923 -44.439045) (xy 4.422675 -44.509589)
			(xy 4.526831 -44.586758) (xy 4.625988 -44.670253) (xy 4.719762 -44.759751) (xy 4.807791 -44.854906)
			(xy 4.889734 -44.955349) (xy 4.965273 -45.060692) (xy 5.034118 -45.170528) (xy 5.096001 -45.284432)
			(xy 5.150682 -45.401962) (xy 5.197952 -45.522665) (xy 5.237625 -45.646073) (xy 5.26955 -45.771709)
			(xy 5.293602 -45.899086) (xy 5.309689 -46.027712) (xy 5.317748 -46.15709) (xy 5.318252 -46.221904)
			(xy 12.580624 -46.221904) (xy 12.584655 -46.092338) (xy 12.596734 -45.963274) (xy 12.616813 -45.83521)
			(xy 12.644815 -45.708643) (xy 12.680632 -45.58406) (xy 12.724124 -45.461946) (xy 12.775124 -45.342772)
			(xy 12.833435 -45.226999) (xy 12.89883 -45.115075) (xy 12.971057 -45.007433) (xy 13.049837 -44.90449)
			(xy 13.134864 -44.806644) (xy 13.225809 -44.714272) (xy 13.322321 -44.627734) (xy 13.424027 -44.547363)
			(xy 13.530533 -44.473471) (xy 13.641426 -44.406343) (xy 13.756278 -44.346239) (xy 13.874645 -44.293392)
			(xy 13.996068 -44.248005) (xy 14.120078 -44.210256) (xy 14.246195 -44.180289) (xy 14.373931 -44.15822)
			(xy 14.502792 -44.144136) (xy 14.632279 -44.13809) (xy 14.761892 -44.140106) (xy 14.891128 -44.150176)
			(xy 15.019489 -44.168261) (xy 15.146477 -44.194291) (xy 15.271601 -44.228166) (xy 15.394377 -44.269754)
			(xy 15.51433 -44.318895) (xy 15.630995 -44.375398) (xy 15.743923 -44.439045) (xy 15.852675 -44.509589)
			(xy 15.956831 -44.586758) (xy 16.055988 -44.670253) (xy 16.149762 -44.759751) (xy 16.237791 -44.854906)
			(xy 16.319734 -44.955349) (xy 16.395273 -45.060692) (xy 16.464118 -45.170528) (xy 16.526001 -45.284432)
			(xy 16.580682 -45.401962) (xy 16.627952 -45.522665) (xy 16.667625 -45.646073) (xy 16.69955 -45.771709)
			(xy 16.723602 -45.899086) (xy 16.739689 -46.027712) (xy 16.747748 -46.15709) (xy 16.748252 -46.221904)
			(xy 16.747748 -46.286718) (xy 16.739689 -46.416096) (xy 16.723602 -46.544722) (xy 16.69955 -46.672099)
			(xy 16.667625 -46.797735) (xy 16.627952 -46.921143) (xy 16.580682 -47.041846) (xy 16.526001 -47.159376)
			(xy 16.464118 -47.27328) (xy 16.395273 -47.383116) (xy 16.319734 -47.488459) (xy 16.237791 -47.588902)
			(xy 16.149762 -47.684057) (xy 16.055988 -47.773555) (xy 15.956831 -47.85705) (xy 15.852675 -47.934219)
			(xy 15.743923 -48.004763) (xy 15.630995 -48.06841) (xy 15.51433 -48.124913) (xy 15.394377 -48.174054)
			(xy 15.271601 -48.215642) (xy 15.146477 -48.249517) (xy 15.019489 -48.275547) (xy 14.891128 -48.293632)
			(xy 14.761892 -48.303702) (xy 14.632279 -48.305718) (xy 14.502792 -48.299672) (xy 14.373931 -48.285588)
			(xy 14.246195 -48.263519) (xy 14.120078 -48.233552) (xy 13.996068 -48.195803) (xy 13.874645 -48.150416)
			(xy 13.756278 -48.097569) (xy 13.641426 -48.037465) (xy 13.530533 -47.970337) (xy 13.424027 -47.896445)
			(xy 13.322321 -47.816074) (xy 13.225809 -47.729536) (xy 13.134864 -47.637164) (xy 13.049837 -47.539318)
			(xy 12.971057 -47.436375) (xy 12.89883 -47.328733) (xy 12.833435 -47.216809) (xy 12.775124 -47.101036)
			(xy 12.724124 -46.981862) (xy 12.680632 -46.859748) (xy 12.644815 -46.735165) (xy 12.616813 -46.608598)
			(xy 12.596734 -46.480534) (xy 12.584655 -46.35147) (xy 12.580624 -46.221904) (xy 5.318252 -46.221904)
			(xy 5.317748 -46.286718) (xy 5.309689 -46.416096) (xy 5.293602 -46.544722) (xy 5.26955 -46.672099)
			(xy 5.237625 -46.797735) (xy 5.197952 -46.921143) (xy 5.150682 -47.041846) (xy 5.096001 -47.159376)
			(xy 5.034118 -47.27328) (xy 4.965273 -47.383116) (xy 4.889734 -47.488459) (xy 4.807791 -47.588902)
			(xy 4.719762 -47.684057) (xy 4.625988 -47.773555) (xy 4.526831 -47.85705) (xy 4.422675 -47.934219)
			(xy 4.313923 -48.004763) (xy 4.200995 -48.06841) (xy 4.08433 -48.124913) (xy 3.964377 -48.174054)
			(xy 3.841601 -48.215642) (xy 3.716477 -48.249517) (xy 3.589489 -48.275547) (xy 3.461128 -48.293632)
			(xy 3.331892 -48.303702) (xy 3.202279 -48.305718) (xy 3.072792 -48.299672) (xy 2.943931 -48.285588)
			(xy 2.816195 -48.263519) (xy 2.690078 -48.233552) (xy 2.566068 -48.195803) (xy 2.444645 -48.150416)
			(xy 2.326278 -48.097569) (xy 2.211426 -48.037465) (xy 2.100533 -47.970337) (xy 1.994027 -47.896445)
			(xy 1.892321 -47.816074) (xy 1.795809 -47.729536) (xy 1.704864 -47.637164) (xy 1.619837 -47.539318)
			(xy 1.541057 -47.436375) (xy 1.46883 -47.328733) (xy 1.403435 -47.216809) (xy 1.345124 -47.101036)
			(xy 1.294124 -46.981862) (xy 1.250632 -46.859748) (xy 1.214815 -46.735165) (xy 1.186813 -46.608598)
			(xy 1.166734 -46.480534) (xy 1.154655 -46.35147) (xy 1.150624 -46.221904) (xy 0.509016 -46.221904)
			(xy 0.509016 -51.36007) (xy 39.818063 -51.36007) (xy 39.82207 -51.244046) (xy 39.834072 -51.128574)
			(xy 39.854012 -51.014206) (xy 39.881795 -50.901486) (xy 39.917289 -50.790952) (xy 39.960324 -50.683129)
			(xy 40.010695 -50.578532) (xy 40.068162 -50.47766) (xy 40.132452 -50.380993) (xy 40.203257 -50.288992)
			(xy 40.280241 -50.202095) (xy 40.363037 -50.120716) (xy 40.45125 -50.045243) (xy 40.54446 -49.976036)
			(xy 40.642223 -49.913424) (xy 40.744072 -49.857707) (xy 40.849522 -49.809149) (xy 40.958071 -49.767981)
			(xy 41.069202 -49.734401) (xy 41.182385 -49.708568) (xy 41.29708 -49.690605) (xy 41.412742 -49.680597)
			(xy 41.528818 -49.678594) (xy 41.644756 -49.684603) (xy 41.760003 -49.698596) (xy 41.874009 -49.720507)
			(xy 41.986233 -49.750232) (xy 42.096139 -49.787628) (xy 42.203202 -49.832517) (xy 42.306914 -49.884686)
			(xy 42.406779 -49.943886) (xy 42.502322 -50.009835) (xy 42.593088 -50.082218) (xy 42.678643 -50.160691)
			(xy 42.758581 -50.244879) (xy 42.83252 -50.334381) (xy 42.900108 -50.428772) (xy 42.961022 -50.5276)
			(xy 43.014974 -50.630396) (xy 43.061704 -50.736669) (xy 43.100992 -50.845913) (xy 43.132649 -50.957606)
			(xy 43.156525 -51.071218) (xy 43.172506 -51.186206) (xy 43.180515 -51.302023) (xy 43.181016 -51.36007)
			(xy 43.180515 -51.418117) (xy 43.172506 -51.533934) (xy 43.156525 -51.648922) (xy 43.132649 -51.762534)
			(xy 43.100992 -51.874227) (xy 43.061704 -51.983471) (xy 43.014974 -52.089744) (xy 42.961022 -52.19254)
			(xy 42.900108 -52.291368) (xy 42.83252 -52.385759) (xy 42.758581 -52.475261) (xy 42.678643 -52.559449)
			(xy 42.593088 -52.637922) (xy 42.502604 -52.71008) (xy 93.154506 -52.71008) (xy 93.158522 -52.59381)
			(xy 93.170549 -52.478095) (xy 93.190531 -52.363485) (xy 93.218373 -52.250526) (xy 93.253942 -52.139758)
			(xy 93.297068 -52.031707) (xy 93.347545 -51.926889) (xy 93.405134 -51.825804) (xy 93.46956 -51.728932)
			(xy 93.540515 -51.636736) (xy 93.617662 -51.549655) (xy 93.700633 -51.468104) (xy 93.789033 -51.392472)
			(xy 93.88244 -51.323118) (xy 93.980409 -51.260375) (xy 94.082473 -51.204539) (xy 94.188147 -51.155878)
			(xy 94.296926 -51.114624) (xy 94.408291 -51.080973) (xy 94.521714 -51.055085) (xy 94.636651 -51.037084)
			(xy 94.752557 -51.027055) (xy 94.868879 -51.025047) (xy 94.985062 -51.031069) (xy 95.100553 -51.045092)
			(xy 95.214801 -51.06705) (xy 95.327262 -51.096837) (xy 95.4374 -51.134312) (xy 95.54469 -51.179297)
			(xy 95.648621 -51.231576) (xy 95.748697 -51.290901) (xy 95.844443 -51.356989) (xy 95.9354 -51.429525)
			(xy 96.021136 -51.508164) (xy 96.101243 -51.59253) (xy 96.175339 -51.682222) (xy 96.243069 -51.776812)
			(xy 96.304113 -51.87585) (xy 96.358178 -51.978863) (xy 96.405008 -52.08536) (xy 96.444379 -52.194835)
			(xy 96.476103 -52.306765) (xy 96.500029 -52.420617) (xy 96.516043 -52.535849) (xy 96.52407 -52.651911)
			(xy 96.524572 -52.71008) (xy 96.52407 -52.768249) (xy 96.516043 -52.884311) (xy 96.500029 -52.999543)
			(xy 96.476103 -53.113395) (xy 96.444379 -53.225325) (xy 96.405008 -53.3348) (xy 96.358178 -53.441297)
			(xy 96.304113 -53.54431) (xy 96.243069 -53.643348) (xy 96.175339 -53.737938) (xy 96.101243 -53.82763)
			(xy 96.021136 -53.911996) (xy 95.9354 -53.990635) (xy 95.844443 -54.063171) (xy 95.748697 -54.129259)
			(xy 95.648621 -54.188584) (xy 95.54469 -54.240863) (xy 95.4374 -54.285848) (xy 95.327262 -54.323323)
			(xy 95.214801 -54.35311) (xy 95.100553 -54.375068) (xy 94.985062 -54.389091) (xy 94.868879 -54.395113)
			(xy 94.752557 -54.393105) (xy 94.636651 -54.383076) (xy 94.521714 -54.365075) (xy 94.408291 -54.339187)
			(xy 94.296926 -54.305536) (xy 94.188147 -54.264282) (xy 94.082473 -54.215621) (xy 93.980409 -54.159785)
			(xy 93.88244 -54.097042) (xy 93.789033 -54.027688) (xy 93.700633 -53.952056) (xy 93.617662 -53.870505)
			(xy 93.540515 -53.783424) (xy 93.46956 -53.691228) (xy 93.405134 -53.594356) (xy 93.347545 -53.493271)
			(xy 93.297068 -53.388453) (xy 93.253942 -53.280402) (xy 93.218373 -53.169634) (xy 93.190531 -53.056675)
			(xy 93.170549 -52.942065) (xy 93.158522 -52.82635) (xy 93.154506 -52.71008) (xy 42.502604 -52.71008)
			(xy 42.502322 -52.710305) (xy 42.406779 -52.776254) (xy 42.306914 -52.835454) (xy 42.203202 -52.887623)
			(xy 42.096139 -52.932512) (xy 41.986233 -52.969908) (xy 41.874009 -52.999633) (xy 41.760003 -53.021544)
			(xy 41.644756 -53.035537) (xy 41.528818 -53.041546) (xy 41.412742 -53.039543) (xy 41.29708 -53.029535)
			(xy 41.182385 -53.011572) (xy 41.069202 -52.985739) (xy 40.958071 -52.952159) (xy 40.849522 -52.910991)
			(xy 40.744072 -52.862433) (xy 40.642223 -52.806716) (xy 40.54446 -52.744104) (xy 40.45125 -52.674897)
			(xy 40.363037 -52.599424) (xy 40.280241 -52.518045) (xy 40.203257 -52.431148) (xy 40.132452 -52.339147)
			(xy 40.068162 -52.24248) (xy 40.010695 -52.141608) (xy 39.960324 -52.037011) (xy 39.917289 -51.929188)
			(xy 39.881795 -51.818654) (xy 39.854012 -51.705934) (xy 39.834072 -51.591566) (xy 39.82207 -51.476094)
			(xy 39.818063 -51.36007) (xy 0.509016 -51.36007) (xy 0.509016 -64.46012) (xy 86.877404 -64.46012)
			(xy 86.881424 -64.269469) (xy 86.893478 -64.079156) (xy 86.913544 -63.889521) (xy 86.941587 -63.7009)
			(xy 86.977556 -63.51363) (xy 87.021388 -63.328042) (xy 87.073005 -63.144467) (xy 87.132315 -62.963231)
			(xy 87.199213 -62.784656) (xy 87.273579 -62.609061) (xy 87.355281 -62.436756) (xy 87.444175 -62.268049)
			(xy 87.540101 -62.103239) (xy 87.64289 -61.94262) (xy 87.752359 -61.786477) (xy 87.868313 -61.635088)
			(xy 87.990547 -61.488721) (xy 88.118841 -61.347637) (xy 88.252969 -61.212088) (xy 88.392693 -61.082313)
			(xy 88.537763 -60.958543) (xy 88.687921 -60.841) (xy 88.842902 -60.729891) (xy 89.002429 -60.625414)
			(xy 89.166218 -60.527755) (xy 89.333978 -60.437088) (xy 89.505412 -60.353574) (xy 89.680214 -60.277361)
			(xy 89.858073 -60.208585) (xy 90.038674 -60.147367) (xy 90.221694 -60.093818) (xy 90.40681 -60.048032)
			(xy 90.593691 -60.01009) (xy 90.782006 -59.980061) (xy 90.971419 -59.957996) (xy 91.161593 -59.943937)
			(xy 91.352192 -59.937907) (xy 91.542875 -59.939917) (xy 91.733304 -59.949964) (xy 91.92314 -59.96803)
			(xy 92.112046 -59.994083) (xy 92.299685 -60.028076) (xy 92.485725 -60.069949) (xy 92.669834 -60.119628)
			(xy 92.851685 -60.177024) (xy 93.030955 -60.242035) (xy 93.207325 -60.314546) (xy 93.380481 -60.394427)
			(xy 93.550116 -60.481537) (xy 93.715928 -60.575721) (xy 93.877622 -60.676812) (xy 94.03491 -60.784628)
			(xy 94.187513 -60.89898) (xy 94.335161 -61.019663) (xy 94.477589 -61.146464) (xy 94.614545 -61.279155)
			(xy 94.745786 -61.417503) (xy 94.871078 -61.56126) (xy 94.990198 -61.710171) (xy 95.102934 -61.863972)
			(xy 95.209087 -62.022388) (xy 95.308467 -62.185139) (xy 95.400897 -62.351934) (xy 95.486214 -62.522478)
			(xy 95.564266 -62.696466) (xy 95.634913 -62.873591) (xy 95.698031 -63.053536) (xy 95.753507 -63.235982)
			(xy 95.801242 -63.420605) (xy 95.841152 -63.607075) (xy 95.873165 -63.795063) (xy 95.897225 -63.984233)
			(xy 95.913288 -64.174249) (xy 95.921327 -64.364773) (xy 95.92183 -64.46012) (xy 95.921327 -64.555467)
			(xy 95.913288 -64.745991) (xy 95.897225 -64.936007) (xy 95.873165 -65.125177) (xy 95.841152 -65.313165)
			(xy 95.801242 -65.499635) (xy 95.753507 -65.684258) (xy 95.698031 -65.866704) (xy 95.634913 -66.046649)
			(xy 95.564266 -66.223774) (xy 95.486214 -66.397762) (xy 95.400897 -66.568306) (xy 95.308467 -66.735101)
			(xy 95.209087 -66.897852) (xy 95.102934 -67.056268) (xy 94.990198 -67.210069) (xy 94.871078 -67.35898)
			(xy 94.745786 -67.502737) (xy 94.614545 -67.641085) (xy 94.477589 -67.773776) (xy 94.335161 -67.900577)
			(xy 94.187513 -68.02126) (xy 94.03491 -68.135612) (xy 93.877622 -68.243428) (xy 93.715928 -68.344519)
			(xy 93.550116 -68.438703) (xy 93.380481 -68.525813) (xy 93.207325 -68.605694) (xy 93.030955 -68.678205)
			(xy 92.851685 -68.743216) (xy 92.669834 -68.800612) (xy 92.485725 -68.850291) (xy 92.299685 -68.892164)
			(xy 92.112046 -68.926157) (xy 91.92314 -68.95221) (xy 91.733304 -68.970276) (xy 91.542875 -68.980323)
			(xy 91.352192 -68.982333) (xy 91.161593 -68.976303) (xy 90.971419 -68.962244) (xy 90.782006 -68.940179)
			(xy 90.593691 -68.91015) (xy 90.40681 -68.872208) (xy 90.221694 -68.826422) (xy 90.038674 -68.772873)
			(xy 89.858073 -68.711655) (xy 89.680214 -68.642879) (xy 89.505412 -68.566666) (xy 89.333978 -68.483152)
			(xy 89.166218 -68.392485) (xy 89.002429 -68.294826) (xy 88.842902 -68.190349) (xy 88.687921 -68.07924)
			(xy 88.537763 -67.961697) (xy 88.392693 -67.837927) (xy 88.252969 -67.708152) (xy 88.118841 -67.572603)
			(xy 87.990547 -67.431519) (xy 87.868313 -67.285152) (xy 87.752359 -67.133763) (xy 87.64289 -66.97762)
			(xy 87.540101 -66.817001) (xy 87.444175 -66.652191) (xy 87.355281 -66.483484) (xy 87.273579 -66.311179)
			(xy 87.199213 -66.135584) (xy 87.132315 -65.957009) (xy 87.073005 -65.775773) (xy 87.021388 -65.592198)
			(xy 86.977556 -65.40661) (xy 86.941587 -65.21934) (xy 86.913544 -65.030719) (xy 86.893478 -64.841084)
			(xy 86.881424 -64.650771) (xy 86.877404 -64.46012) (xy 0.509016 -64.46012) (xy 0.509016 -68.277994)
			(xy 1.150624 -68.277994) (xy 1.154655 -68.148428) (xy 1.166734 -68.019364) (xy 1.186813 -67.8913)
			(xy 1.214815 -67.764733) (xy 1.250632 -67.64015) (xy 1.294124 -67.518036) (xy 1.345124 -67.398862)
			(xy 1.403435 -67.283089) (xy 1.46883 -67.171165) (xy 1.541057 -67.063523) (xy 1.619837 -66.96058)
			(xy 1.704864 -66.862734) (xy 1.795809 -66.770362) (xy 1.892321 -66.683824) (xy 1.994027 -66.603453)
			(xy 2.100533 -66.529561) (xy 2.211426 -66.462433) (xy 2.326278 -66.402329) (xy 2.444645 -66.349482)
			(xy 2.566068 -66.304095) (xy 2.690078 -66.266346) (xy 2.816195 -66.236379) (xy 2.943931 -66.21431)
			(xy 3.072792 -66.200226) (xy 3.202279 -66.19418) (xy 3.331892 -66.196196) (xy 3.461128 -66.206266)
			(xy 3.589489 -66.224351) (xy 3.716477 -66.250381) (xy 3.841601 -66.284256) (xy 3.964377 -66.325844)
			(xy 4.08433 -66.374985) (xy 4.200995 -66.431488) (xy 4.313923 -66.495135) (xy 4.422675 -66.565679)
			(xy 4.526831 -66.642848) (xy 4.625988 -66.726343) (xy 4.719762 -66.815841) (xy 4.807791 -66.910996)
			(xy 4.889734 -67.011439) (xy 4.965273 -67.116782) (xy 5.034118 -67.226618) (xy 5.096001 -67.340522)
			(xy 5.150682 -67.458052) (xy 5.197952 -67.578755) (xy 5.237625 -67.702163) (xy 5.26955 -67.827799)
			(xy 5.293602 -67.955176) (xy 5.309689 -68.083802) (xy 5.317748 -68.21318) (xy 5.318252 -68.277994)
			(xy 12.580624 -68.277994) (xy 12.584655 -68.148428) (xy 12.596734 -68.019364) (xy 12.616813 -67.8913)
			(xy 12.644815 -67.764733) (xy 12.680632 -67.64015) (xy 12.724124 -67.518036) (xy 12.775124 -67.398862)
			(xy 12.833435 -67.283089) (xy 12.89883 -67.171165) (xy 12.971057 -67.063523) (xy 13.049837 -66.96058)
			(xy 13.134864 -66.862734) (xy 13.225809 -66.770362) (xy 13.322321 -66.683824) (xy 13.424027 -66.603453)
			(xy 13.530533 -66.529561) (xy 13.641426 -66.462433) (xy 13.756278 -66.402329) (xy 13.874645 -66.349482)
			(xy 13.996068 -66.304095) (xy 14.120078 -66.266346) (xy 14.246195 -66.236379) (xy 14.373931 -66.21431)
			(xy 14.502792 -66.200226) (xy 14.632279 -66.19418) (xy 14.761892 -66.196196) (xy 14.891128 -66.206266)
			(xy 15.019489 -66.224351) (xy 15.146477 -66.250381) (xy 15.271601 -66.284256) (xy 15.394377 -66.325844)
			(xy 15.51433 -66.374985) (xy 15.630995 -66.431488) (xy 15.743923 -66.495135) (xy 15.852675 -66.565679)
			(xy 15.956831 -66.642848) (xy 16.055988 -66.726343) (xy 16.149762 -66.815841) (xy 16.237791 -66.910996)
			(xy 16.319734 -67.011439) (xy 16.395273 -67.116782) (xy 16.464118 -67.226618) (xy 16.526001 -67.340522)
			(xy 16.580682 -67.458052) (xy 16.627952 -67.578755) (xy 16.667625 -67.702163) (xy 16.69955 -67.827799)
			(xy 16.723602 -67.955176) (xy 16.739689 -68.083802) (xy 16.747748 -68.21318) (xy 16.748252 -68.277994)
			(xy 16.747748 -68.342808) (xy 16.739689 -68.472186) (xy 16.723602 -68.600812) (xy 16.69955 -68.728189)
			(xy 16.667625 -68.853825) (xy 16.627952 -68.977233) (xy 16.580682 -69.097936) (xy 16.526001 -69.215466)
			(xy 16.464118 -69.32937) (xy 16.395273 -69.439206) (xy 16.319734 -69.544549) (xy 16.237791 -69.644992)
			(xy 16.149762 -69.740147) (xy 16.055988 -69.829645) (xy 15.956831 -69.91314) (xy 15.852675 -69.990309)
			(xy 15.743923 -70.060853) (xy 15.630995 -70.1245) (xy 15.51433 -70.181003) (xy 15.394377 -70.230144)
			(xy 15.271601 -70.271732) (xy 15.146477 -70.305607) (xy 15.019489 -70.331637) (xy 14.891128 -70.349722)
			(xy 14.761892 -70.359792) (xy 14.632279 -70.361808) (xy 14.502792 -70.355762) (xy 14.373931 -70.341678)
			(xy 14.246195 -70.319609) (xy 14.120078 -70.289642) (xy 13.996068 -70.251893) (xy 13.874645 -70.206506)
			(xy 13.756278 -70.153659) (xy 13.641426 -70.093555) (xy 13.530533 -70.026427) (xy 13.424027 -69.952535)
			(xy 13.322321 -69.872164) (xy 13.225809 -69.785626) (xy 13.134864 -69.693254) (xy 13.049837 -69.595408)
			(xy 12.971057 -69.492465) (xy 12.89883 -69.384823) (xy 12.833435 -69.272899) (xy 12.775124 -69.157126)
			(xy 12.724124 -69.037952) (xy 12.680632 -68.915838) (xy 12.644815 -68.791255) (xy 12.616813 -68.664688)
			(xy 12.596734 -68.536624) (xy 12.584655 -68.40756) (xy 12.580624 -68.277994) (xy 5.318252 -68.277994)
			(xy 5.317748 -68.342808) (xy 5.309689 -68.472186) (xy 5.293602 -68.600812) (xy 5.26955 -68.728189)
			(xy 5.237625 -68.853825) (xy 5.197952 -68.977233) (xy 5.150682 -69.097936) (xy 5.096001 -69.215466)
			(xy 5.034118 -69.32937) (xy 4.965273 -69.439206) (xy 4.889734 -69.544549) (xy 4.807791 -69.644992)
			(xy 4.719762 -69.740147) (xy 4.625988 -69.829645) (xy 4.526831 -69.91314) (xy 4.422675 -69.990309)
			(xy 4.313923 -70.060853) (xy 4.200995 -70.1245) (xy 4.08433 -70.181003) (xy 3.964377 -70.230144)
			(xy 3.841601 -70.271732) (xy 3.716477 -70.305607) (xy 3.589489 -70.331637) (xy 3.461128 -70.349722)
			(xy 3.331892 -70.359792) (xy 3.202279 -70.361808) (xy 3.072792 -70.355762) (xy 2.943931 -70.341678)
			(xy 2.816195 -70.319609) (xy 2.690078 -70.289642) (xy 2.566068 -70.251893) (xy 2.444645 -70.206506)
			(xy 2.326278 -70.153659) (xy 2.211426 -70.093555) (xy 2.100533 -70.026427) (xy 1.994027 -69.952535)
			(xy 1.892321 -69.872164) (xy 1.795809 -69.785626) (xy 1.704864 -69.693254) (xy 1.619837 -69.595408)
			(xy 1.541057 -69.492465) (xy 1.46883 -69.384823) (xy 1.403435 -69.272899) (xy 1.345124 -69.157126)
			(xy 1.294124 -69.037952) (xy 1.250632 -68.915838) (xy 1.214815 -68.791255) (xy 1.186813 -68.664688)
			(xy 1.166734 -68.536624) (xy 1.154655 -68.40756) (xy 1.150624 -68.277994) (xy 0.509016 -68.277994)
			(xy 0.509016 -78.378673) (xy 74.888081 -78.378673) (xy 74.888081 -78.220963) (xy 74.896069 -78.063456)
			(xy 74.912025 -77.906556) (xy 74.935906 -77.750665) (xy 74.967653 -77.596184) (xy 75.007183 -77.443509)
			(xy 75.054395 -77.293033) (xy 75.109169 -77.14514) (xy 75.171362 -77.000212) (xy 75.240817 -76.85862)
			(xy 75.317353 -76.720727) (xy 75.400776 -76.586888) (xy 75.49087 -76.457446) (xy 75.587405 -76.332733)
			(xy 75.690133 -76.21307) (xy 75.798789 -76.098763) (xy 75.913096 -75.990107) (xy 76.032759 -75.887379)
			(xy 76.157472 -75.790844) (xy 76.286914 -75.70075) (xy 76.420753 -75.617327) (xy 76.558646 -75.540791)
			(xy 76.700238 -75.471336) (xy 76.845166 -75.409143) (xy 76.993059 -75.354369) (xy 77.143535 -75.307157)
			(xy 77.29621 -75.267627) (xy 77.450691 -75.23588) (xy 77.606582 -75.211999) (xy 77.763482 -75.196043)
			(xy 77.920989 -75.188055) (xy 78.078699 -75.188055) (xy 78.236206 -75.196043) (xy 78.393106 -75.211999)
			(xy 78.548997 -75.23588) (xy 78.703478 -75.267627) (xy 78.856153 -75.307157) (xy 79.006629 -75.354369)
			(xy 79.154522 -75.409143) (xy 79.29945 -75.471336) (xy 79.441042 -75.540791) (xy 79.578935 -75.617327)
			(xy 79.712774 -75.70075) (xy 79.842216 -75.790844) (xy 79.966929 -75.887379) (xy 80.086592 -75.990107)
			(xy 80.200899 -76.098763) (xy 80.309555 -76.21307) (xy 80.412283 -76.332733) (xy 80.508818 -76.457446)
			(xy 80.598912 -76.586888) (xy 80.682335 -76.720727) (xy 80.758871 -76.85862) (xy 80.828326 -77.000212)
			(xy 80.890519 -77.14514) (xy 80.945293 -77.293033) (xy 80.992505 -77.443509) (xy 81.032035 -77.596184)
			(xy 81.063782 -77.750665) (xy 81.087663 -77.906556) (xy 81.103619 -78.063456) (xy 81.111607 -78.220963)
			(xy 81.112106 -78.299818) (xy 81.111607 -78.378673) (xy 81.111599 -78.37883) (xy 90.891859 -78.37883)
			(xy 90.891859 -78.221314) (xy 90.899837 -78.064) (xy 90.915772 -77.907291) (xy 90.939625 -77.751592)
			(xy 90.971333 -77.5973) (xy 91.010814 -77.444812) (xy 91.057969 -77.294519) (xy 91.112675 -77.146808)
			(xy 91.174793 -77.002057) (xy 91.244162 -76.860638) (xy 91.320605 -76.722914) (xy 91.403926 -76.589239)
			(xy 91.49391 -76.459955) (xy 91.590326 -76.335395) (xy 91.692928 -76.215878) (xy 91.801452 -76.101712)
			(xy 91.915618 -75.993188) (xy 92.035135 -75.890586) (xy 92.159695 -75.79417) (xy 92.288979 -75.704186)
			(xy 92.422654 -75.620865) (xy 92.560378 -75.544422) (xy 92.701797 -75.475053) (xy 92.846548 -75.412935)
			(xy 92.994259 -75.358229) (xy 93.144552 -75.311074) (xy 93.29704 -75.271593) (xy 93.451332 -75.239885)
			(xy 93.607031 -75.216032) (xy 93.76374 -75.200097) (xy 93.921054 -75.192119) (xy 94.07857 -75.192119)
			(xy 94.235884 -75.200097) (xy 94.392593 -75.216032) (xy 94.548292 -75.239885) (xy 94.702584 -75.271593)
			(xy 94.855072 -75.311074) (xy 95.005365 -75.358229) (xy 95.153076 -75.412935) (xy 95.297827 -75.475053)
			(xy 95.439246 -75.544422) (xy 95.57697 -75.620865) (xy 95.710645 -75.704186) (xy 95.839929 -75.79417)
			(xy 95.964489 -75.890586) (xy 96.084006 -75.993188) (xy 96.198172 -76.101712) (xy 96.306696 -76.215878)
			(xy 96.409298 -76.335395) (xy 96.505714 -76.459955) (xy 96.595698 -76.589239) (xy 96.679019 -76.722914)
			(xy 96.755462 -76.860638) (xy 96.824831 -77.002057) (xy 96.886949 -77.146808) (xy 96.941655 -77.294519)
			(xy 96.98881 -77.444812) (xy 97.028291 -77.5973) (xy 97.059999 -77.751592) (xy 97.083852 -77.907291)
			(xy 97.099787 -78.064) (xy 97.107765 -78.221314) (xy 97.108264 -78.300072) (xy 97.107765 -78.37883)
			(xy 97.099787 -78.536144) (xy 97.083852 -78.692853) (xy 97.059999 -78.848552) (xy 97.028291 -79.002844)
			(xy 96.98881 -79.155332) (xy 96.941655 -79.305625) (xy 96.886949 -79.453336) (xy 96.824831 -79.598087)
			(xy 96.755462 -79.739506) (xy 96.679019 -79.87723) (xy 96.595698 -80.010905) (xy 96.505714 -80.140189)
			(xy 96.409298 -80.264749) (xy 96.306696 -80.384266) (xy 96.198172 -80.498432) (xy 96.084006 -80.606956)
			(xy 95.964489 -80.709558) (xy 95.839929 -80.805974) (xy 95.710645 -80.895958) (xy 95.57697 -80.979279)
			(xy 95.439246 -81.055722) (xy 95.297827 -81.125091) (xy 95.153076 -81.187209) (xy 95.005365 -81.241915)
			(xy 94.855072 -81.28907) (xy 94.702584 -81.328551) (xy 94.548292 -81.360259) (xy 94.392593 -81.384112)
			(xy 94.235884 -81.400047) (xy 94.07857 -81.408025) (xy 93.921054 -81.408025) (xy 93.76374 -81.400047)
			(xy 93.607031 -81.384112) (xy 93.451332 -81.360259) (xy 93.29704 -81.328551) (xy 93.144552 -81.28907)
			(xy 92.994259 -81.241915) (xy 92.846548 -81.187209) (xy 92.701797 -81.125091) (xy 92.560378 -81.055722)
			(xy 92.422654 -80.979279) (xy 92.288979 -80.895958) (xy 92.159695 -80.805974) (xy 92.035135 -80.709558)
			(xy 91.915618 -80.606956) (xy 91.801452 -80.498432) (xy 91.692928 -80.384266) (xy 91.590326 -80.264749)
			(xy 91.49391 -80.140189) (xy 91.403926 -80.010905) (xy 91.320605 -79.87723) (xy 91.244162 -79.739506)
			(xy 91.174793 -79.598087) (xy 91.112675 -79.453336) (xy 91.057969 -79.305625) (xy 91.010814 -79.155332)
			(xy 90.971333 -79.002844) (xy 90.939625 -78.848552) (xy 90.915772 -78.692853) (xy 90.899837 -78.536144)
			(xy 90.891859 -78.37883) (xy 81.111599 -78.37883) (xy 81.103619 -78.53618) (xy 81.087663 -78.69308)
			(xy 81.063782 -78.848971) (xy 81.032035 -79.003452) (xy 80.992505 -79.156127) (xy 80.945293 -79.306603)
			(xy 80.890519 -79.454496) (xy 80.828326 -79.599424) (xy 80.758871 -79.741016) (xy 80.682335 -79.878909)
			(xy 80.598912 -80.012748) (xy 80.508818 -80.14219) (xy 80.412283 -80.266903) (xy 80.309555 -80.386566)
			(xy 80.200899 -80.500873) (xy 80.086592 -80.609529) (xy 79.966929 -80.712257) (xy 79.842216 -80.808792)
			(xy 79.712774 -80.898886) (xy 79.578935 -80.982309) (xy 79.441042 -81.058845) (xy 79.29945 -81.1283)
			(xy 79.154522 -81.190493) (xy 79.006629 -81.245267) (xy 78.856153 -81.292479) (xy 78.703478 -81.332009)
			(xy 78.548997 -81.363756) (xy 78.393106 -81.387637) (xy 78.236206 -81.403593) (xy 78.078699 -81.411581)
			(xy 77.920989 -81.411581) (xy 77.763482 -81.403593) (xy 77.606582 -81.387637) (xy 77.450691 -81.363756)
			(xy 77.29621 -81.332009) (xy 77.143535 -81.292479) (xy 76.993059 -81.245267) (xy 76.845166 -81.190493)
			(xy 76.700238 -81.1283) (xy 76.558646 -81.058845) (xy 76.420753 -80.982309) (xy 76.286914 -80.898886)
			(xy 76.157472 -80.808792) (xy 76.032759 -80.712257) (xy 75.913096 -80.609529) (xy 75.798789 -80.500873)
			(xy 75.690133 -80.386566) (xy 75.587405 -80.266903) (xy 75.49087 -80.14219) (xy 75.400776 -80.012748)
			(xy 75.317353 -79.878909) (xy 75.240817 -79.741016) (xy 75.171362 -79.599424) (xy 75.109169 -79.454496)
			(xy 75.054395 -79.306603) (xy 75.007183 -79.156127) (xy 74.967653 -79.003452) (xy 74.935906 -78.848971)
			(xy 74.912025 -78.69308) (xy 74.896069 -78.53618) (xy 74.888081 -78.378673) (xy 0.509016 -78.378673)
			(xy 0.509016 -95.81007) (xy 39.818063 -95.81007) (xy 39.82207 -95.694046) (xy 39.834072 -95.578574)
			(xy 39.854012 -95.464206) (xy 39.881795 -95.351486) (xy 39.917289 -95.240952) (xy 39.960324 -95.133129)
			(xy 40.010695 -95.028532) (xy 40.068162 -94.92766) (xy 40.132452 -94.830993) (xy 40.203257 -94.738992)
			(xy 40.280241 -94.652095) (xy 40.363037 -94.570716) (xy 40.45125 -94.495243) (xy 40.54446 -94.426036)
			(xy 40.642223 -94.363424) (xy 40.744072 -94.307707) (xy 40.849522 -94.259149) (xy 40.958071 -94.217981)
			(xy 41.069202 -94.184401) (xy 41.182385 -94.158568) (xy 41.29708 -94.140605) (xy 41.412742 -94.130597)
			(xy 41.528818 -94.128594) (xy 41.644756 -94.134603) (xy 41.760003 -94.148596) (xy 41.874009 -94.170507)
			(xy 41.986233 -94.200232) (xy 42.096139 -94.237628) (xy 42.203202 -94.282517) (xy 42.306914 -94.334686)
			(xy 42.406779 -94.393886) (xy 42.502322 -94.459835) (xy 42.593088 -94.532218) (xy 42.678643 -94.610691)
			(xy 42.758581 -94.694879) (xy 42.83252 -94.784381) (xy 42.900108 -94.878772) (xy 42.961022 -94.9776)
			(xy 43.014974 -95.080396) (xy 43.061704 -95.186669) (xy 43.100992 -95.295913) (xy 43.132649 -95.407606)
			(xy 43.156525 -95.521218) (xy 43.172506 -95.636206) (xy 43.180515 -95.752023) (xy 43.181016 -95.81007)
			(xy 43.180515 -95.868117) (xy 43.172506 -95.983934) (xy 43.156525 -96.098922) (xy 43.132649 -96.212534)
			(xy 43.100992 -96.324227) (xy 43.061704 -96.433471) (xy 43.014974 -96.539744) (xy 42.961022 -96.64254)
			(xy 42.900108 -96.741368) (xy 42.83252 -96.835759) (xy 42.758581 -96.925261) (xy 42.678643 -97.009449)
			(xy 42.593088 -97.087922) (xy 42.502604 -97.16008) (xy 93.154506 -97.16008) (xy 93.158522 -97.04381)
			(xy 93.170549 -96.928095) (xy 93.190531 -96.813485) (xy 93.218373 -96.700526) (xy 93.253942 -96.589758)
			(xy 93.297068 -96.481707) (xy 93.347545 -96.376889) (xy 93.405134 -96.275804) (xy 93.46956 -96.178932)
			(xy 93.540515 -96.086736) (xy 93.617662 -95.999655) (xy 93.700633 -95.918104) (xy 93.789033 -95.842472)
			(xy 93.88244 -95.773118) (xy 93.980409 -95.710375) (xy 94.082473 -95.654539) (xy 94.188147 -95.605878)
			(xy 94.296926 -95.564624) (xy 94.408291 -95.530973) (xy 94.521714 -95.505085) (xy 94.636651 -95.487084)
			(xy 94.752557 -95.477055) (xy 94.868879 -95.475047) (xy 94.985062 -95.481069) (xy 95.100553 -95.495092)
			(xy 95.214801 -95.51705) (xy 95.327262 -95.546837) (xy 95.4374 -95.584312) (xy 95.54469 -95.629297)
			(xy 95.648621 -95.681576) (xy 95.748697 -95.740901) (xy 95.844443 -95.806989) (xy 95.9354 -95.879525)
			(xy 96.021136 -95.958164) (xy 96.101243 -96.04253) (xy 96.175339 -96.132222) (xy 96.243069 -96.226812)
			(xy 96.304113 -96.32585) (xy 96.358178 -96.428863) (xy 96.405008 -96.53536) (xy 96.444379 -96.644835)
			(xy 96.476103 -96.756765) (xy 96.500029 -96.870617) (xy 96.516043 -96.985849) (xy 96.52407 -97.101911)
			(xy 96.524572 -97.16008) (xy 96.52407 -97.218249) (xy 96.516043 -97.334311) (xy 96.500029 -97.449543)
			(xy 96.476103 -97.563395) (xy 96.444379 -97.675325) (xy 96.405008 -97.7848) (xy 96.358178 -97.891297)
			(xy 96.304113 -97.99431) (xy 96.243069 -98.093348) (xy 96.175339 -98.187938) (xy 96.101243 -98.27763)
			(xy 96.021136 -98.361996) (xy 95.9354 -98.440635) (xy 95.844443 -98.513171) (xy 95.748697 -98.579259)
			(xy 95.648621 -98.638584) (xy 95.54469 -98.690863) (xy 95.4374 -98.735848) (xy 95.327262 -98.773323)
			(xy 95.214801 -98.80311) (xy 95.100553 -98.825068) (xy 94.985062 -98.839091) (xy 94.868879 -98.845113)
			(xy 94.752557 -98.843105) (xy 94.636651 -98.833076) (xy 94.521714 -98.815075) (xy 94.408291 -98.789187)
			(xy 94.296926 -98.755536) (xy 94.188147 -98.714282) (xy 94.082473 -98.665621) (xy 93.980409 -98.609785)
			(xy 93.88244 -98.547042) (xy 93.789033 -98.477688) (xy 93.700633 -98.402056) (xy 93.617662 -98.320505)
			(xy 93.540515 -98.233424) (xy 93.46956 -98.141228) (xy 93.405134 -98.044356) (xy 93.347545 -97.943271)
			(xy 93.297068 -97.838453) (xy 93.253942 -97.730402) (xy 93.218373 -97.619634) (xy 93.190531 -97.506675)
			(xy 93.170549 -97.392065) (xy 93.158522 -97.27635) (xy 93.154506 -97.16008) (xy 42.502604 -97.16008)
			(xy 42.502322 -97.160305) (xy 42.406779 -97.226254) (xy 42.306914 -97.285454) (xy 42.203202 -97.337623)
			(xy 42.096139 -97.382512) (xy 41.986233 -97.419908) (xy 41.874009 -97.449633) (xy 41.760003 -97.471544)
			(xy 41.644756 -97.485537) (xy 41.528818 -97.491546) (xy 41.412742 -97.489543) (xy 41.29708 -97.479535)
			(xy 41.182385 -97.461572) (xy 41.069202 -97.435739) (xy 40.958071 -97.402159) (xy 40.849522 -97.360991)
			(xy 40.744072 -97.312433) (xy 40.642223 -97.256716) (xy 40.54446 -97.194104) (xy 40.45125 -97.124897)
			(xy 40.363037 -97.049424) (xy 40.280241 -96.968045) (xy 40.203257 -96.881148) (xy 40.132452 -96.789147)
			(xy 40.068162 -96.69248) (xy 40.010695 -96.591608) (xy 39.960324 -96.487011) (xy 39.917289 -96.379188)
			(xy 39.881795 -96.268654) (xy 39.854012 -96.155934) (xy 39.834072 -96.041566) (xy 39.82207 -95.926094)
			(xy 39.818063 -95.81007) (xy 0.509016 -95.81007) (xy 0.509016 -99.271836) (xy 1.150624 -99.271836)
			(xy 1.154655 -99.14227) (xy 1.166734 -99.013206) (xy 1.186813 -98.885142) (xy 1.214815 -98.758575)
			(xy 1.250632 -98.633992) (xy 1.294124 -98.511878) (xy 1.345124 -98.392704) (xy 1.403435 -98.276931)
			(xy 1.46883 -98.165007) (xy 1.541057 -98.057365) (xy 1.619837 -97.954422) (xy 1.704864 -97.856576)
			(xy 1.795809 -97.764204) (xy 1.892321 -97.677666) (xy 1.994027 -97.597295) (xy 2.100533 -97.523403)
			(xy 2.211426 -97.456275) (xy 2.326278 -97.396171) (xy 2.444645 -97.343324) (xy 2.566068 -97.297937)
			(xy 2.690078 -97.260188) (xy 2.816195 -97.230221) (xy 2.943931 -97.208152) (xy 3.072792 -97.194068)
			(xy 3.202279 -97.188022) (xy 3.331892 -97.190038) (xy 3.461128 -97.200108) (xy 3.589489 -97.218193)
			(xy 3.716477 -97.244223) (xy 3.841601 -97.278098) (xy 3.964377 -97.319686) (xy 4.08433 -97.368827)
			(xy 4.200995 -97.42533) (xy 4.313923 -97.488977) (xy 4.422675 -97.559521) (xy 4.526831 -97.63669)
			(xy 4.625988 -97.720185) (xy 4.719762 -97.809683) (xy 4.807791 -97.904838) (xy 4.889734 -98.005281)
			(xy 4.965273 -98.110624) (xy 5.034118 -98.22046) (xy 5.096001 -98.334364) (xy 5.150682 -98.451894)
			(xy 5.197952 -98.572597) (xy 5.237625 -98.696005) (xy 5.26955 -98.821641) (xy 5.293602 -98.949018)
			(xy 5.309689 -99.077644) (xy 5.317748 -99.207022) (xy 5.318252 -99.271836) (xy 12.580624 -99.271836)
			(xy 12.584655 -99.14227) (xy 12.596734 -99.013206) (xy 12.616813 -98.885142) (xy 12.644815 -98.758575)
			(xy 12.680632 -98.633992) (xy 12.724124 -98.511878) (xy 12.775124 -98.392704) (xy 12.833435 -98.276931)
			(xy 12.89883 -98.165007) (xy 12.971057 -98.057365) (xy 13.049837 -97.954422) (xy 13.134864 -97.856576)
			(xy 13.225809 -97.764204) (xy 13.322321 -97.677666) (xy 13.424027 -97.597295) (xy 13.530533 -97.523403)
			(xy 13.641426 -97.456275) (xy 13.756278 -97.396171) (xy 13.874645 -97.343324) (xy 13.996068 -97.297937)
			(xy 14.120078 -97.260188) (xy 14.246195 -97.230221) (xy 14.373931 -97.208152) (xy 14.502792 -97.194068)
			(xy 14.632279 -97.188022) (xy 14.761892 -97.190038) (xy 14.891128 -97.200108) (xy 15.019489 -97.218193)
			(xy 15.146477 -97.244223) (xy 15.271601 -97.278098) (xy 15.394377 -97.319686) (xy 15.51433 -97.368827)
			(xy 15.630995 -97.42533) (xy 15.743923 -97.488977) (xy 15.852675 -97.559521) (xy 15.956831 -97.63669)
			(xy 16.055988 -97.720185) (xy 16.149762 -97.809683) (xy 16.237791 -97.904838) (xy 16.319734 -98.005281)
			(xy 16.395273 -98.110624) (xy 16.464118 -98.22046) (xy 16.526001 -98.334364) (xy 16.580682 -98.451894)
			(xy 16.627952 -98.572597) (xy 16.667625 -98.696005) (xy 16.69955 -98.821641) (xy 16.723602 -98.949018)
			(xy 16.739689 -99.077644) (xy 16.747748 -99.207022) (xy 16.748252 -99.271836) (xy 16.747748 -99.33665)
			(xy 16.739689 -99.466028) (xy 16.723602 -99.594654) (xy 16.69955 -99.722031) (xy 16.667625 -99.847667)
			(xy 16.627952 -99.971075) (xy 16.580682 -100.091778) (xy 16.526001 -100.209308) (xy 16.464118 -100.323212)
			(xy 16.395273 -100.433048) (xy 16.319734 -100.538391) (xy 16.237791 -100.638834) (xy 16.149762 -100.733989)
			(xy 16.055988 -100.823487) (xy 15.956831 -100.906982) (xy 15.852675 -100.984151) (xy 15.743923 -101.054695)
			(xy 15.630995 -101.118342) (xy 15.51433 -101.174845) (xy 15.394377 -101.223986) (xy 15.271601 -101.265574)
			(xy 15.146477 -101.299449) (xy 15.019489 -101.325479) (xy 14.891128 -101.343564) (xy 14.761892 -101.353634)
			(xy 14.632279 -101.35565) (xy 14.502792 -101.349604) (xy 14.373931 -101.33552) (xy 14.246195 -101.313451)
			(xy 14.120078 -101.283484) (xy 13.996068 -101.245735) (xy 13.874645 -101.200348) (xy 13.756278 -101.147501)
			(xy 13.641426 -101.087397) (xy 13.530533 -101.020269) (xy 13.424027 -100.946377) (xy 13.322321 -100.866006)
			(xy 13.225809 -100.779468) (xy 13.134864 -100.687096) (xy 13.049837 -100.58925) (xy 12.971057 -100.486307)
			(xy 12.89883 -100.378665) (xy 12.833435 -100.266741) (xy 12.775124 -100.150968) (xy 12.724124 -100.031794)
			(xy 12.680632 -99.90968) (xy 12.644815 -99.785097) (xy 12.616813 -99.65853) (xy 12.596734 -99.530466)
			(xy 12.584655 -99.401402) (xy 12.580624 -99.271836) (xy 5.318252 -99.271836) (xy 5.317748 -99.33665)
			(xy 5.309689 -99.466028) (xy 5.293602 -99.594654) (xy 5.26955 -99.722031) (xy 5.237625 -99.847667)
			(xy 5.197952 -99.971075) (xy 5.150682 -100.091778) (xy 5.096001 -100.209308) (xy 5.034118 -100.323212)
			(xy 4.965273 -100.433048) (xy 4.889734 -100.538391) (xy 4.807791 -100.638834) (xy 4.719762 -100.733989)
			(xy 4.625988 -100.823487) (xy 4.526831 -100.906982) (xy 4.422675 -100.984151) (xy 4.313923 -101.054695)
			(xy 4.200995 -101.118342) (xy 4.08433 -101.174845) (xy 3.964377 -101.223986) (xy 3.841601 -101.265574)
			(xy 3.716477 -101.299449) (xy 3.589489 -101.325479) (xy 3.461128 -101.343564) (xy 3.331892 -101.353634)
			(xy 3.202279 -101.35565) (xy 3.072792 -101.349604) (xy 2.943931 -101.33552) (xy 2.816195 -101.313451)
			(xy 2.690078 -101.283484) (xy 2.566068 -101.245735) (xy 2.444645 -101.200348) (xy 2.326278 -101.147501)
			(xy 2.211426 -101.087397) (xy 2.100533 -101.020269) (xy 1.994027 -100.946377) (xy 1.892321 -100.866006)
			(xy 1.795809 -100.779468) (xy 1.704864 -100.687096) (xy 1.619837 -100.58925) (xy 1.541057 -100.486307)
			(xy 1.46883 -100.378665) (xy 1.403435 -100.266741) (xy 1.345124 -100.150968) (xy 1.294124 -100.031794)
			(xy 1.250632 -99.90968) (xy 1.214815 -99.785097) (xy 1.186813 -99.65853) (xy 1.166734 -99.530466)
			(xy 1.154655 -99.401402) (xy 1.150624 -99.271836) (xy 0.509016 -99.271836) (xy 0.509016 -108.909866)
			(xy 86.877404 -108.909866) (xy 86.881424 -108.719215) (xy 86.893478 -108.528902) (xy 86.913544 -108.339267)
			(xy 86.941587 -108.150646) (xy 86.977556 -107.963376) (xy 87.021388 -107.777788) (xy 87.073005 -107.594213)
			(xy 87.132315 -107.412977) (xy 87.199213 -107.234402) (xy 87.273579 -107.058807) (xy 87.355281 -106.886502)
			(xy 87.444175 -106.717795) (xy 87.540101 -106.552985) (xy 87.64289 -106.392366) (xy 87.752359 -106.236223)
			(xy 87.868313 -106.084834) (xy 87.990547 -105.938467) (xy 88.118841 -105.797383) (xy 88.252969 -105.661834)
			(xy 88.392693 -105.532059) (xy 88.537763 -105.408289) (xy 88.687921 -105.290746) (xy 88.842902 -105.179637)
			(xy 89.002429 -105.07516) (xy 89.166218 -104.977501) (xy 89.333978 -104.886834) (xy 89.505412 -104.80332)
			(xy 89.680214 -104.727107) (xy 89.858073 -104.658331) (xy 90.038674 -104.597113) (xy 90.221694 -104.543564)
			(xy 90.40681 -104.497778) (xy 90.593691 -104.459836) (xy 90.782006 -104.429807) (xy 90.971419 -104.407742)
			(xy 91.161593 -104.393683) (xy 91.352192 -104.387653) (xy 91.542875 -104.389663) (xy 91.733304 -104.39971)
			(xy 91.92314 -104.417776) (xy 92.112046 -104.443829) (xy 92.299685 -104.477822) (xy 92.485725 -104.519695)
			(xy 92.669834 -104.569374) (xy 92.851685 -104.62677) (xy 93.030955 -104.691781) (xy 93.207325 -104.764292)
			(xy 93.380481 -104.844173) (xy 93.550116 -104.931283) (xy 93.715928 -105.025467) (xy 93.877622 -105.126558)
			(xy 94.03491 -105.234374) (xy 94.187513 -105.348726) (xy 94.335161 -105.469409) (xy 94.477589 -105.59621)
			(xy 94.614545 -105.728901) (xy 94.745786 -105.867249) (xy 94.871078 -106.011006) (xy 94.990198 -106.159917)
			(xy 95.102934 -106.313718) (xy 95.209087 -106.472134) (xy 95.308467 -106.634885) (xy 95.400897 -106.80168)
			(xy 95.486214 -106.972224) (xy 95.564266 -107.146212) (xy 95.634913 -107.323337) (xy 95.698031 -107.503282)
			(xy 95.753507 -107.685728) (xy 95.801242 -107.870351) (xy 95.841152 -108.056821) (xy 95.873165 -108.244809)
			(xy 95.897225 -108.433979) (xy 95.913288 -108.623995) (xy 95.921327 -108.814519) (xy 95.92183 -108.909866)
			(xy 95.921327 -109.005213) (xy 95.913288 -109.195737) (xy 95.897225 -109.385753) (xy 95.873165 -109.574923)
			(xy 95.841152 -109.762911) (xy 95.801242 -109.949381) (xy 95.753507 -110.134004) (xy 95.698031 -110.31645)
			(xy 95.634913 -110.496395) (xy 95.564266 -110.67352) (xy 95.486214 -110.847508) (xy 95.400897 -111.018052)
			(xy 95.308467 -111.184847) (xy 95.209087 -111.347598) (xy 95.102934 -111.506014) (xy 94.990198 -111.659815)
			(xy 94.871078 -111.808726) (xy 94.745786 -111.952483) (xy 94.614545 -112.090831) (xy 94.477589 -112.223522)
			(xy 94.335161 -112.350323) (xy 94.187513 -112.471006) (xy 94.03491 -112.585358) (xy 93.877622 -112.693174)
			(xy 93.715928 -112.794265) (xy 93.550116 -112.888449) (xy 93.380481 -112.975559) (xy 93.207325 -113.05544)
			(xy 93.030955 -113.127951) (xy 92.851685 -113.192962) (xy 92.669834 -113.250358) (xy 92.485725 -113.300037)
			(xy 92.299685 -113.34191) (xy 92.112046 -113.375903) (xy 91.92314 -113.401956) (xy 91.733304 -113.420022)
			(xy 91.542875 -113.430069) (xy 91.352192 -113.432079) (xy 91.161593 -113.426049) (xy 90.971419 -113.41199)
			(xy 90.782006 -113.389925) (xy 90.593691 -113.359896) (xy 90.40681 -113.321954) (xy 90.221694 -113.276168)
			(xy 90.038674 -113.222619) (xy 89.858073 -113.161401) (xy 89.680214 -113.092625) (xy 89.505412 -113.016412)
			(xy 89.333978 -112.932898) (xy 89.166218 -112.842231) (xy 89.002429 -112.744572) (xy 88.842902 -112.640095)
			(xy 88.687921 -112.528986) (xy 88.537763 -112.411443) (xy 88.392693 -112.287673) (xy 88.252969 -112.157898)
			(xy 88.118841 -112.022349) (xy 87.990547 -111.881265) (xy 87.868313 -111.734898) (xy 87.752359 -111.583509)
			(xy 87.64289 -111.427366) (xy 87.540101 -111.266747) (xy 87.444175 -111.101937) (xy 87.355281 -110.93323)
			(xy 87.273579 -110.760925) (xy 87.199213 -110.58533) (xy 87.132315 -110.406755) (xy 87.073005 -110.225519)
			(xy 87.021388 -110.041944) (xy 86.977556 -109.856356) (xy 86.941587 -109.669086) (xy 86.913544 -109.480465)
			(xy 86.893478 -109.29083) (xy 86.881424 -109.100517) (xy 86.877404 -108.909866) (xy 0.509016 -108.909866)
			(xy 0.509016 -118.09984) (xy 14.086591 -118.09984) (xy 14.090616 -117.957648) (xy 14.102679 -117.815912)
			(xy 14.122742 -117.675086) (xy 14.15074 -117.53562) (xy 14.186584 -117.397961) (xy 14.230158 -117.262551)
			(xy 14.281323 -117.129823) (xy 14.339916 -117.000202) (xy 14.405747 -116.874104) (xy 14.478608 -116.751932)
			(xy 14.558263 -116.634078) (xy 14.644459 -116.520919) (xy 14.736918 -116.412817) (xy 14.835346 -116.31012)
			(xy 14.939425 -116.213156) (xy 15.048824 -116.122236) (xy 15.163192 -116.03765) (xy 15.282161 -115.95967)
			(xy 15.405352 -115.888546) (xy 15.532369 -115.824505) (xy 15.662806 -115.767753) (xy 15.796245 -115.718471)
			(xy 15.932258 -115.676817) (xy 16.07041 -115.642925) (xy 16.210259 -115.616904) (xy 16.351355 -115.598836)
			(xy 16.493247 -115.588779) (xy 16.635482 -115.586766) (xy 16.777602 -115.592803) (xy 16.919153 -115.606871)
			(xy 17.059682 -115.628925) (xy 17.198737 -115.658894) (xy 17.335875 -115.696682) (xy 17.470655 -115.742168)
			(xy 17.602646 -115.795206) (xy 17.731425 -115.855627) (xy 17.856579 -115.923236) (xy 17.977707 -115.997818)
			(xy 18.094423 -116.079134) (xy 18.206351 -116.166922) (xy 18.313133 -116.260902) (xy 18.414427 -116.360772)
			(xy 18.509908 -116.466214) (xy 18.599272 -116.576888) (xy 18.68223 -116.692441) (xy 18.758519 -116.812502)
			(xy 18.827893 -116.936687) (xy 18.89013 -117.064598) (xy 18.945031 -117.195825) (xy 18.992419 -117.329948)
			(xy 19.032144 -117.466537) (xy 19.064077 -117.605155) (xy 19.088118 -117.745357) (xy 19.104187 -117.886695)
			(xy 19.112235 -118.028716) (xy 19.112738 -118.09984) (xy 19.112235 -118.170964) (xy 19.104187 -118.312985)
			(xy 19.088118 -118.454323) (xy 19.064077 -118.594525) (xy 19.032144 -118.733143) (xy 18.992419 -118.869732)
			(xy 18.945031 -119.003855) (xy 18.89013 -119.135082) (xy 18.827893 -119.262993) (xy 18.758519 -119.387178)
			(xy 18.68223 -119.507239) (xy 18.599272 -119.622792) (xy 18.509908 -119.733466) (xy 18.414427 -119.838908)
			(xy 18.313133 -119.938778) (xy 18.206351 -120.032758) (xy 18.094423 -120.120546) (xy 17.977707 -120.201862)
			(xy 17.856579 -120.276444) (xy 17.731425 -120.344053) (xy 17.602646 -120.404474) (xy 17.470655 -120.457512)
			(xy 17.335875 -120.502998) (xy 17.198737 -120.540786) (xy 17.059682 -120.570755) (xy 16.919153 -120.592809)
			(xy 16.777602 -120.606877) (xy 16.635482 -120.612914) (xy 16.493247 -120.610901) (xy 16.351355 -120.600844)
			(xy 16.210259 -120.582776) (xy 16.07041 -120.556755) (xy 15.932258 -120.522863) (xy 15.796245 -120.481209)
			(xy 15.662806 -120.431927) (xy 15.532369 -120.375175) (xy 15.405352 -120.311134) (xy 15.282161 -120.24001)
			(xy 15.163192 -120.16203) (xy 15.048824 -120.077444) (xy 14.939425 -119.986524) (xy 14.835346 -119.88956)
			(xy 14.736918 -119.786863) (xy 14.644459 -119.678761) (xy 14.558263 -119.565602) (xy 14.478608 -119.447748)
			(xy 14.405747 -119.325576) (xy 14.339916 -119.199478) (xy 14.281323 -119.069857) (xy 14.230158 -118.937129)
			(xy 14.186584 -118.801719) (xy 14.15074 -118.66406) (xy 14.122742 -118.524594) (xy 14.102679 -118.383768)
			(xy 14.090616 -118.242032) (xy 14.086591 -118.09984) (xy 0.509016 -118.09984) (xy 0.509016 -121.19991)
			(xy 75.486519 -121.19991) (xy 75.490544 -121.057718) (xy 75.502607 -120.915982) (xy 75.52267 -120.775156)
			(xy 75.550668 -120.63569) (xy 75.586512 -120.498031) (xy 75.630086 -120.362621) (xy 75.681251 -120.229893)
			(xy 75.739844 -120.100272) (xy 75.805675 -119.974174) (xy 75.878536 -119.852002) (xy 75.958191 -119.734148)
			(xy 76.044387 -119.620989) (xy 76.136846 -119.512887) (xy 76.235274 -119.41019) (xy 76.339353 -119.313226)
			(xy 76.448752 -119.222306) (xy 76.56312 -119.13772) (xy 76.682089 -119.05974) (xy 76.80528 -118.988616)
			(xy 76.932297 -118.924575) (xy 77.062734 -118.867823) (xy 77.196173 -118.818541) (xy 77.332186 -118.776887)
			(xy 77.470338 -118.742995) (xy 77.610187 -118.716974) (xy 77.751283 -118.698906) (xy 77.893175 -118.688849)
			(xy 78.03541 -118.686836) (xy 78.17753 -118.692873) (xy 78.319081 -118.706941) (xy 78.45961 -118.728995)
			(xy 78.598665 -118.758964) (xy 78.735803 -118.796752) (xy 78.870583 -118.842238) (xy 79.002574 -118.895276)
			(xy 79.131353 -118.955697) (xy 79.256507 -119.023306) (xy 79.377635 -119.097888) (xy 79.494351 -119.179204)
			(xy 79.606279 -119.266992) (xy 79.713061 -119.360972) (xy 79.814355 -119.460842) (xy 79.909836 -119.566284)
			(xy 79.9992 -119.676958) (xy 80.082158 -119.792511) (xy 80.158447 -119.912572) (xy 80.227821 -120.036757)
			(xy 80.290058 -120.164668) (xy 80.344959 -120.295895) (xy 80.392347 -120.430018) (xy 80.432072 -120.566607)
			(xy 80.464005 -120.705225) (xy 80.488046 -120.845427) (xy 80.504115 -120.986765) (xy 80.512163 -121.128786)
			(xy 80.512666 -121.19991) (xy 80.512163 -121.271034) (xy 80.504115 -121.413055) (xy 80.488046 -121.554393)
			(xy 80.464005 -121.694595) (xy 80.432072 -121.833213) (xy 80.392347 -121.969802) (xy 80.344959 -122.103925)
			(xy 80.290058 -122.235152) (xy 80.227821 -122.363063) (xy 80.158447 -122.487248) (xy 80.082158 -122.607309)
			(xy 79.9992 -122.722862) (xy 79.909836 -122.833536) (xy 79.814355 -122.938978) (xy 79.713061 -123.038848)
			(xy 79.606279 -123.132828) (xy 79.494351 -123.220616) (xy 79.377635 -123.301932) (xy 79.256507 -123.376514)
			(xy 79.131353 -123.444123) (xy 79.002574 -123.504544) (xy 78.870583 -123.557582) (xy 78.735803 -123.603068)
			(xy 78.598665 -123.640856) (xy 78.45961 -123.670825) (xy 78.319081 -123.692879) (xy 78.17753 -123.706947)
			(xy 78.03541 -123.712984) (xy 77.893175 -123.710971) (xy 77.751283 -123.700914) (xy 77.610187 -123.682846)
			(xy 77.470338 -123.656825) (xy 77.332186 -123.622933) (xy 77.196173 -123.581279) (xy 77.062734 -123.531997)
			(xy 76.932297 -123.475245) (xy 76.80528 -123.411204) (xy 76.682089 -123.34008) (xy 76.56312 -123.2621)
			(xy 76.448752 -123.177514) (xy 76.339353 -123.086594) (xy 76.235274 -122.98963) (xy 76.136846 -122.886933)
			(xy 76.044387 -122.778831) (xy 75.958191 -122.665672) (xy 75.878536 -122.547818) (xy 75.805675 -122.425646)
			(xy 75.739844 -122.299548) (xy 75.681251 -122.169927) (xy 75.630086 -122.037199) (xy 75.586512 -121.901789)
			(xy 75.550668 -121.76413) (xy 75.52267 -121.624664) (xy 75.502607 -121.483838) (xy 75.490544 -121.342102)
			(xy 75.486519 -121.19991) (xy 0.509016 -121.19991) (xy 0.509016 -138.163122) (xy 1.547863 -138.163122)
			(xy 1.547863 -138.036986) (xy 1.555783 -137.911098) (xy 1.571593 -137.785956) (xy 1.595228 -137.662053)
			(xy 1.626597 -137.53988) (xy 1.665575 -137.419917) (xy 1.712009 -137.302638) (xy 1.765716 -137.188506)
			(xy 1.826483 -137.077971) (xy 1.89407 -136.971471) (xy 1.968211 -136.869424) (xy 2.048614 -136.772234)
			(xy 2.13496 -136.680284) (xy 2.22691 -136.593938) (xy 2.3241 -136.513535) (xy 2.426147 -136.439394)
			(xy 2.532647 -136.371807) (xy 2.643182 -136.31104) (xy 2.757314 -136.257333) (xy 2.874593 -136.210899)
			(xy 2.994556 -136.171921) (xy 3.116729 -136.140552) (xy 3.240632 -136.116917) (xy 3.365774 -136.101107)
			(xy 3.491662 -136.093187) (xy 3.617798 -136.093187) (xy 3.743686 -136.101107) (xy 3.868828 -136.116917)
			(xy 3.992731 -136.140552) (xy 4.114904 -136.171921) (xy 4.234867 -136.210899) (xy 4.352146 -136.257333)
			(xy 4.466278 -136.31104) (xy 4.576813 -136.371807) (xy 4.683313 -136.439394) (xy 4.78536 -136.513535)
			(xy 4.88255 -136.593938) (xy 4.9745 -136.680284) (xy 5.060846 -136.772234) (xy 5.141249 -136.869424)
			(xy 5.21539 -136.971471) (xy 5.282977 -137.077971) (xy 5.343744 -137.188506) (xy 5.397451 -137.302638)
			(xy 5.443885 -137.419917) (xy 5.482863 -137.53988) (xy 5.514232 -137.662053) (xy 5.537867 -137.785956)
			(xy 5.553677 -137.911098) (xy 5.561597 -138.036986) (xy 5.562092 -138.100054) (xy 5.561597 -138.163122)
			(xy 12.977863 -138.163122) (xy 12.977863 -138.036986) (xy 12.985783 -137.911098) (xy 13.001593 -137.785956)
			(xy 13.025228 -137.662053) (xy 13.056597 -137.53988) (xy 13.095575 -137.419917) (xy 13.142009 -137.302638)
			(xy 13.195716 -137.188506) (xy 13.256483 -137.077971) (xy 13.32407 -136.971471) (xy 13.398211 -136.869424)
			(xy 13.478614 -136.772234) (xy 13.56496 -136.680284) (xy 13.65691 -136.593938) (xy 13.7541 -136.513535)
			(xy 13.856147 -136.439394) (xy 13.962647 -136.371807) (xy 14.073182 -136.31104) (xy 14.187314 -136.257333)
			(xy 14.304593 -136.210899) (xy 14.424556 -136.171921) (xy 14.546729 -136.140552) (xy 14.670632 -136.116917)
			(xy 14.795774 -136.101107) (xy 14.921662 -136.093187) (xy 15.047798 -136.093187) (xy 15.173686 -136.101107)
			(xy 15.298828 -136.116917) (xy 15.422731 -136.140552) (xy 15.544904 -136.171921) (xy 15.664867 -136.210899)
			(xy 15.782146 -136.257333) (xy 15.896278 -136.31104) (xy 16.006813 -136.371807) (xy 16.113313 -136.439394)
			(xy 16.21536 -136.513535) (xy 16.31255 -136.593938) (xy 16.4045 -136.680284) (xy 16.490846 -136.772234)
			(xy 16.571249 -136.869424) (xy 16.64539 -136.971471) (xy 16.712977 -137.077971) (xy 16.773744 -137.188506)
			(xy 16.827451 -137.302638) (xy 16.873885 -137.419917) (xy 16.912863 -137.53988) (xy 16.944232 -137.662053)
			(xy 16.967867 -137.785956) (xy 16.983677 -137.911098) (xy 16.991597 -138.036986) (xy 16.992092 -138.100054)
			(xy 16.991597 -138.163122) (xy 16.983677 -138.28901) (xy 16.967867 -138.414152) (xy 16.944232 -138.538055)
			(xy 16.912863 -138.660228) (xy 16.873885 -138.780191) (xy 16.827451 -138.89747) (xy 16.773744 -139.011602)
			(xy 16.712977 -139.122137) (xy 16.64539 -139.228637) (xy 16.571249 -139.330684) (xy 16.490846 -139.427874)
			(xy 16.4045 -139.519824) (xy 16.31255 -139.60617) (xy 16.21536 -139.686573) (xy 16.113313 -139.760714)
			(xy 16.006813 -139.828301) (xy 15.896278 -139.889068) (xy 15.782146 -139.942775) (xy 15.664867 -139.989209)
			(xy 15.544904 -140.028187) (xy 15.422731 -140.059556) (xy 15.298828 -140.083191) (xy 15.173686 -140.099001)
			(xy 15.047798 -140.106921) (xy 14.921662 -140.106921) (xy 14.795774 -140.099001) (xy 14.670632 -140.083191)
			(xy 14.546729 -140.059556) (xy 14.424556 -140.028187) (xy 14.304593 -139.989209) (xy 14.187314 -139.942775)
			(xy 14.073182 -139.889068) (xy 13.962647 -139.828301) (xy 13.856147 -139.760714) (xy 13.7541 -139.686573)
			(xy 13.65691 -139.60617) (xy 13.56496 -139.519824) (xy 13.478614 -139.427874) (xy 13.398211 -139.330684)
			(xy 13.32407 -139.228637) (xy 13.256483 -139.122137) (xy 13.195716 -139.011602) (xy 13.142009 -138.89747)
			(xy 13.095575 -138.780191) (xy 13.056597 -138.660228) (xy 13.025228 -138.538055) (xy 13.001593 -138.414152)
			(xy 12.985783 -138.28901) (xy 12.977863 -138.163122) (xy 5.561597 -138.163122) (xy 5.553677 -138.28901)
			(xy 5.537867 -138.414152) (xy 5.514232 -138.538055) (xy 5.482863 -138.660228) (xy 5.443885 -138.780191)
			(xy 5.397451 -138.89747) (xy 5.343744 -139.011602) (xy 5.282977 -139.122137) (xy 5.21539 -139.228637)
			(xy 5.141249 -139.330684) (xy 5.060846 -139.427874) (xy 4.9745 -139.519824) (xy 4.88255 -139.60617)
			(xy 4.78536 -139.686573) (xy 4.683313 -139.760714) (xy 4.576813 -139.828301) (xy 4.466278 -139.889068)
			(xy 4.352146 -139.942775) (xy 4.234867 -139.989209) (xy 4.114904 -140.028187) (xy 3.992731 -140.059556)
			(xy 3.868828 -140.083191) (xy 3.743686 -140.099001) (xy 3.617798 -140.106921) (xy 3.491662 -140.106921)
			(xy 3.365774 -140.099001) (xy 3.240632 -140.083191) (xy 3.116729 -140.059556) (xy 2.994556 -140.028187)
			(xy 2.874593 -139.989209) (xy 2.757314 -139.942775) (xy 2.643182 -139.889068) (xy 2.532647 -139.828301)
			(xy 2.426147 -139.760714) (xy 2.3241 -139.686573) (xy 2.22691 -139.60617) (xy 2.13496 -139.519824)
			(xy 2.048614 -139.427874) (xy 1.968211 -139.330684) (xy 1.89407 -139.228637) (xy 1.826483 -139.122137)
			(xy 1.765716 -139.011602) (xy 1.712009 -138.89747) (xy 1.665575 -138.780191) (xy 1.626597 -138.660228)
			(xy 1.595228 -138.538055) (xy 1.571593 -138.414152) (xy 1.555783 -138.28901) (xy 1.547863 -138.163122)
			(xy 0.509016 -138.163122) (xy 0.509016 -140.26007) (xy 39.818317 -140.26007) (xy 39.822324 -140.144046)
			(xy 39.834326 -140.028574) (xy 39.854266 -139.914206) (xy 39.882049 -139.801486) (xy 39.917543 -139.690952)
			(xy 39.960578 -139.583129) (xy 40.010949 -139.478532) (xy 40.068416 -139.37766) (xy 40.132706 -139.280993)
			(xy 40.203511 -139.188992) (xy 40.280495 -139.102095) (xy 40.363291 -139.020716) (xy 40.451504 -138.945243)
			(xy 40.544714 -138.876036) (xy 40.642477 -138.813424) (xy 40.744326 -138.757707) (xy 40.849776 -138.709149)
			(xy 40.958325 -138.667981) (xy 41.069456 -138.634401) (xy 41.182639 -138.608568) (xy 41.297334 -138.590605)
			(xy 41.412996 -138.580597) (xy 41.529072 -138.578594) (xy 41.64501 -138.584603) (xy 41.760257 -138.598596)
			(xy 41.874263 -138.620507) (xy 41.986487 -138.650232) (xy 42.096393 -138.687628) (xy 42.203456 -138.732517)
			(xy 42.307168 -138.784686) (xy 42.407033 -138.843886) (xy 42.502576 -138.909835) (xy 42.593342 -138.982218)
			(xy 42.678897 -139.060691) (xy 42.758835 -139.144879) (xy 42.832774 -139.234381) (xy 42.900362 -139.328772)
			(xy 42.961276 -139.4276) (xy 43.015228 -139.530396) (xy 43.061958 -139.636669) (xy 43.101246 -139.745913)
			(xy 43.132903 -139.857606) (xy 43.156779 -139.971218) (xy 43.17276 -140.086206) (xy 43.180769 -140.202023)
			(xy 43.18127 -140.26007) (xy 43.180769 -140.318117) (xy 43.17276 -140.433934) (xy 43.156779 -140.548922)
			(xy 43.132903 -140.662534) (xy 43.101246 -140.774227) (xy 43.061958 -140.883471) (xy 43.015228 -140.989744)
			(xy 42.961276 -141.09254) (xy 42.900362 -141.191368) (xy 42.832774 -141.285759) (xy 42.758835 -141.375261)
			(xy 42.678897 -141.459449) (xy 42.593342 -141.537922) (xy 42.502858 -141.61008) (xy 93.15476 -141.61008)
			(xy 93.158776 -141.49381) (xy 93.170803 -141.378095) (xy 93.190785 -141.263485) (xy 93.218627 -141.150526)
			(xy 93.254196 -141.039758) (xy 93.297322 -140.931707) (xy 93.347799 -140.826889) (xy 93.405388 -140.725804)
			(xy 93.469814 -140.628932) (xy 93.540769 -140.536736) (xy 93.617916 -140.449655) (xy 93.700887 -140.368104)
			(xy 93.789287 -140.292472) (xy 93.882694 -140.223118) (xy 93.980663 -140.160375) (xy 94.082727 -140.104539)
			(xy 94.188401 -140.055878) (xy 94.29718 -140.014624) (xy 94.408545 -139.980973) (xy 94.521968 -139.955085)
			(xy 94.636905 -139.937084) (xy 94.752811 -139.927055) (xy 94.869133 -139.925047) (xy 94.985316 -139.931069)
			(xy 95.100807 -139.945092) (xy 95.215055 -139.96705) (xy 95.327516 -139.996837) (xy 95.437654 -140.034312)
			(xy 95.544944 -140.079297) (xy 95.648875 -140.131576) (xy 95.748951 -140.190901) (xy 95.844697 -140.256989)
			(xy 95.935654 -140.329525) (xy 96.02139 -140.408164) (xy 96.101497 -140.49253) (xy 96.175593 -140.582222)
			(xy 96.243323 -140.676812) (xy 96.304367 -140.77585) (xy 96.358432 -140.878863) (xy 96.405262 -140.98536)
			(xy 96.444633 -141.094835) (xy 96.476357 -141.206765) (xy 96.500283 -141.320617) (xy 96.516297 -141.435849)
			(xy 96.524324 -141.551911) (xy 96.524826 -141.61008) (xy 96.524324 -141.668249) (xy 96.516297 -141.784311)
			(xy 96.500283 -141.899543) (xy 96.476357 -142.013395) (xy 96.444633 -142.125325) (xy 96.405262 -142.2348)
			(xy 96.358432 -142.341297) (xy 96.304367 -142.44431) (xy 96.243323 -142.543348) (xy 96.175593 -142.637938)
			(xy 96.101497 -142.72763) (xy 96.02139 -142.811996) (xy 95.935654 -142.890635) (xy 95.844697 -142.963171)
			(xy 95.748951 -143.029259) (xy 95.648875 -143.088584) (xy 95.544944 -143.140863) (xy 95.437654 -143.185848)
			(xy 95.327516 -143.223323) (xy 95.215055 -143.25311) (xy 95.100807 -143.275068) (xy 94.985316 -143.289091)
			(xy 94.869133 -143.295113) (xy 94.752811 -143.293105) (xy 94.636905 -143.283076) (xy 94.521968 -143.265075)
			(xy 94.408545 -143.239187) (xy 94.29718 -143.205536) (xy 94.188401 -143.164282) (xy 94.082727 -143.115621)
			(xy 93.980663 -143.059785) (xy 93.882694 -142.997042) (xy 93.789287 -142.927688) (xy 93.700887 -142.852056)
			(xy 93.617916 -142.770505) (xy 93.540769 -142.683424) (xy 93.469814 -142.591228) (xy 93.405388 -142.494356)
			(xy 93.347799 -142.393271) (xy 93.297322 -142.288453) (xy 93.254196 -142.180402) (xy 93.218627 -142.069634)
			(xy 93.190785 -141.956675) (xy 93.170803 -141.842065) (xy 93.158776 -141.72635) (xy 93.15476 -141.61008)
			(xy 42.502858 -141.61008) (xy 42.502576 -141.610305) (xy 42.407033 -141.676254) (xy 42.307168 -141.735454)
			(xy 42.203456 -141.787623) (xy 42.096393 -141.832512) (xy 41.986487 -141.869908) (xy 41.874263 -141.899633)
			(xy 41.760257 -141.921544) (xy 41.64501 -141.935537) (xy 41.529072 -141.941546) (xy 41.412996 -141.939543)
			(xy 41.297334 -141.929535) (xy 41.182639 -141.911572) (xy 41.069456 -141.885739) (xy 40.958325 -141.852159)
			(xy 40.849776 -141.810991) (xy 40.744326 -141.762433) (xy 40.642477 -141.706716) (xy 40.544714 -141.644104)
			(xy 40.451504 -141.574897) (xy 40.363291 -141.499424) (xy 40.280495 -141.418045) (xy 40.203511 -141.331148)
			(xy 40.132706 -141.239147) (xy 40.068416 -141.14248) (xy 40.010949 -141.041608) (xy 39.960578 -140.937011)
			(xy 39.917543 -140.829188) (xy 39.882049 -140.718654) (xy 39.854266 -140.605934) (xy 39.834326 -140.491566)
			(xy 39.822324 -140.376094) (xy 39.818317 -140.26007) (xy 0.509016 -140.26007) (xy 0.509016 -153.359866)
			(xy 86.877404 -153.359866) (xy 86.881424 -153.169215) (xy 86.893478 -152.978902) (xy 86.913544 -152.789267)
			(xy 86.941587 -152.600646) (xy 86.977556 -152.413376) (xy 87.021388 -152.227788) (xy 87.073005 -152.044213)
			(xy 87.132315 -151.862977) (xy 87.199213 -151.684402) (xy 87.273579 -151.508807) (xy 87.355281 -151.336502)
			(xy 87.444175 -151.167795) (xy 87.540101 -151.002985) (xy 87.64289 -150.842366) (xy 87.752359 -150.686223)
			(xy 87.868313 -150.534834) (xy 87.990547 -150.388467) (xy 88.118841 -150.247383) (xy 88.252969 -150.111834)
			(xy 88.392693 -149.982059) (xy 88.537763 -149.858289) (xy 88.687921 -149.740746) (xy 88.842902 -149.629637)
			(xy 89.002429 -149.52516) (xy 89.166218 -149.427501) (xy 89.333978 -149.336834) (xy 89.505412 -149.25332)
			(xy 89.680214 -149.177107) (xy 89.858073 -149.108331) (xy 90.038674 -149.047113) (xy 90.221694 -148.993564)
			(xy 90.40681 -148.947778) (xy 90.593691 -148.909836) (xy 90.782006 -148.879807) (xy 90.971419 -148.857742)
			(xy 91.161593 -148.843683) (xy 91.352192 -148.837653) (xy 91.542875 -148.839663) (xy 91.733304 -148.84971)
			(xy 91.92314 -148.867776) (xy 92.112046 -148.893829) (xy 92.299685 -148.927822) (xy 92.485725 -148.969695)
			(xy 92.669834 -149.019374) (xy 92.851685 -149.07677) (xy 93.030955 -149.141781) (xy 93.207325 -149.214292)
			(xy 93.380481 -149.294173) (xy 93.550116 -149.381283) (xy 93.715928 -149.475467) (xy 93.877622 -149.576558)
			(xy 94.03491 -149.684374) (xy 94.187513 -149.798726) (xy 94.335161 -149.919409) (xy 94.477589 -150.04621)
			(xy 94.614545 -150.178901) (xy 94.745786 -150.317249) (xy 94.871078 -150.461006) (xy 94.990198 -150.609917)
			(xy 95.102934 -150.763718) (xy 95.209087 -150.922134) (xy 95.308467 -151.084885) (xy 95.400897 -151.25168)
			(xy 95.486214 -151.422224) (xy 95.564266 -151.596212) (xy 95.634913 -151.773337) (xy 95.698031 -151.953282)
			(xy 95.753507 -152.135728) (xy 95.801242 -152.320351) (xy 95.841152 -152.506821) (xy 95.873165 -152.694809)
			(xy 95.897225 -152.883979) (xy 95.913288 -153.073995) (xy 95.921327 -153.264519) (xy 95.92183 -153.359866)
			(xy 95.921327 -153.455213) (xy 95.913288 -153.645737) (xy 95.897225 -153.835753) (xy 95.873165 -154.024923)
			(xy 95.841152 -154.212911) (xy 95.801242 -154.399381) (xy 95.753507 -154.584004) (xy 95.698031 -154.76645)
			(xy 95.634913 -154.946395) (xy 95.564266 -155.12352) (xy 95.486214 -155.297508) (xy 95.400897 -155.468052)
			(xy 95.308467 -155.634847) (xy 95.209087 -155.797598) (xy 95.102934 -155.956014) (xy 94.990198 -156.109815)
			(xy 94.871078 -156.258726) (xy 94.745786 -156.402483) (xy 94.614545 -156.540831) (xy 94.477589 -156.673522)
			(xy 94.335161 -156.800323) (xy 94.187513 -156.921006) (xy 94.03491 -157.035358) (xy 93.877622 -157.143174)
			(xy 93.715928 -157.244265) (xy 93.550116 -157.338449) (xy 93.380481 -157.425559) (xy 93.207325 -157.50544)
			(xy 93.030955 -157.577951) (xy 92.851685 -157.642962) (xy 92.669834 -157.700358) (xy 92.485725 -157.750037)
			(xy 92.299685 -157.79191) (xy 92.112046 -157.825903) (xy 91.92314 -157.851956) (xy 91.733304 -157.870022)
			(xy 91.542875 -157.880069) (xy 91.352192 -157.882079) (xy 91.161593 -157.876049) (xy 90.971419 -157.86199)
			(xy 90.782006 -157.839925) (xy 90.593691 -157.809896) (xy 90.40681 -157.771954) (xy 90.221694 -157.726168)
			(xy 90.038674 -157.672619) (xy 89.858073 -157.611401) (xy 89.680214 -157.542625) (xy 89.505412 -157.466412)
			(xy 89.333978 -157.382898) (xy 89.166218 -157.292231) (xy 89.002429 -157.194572) (xy 88.842902 -157.090095)
			(xy 88.687921 -156.978986) (xy 88.537763 -156.861443) (xy 88.392693 -156.737673) (xy 88.252969 -156.607898)
			(xy 88.118841 -156.472349) (xy 87.990547 -156.331265) (xy 87.868313 -156.184898) (xy 87.752359 -156.033509)
			(xy 87.64289 -155.877366) (xy 87.540101 -155.716747) (xy 87.444175 -155.551937) (xy 87.355281 -155.38323)
			(xy 87.273579 -155.210925) (xy 87.199213 -155.03533) (xy 87.132315 -154.856755) (xy 87.073005 -154.675519)
			(xy 87.021388 -154.491944) (xy 86.977556 -154.306356) (xy 86.941587 -154.119086) (xy 86.913544 -153.930465)
			(xy 86.893478 -153.74083) (xy 86.881424 -153.550517) (xy 86.877404 -153.359866) (xy 0.509016 -153.359866)
			(xy 0.509016 -184.71007) (xy 39.818317 -184.71007) (xy 39.822324 -184.594046) (xy 39.834326 -184.478574)
			(xy 39.854266 -184.364206) (xy 39.882049 -184.251486) (xy 39.917543 -184.140952) (xy 39.960578 -184.033129)
			(xy 40.010949 -183.928532) (xy 40.068416 -183.82766) (xy 40.132706 -183.730993) (xy 40.203511 -183.638992)
			(xy 40.280495 -183.552095) (xy 40.363291 -183.470716) (xy 40.451504 -183.395243) (xy 40.544714 -183.326036)
			(xy 40.642477 -183.263424) (xy 40.744326 -183.207707) (xy 40.849776 -183.159149) (xy 40.958325 -183.117981)
			(xy 41.069456 -183.084401) (xy 41.182639 -183.058568) (xy 41.297334 -183.040605) (xy 41.412996 -183.030597)
			(xy 41.529072 -183.028594) (xy 41.64501 -183.034603) (xy 41.760257 -183.048596) (xy 41.874263 -183.070507)
			(xy 41.986487 -183.100232) (xy 42.096393 -183.137628) (xy 42.203456 -183.182517) (xy 42.307168 -183.234686)
			(xy 42.407033 -183.293886) (xy 42.502576 -183.359835) (xy 42.593342 -183.432218) (xy 42.678897 -183.510691)
			(xy 42.758835 -183.594879) (xy 42.832774 -183.684381) (xy 42.900362 -183.778772) (xy 42.961276 -183.8776)
			(xy 43.015228 -183.980396) (xy 43.061958 -184.086669) (xy 43.101246 -184.195913) (xy 43.132903 -184.307606)
			(xy 43.156779 -184.421218) (xy 43.17276 -184.536206) (xy 43.180769 -184.652023) (xy 43.18127 -184.71007)
			(xy 43.180769 -184.768117) (xy 43.17276 -184.883934) (xy 43.156779 -184.998922) (xy 43.132903 -185.112534)
			(xy 43.101246 -185.224227) (xy 43.061958 -185.333471) (xy 43.015228 -185.439744) (xy 42.961276 -185.54254)
			(xy 42.900362 -185.641368) (xy 42.832774 -185.735759) (xy 42.758835 -185.825261) (xy 42.678897 -185.909449)
			(xy 42.593342 -185.987922) (xy 42.502858 -186.06008) (xy 93.15476 -186.06008) (xy 93.158776 -185.94381)
			(xy 93.170803 -185.828095) (xy 93.190785 -185.713485) (xy 93.218627 -185.600526) (xy 93.254196 -185.489758)
			(xy 93.297322 -185.381707) (xy 93.347799 -185.276889) (xy 93.405388 -185.175804) (xy 93.469814 -185.078932)
			(xy 93.540769 -184.986736) (xy 93.617916 -184.899655) (xy 93.700887 -184.818104) (xy 93.789287 -184.742472)
			(xy 93.882694 -184.673118) (xy 93.980663 -184.610375) (xy 94.082727 -184.554539) (xy 94.188401 -184.505878)
			(xy 94.29718 -184.464624) (xy 94.408545 -184.430973) (xy 94.521968 -184.405085) (xy 94.636905 -184.387084)
			(xy 94.752811 -184.377055) (xy 94.869133 -184.375047) (xy 94.985316 -184.381069) (xy 95.100807 -184.395092)
			(xy 95.215055 -184.41705) (xy 95.327516 -184.446837) (xy 95.437654 -184.484312) (xy 95.544944 -184.529297)
			(xy 95.648875 -184.581576) (xy 95.748951 -184.640901) (xy 95.844697 -184.706989) (xy 95.935654 -184.779525)
			(xy 96.02139 -184.858164) (xy 96.101497 -184.94253) (xy 96.175593 -185.032222) (xy 96.243323 -185.126812)
			(xy 96.304367 -185.22585) (xy 96.358432 -185.328863) (xy 96.405262 -185.43536) (xy 96.444633 -185.544835)
			(xy 96.476357 -185.656765) (xy 96.500283 -185.770617) (xy 96.516297 -185.885849) (xy 96.524324 -186.001911)
			(xy 96.524826 -186.06008) (xy 96.524324 -186.118249) (xy 96.516297 -186.234311) (xy 96.500283 -186.349543)
			(xy 96.476357 -186.463395) (xy 96.444633 -186.575325) (xy 96.405262 -186.6848) (xy 96.358432 -186.791297)
			(xy 96.304367 -186.89431) (xy 96.243323 -186.993348) (xy 96.175593 -187.087938) (xy 96.101497 -187.17763)
			(xy 96.02139 -187.261996) (xy 95.935654 -187.340635) (xy 95.844697 -187.413171) (xy 95.748951 -187.479259)
			(xy 95.648875 -187.538584) (xy 95.544944 -187.590863) (xy 95.437654 -187.635848) (xy 95.327516 -187.673323)
			(xy 95.215055 -187.70311) (xy 95.100807 -187.725068) (xy 94.985316 -187.739091) (xy 94.869133 -187.745113)
			(xy 94.752811 -187.743105) (xy 94.636905 -187.733076) (xy 94.521968 -187.715075) (xy 94.408545 -187.689187)
			(xy 94.29718 -187.655536) (xy 94.188401 -187.614282) (xy 94.082727 -187.565621) (xy 93.980663 -187.509785)
			(xy 93.882694 -187.447042) (xy 93.789287 -187.377688) (xy 93.700887 -187.302056) (xy 93.617916 -187.220505)
			(xy 93.540769 -187.133424) (xy 93.469814 -187.041228) (xy 93.405388 -186.944356) (xy 93.347799 -186.843271)
			(xy 93.297322 -186.738453) (xy 93.254196 -186.630402) (xy 93.218627 -186.519634) (xy 93.190785 -186.406675)
			(xy 93.170803 -186.292065) (xy 93.158776 -186.17635) (xy 93.15476 -186.06008) (xy 42.502858 -186.06008)
			(xy 42.502576 -186.060305) (xy 42.407033 -186.126254) (xy 42.307168 -186.185454) (xy 42.203456 -186.237623)
			(xy 42.096393 -186.282512) (xy 41.986487 -186.319908) (xy 41.874263 -186.349633) (xy 41.760257 -186.371544)
			(xy 41.64501 -186.385537) (xy 41.529072 -186.391546) (xy 41.412996 -186.389543) (xy 41.297334 -186.379535)
			(xy 41.182639 -186.361572) (xy 41.069456 -186.335739) (xy 40.958325 -186.302159) (xy 40.849776 -186.260991)
			(xy 40.744326 -186.212433) (xy 40.642477 -186.156716) (xy 40.544714 -186.094104) (xy 40.451504 -186.024897)
			(xy 40.363291 -185.949424) (xy 40.280495 -185.868045) (xy 40.203511 -185.781148) (xy 40.132706 -185.689147)
			(xy 40.068416 -185.59248) (xy 40.010949 -185.491608) (xy 39.960578 -185.387011) (xy 39.917543 -185.279188)
			(xy 39.882049 -185.168654) (xy 39.854266 -185.055934) (xy 39.834326 -184.941566) (xy 39.822324 -184.826094)
			(xy 39.818317 -184.71007) (xy 0.509016 -184.71007) (xy 0.509016 -197.81012) (xy 86.877404 -197.81012)
			(xy 86.881424 -197.619469) (xy 86.893478 -197.429156) (xy 86.913544 -197.239521) (xy 86.941587 -197.0509)
			(xy 86.977556 -196.86363) (xy 87.021388 -196.678042) (xy 87.073005 -196.494467) (xy 87.132315 -196.313231)
			(xy 87.199213 -196.134656) (xy 87.273579 -195.959061) (xy 87.355281 -195.786756) (xy 87.444175 -195.618049)
			(xy 87.540101 -195.453239) (xy 87.64289 -195.29262) (xy 87.752359 -195.136477) (xy 87.868313 -194.985088)
			(xy 87.990547 -194.838721) (xy 88.118841 -194.697637) (xy 88.252969 -194.562088) (xy 88.392693 -194.432313)
			(xy 88.537763 -194.308543) (xy 88.687921 -194.191) (xy 88.842902 -194.079891) (xy 89.002429 -193.975414)
			(xy 89.166218 -193.877755) (xy 89.333978 -193.787088) (xy 89.505412 -193.703574) (xy 89.680214 -193.627361)
			(xy 89.858073 -193.558585) (xy 90.038674 -193.497367) (xy 90.221694 -193.443818) (xy 90.40681 -193.398032)
			(xy 90.593691 -193.36009) (xy 90.782006 -193.330061) (xy 90.971419 -193.307996) (xy 91.161593 -193.293937)
			(xy 91.352192 -193.287907) (xy 91.542875 -193.289917) (xy 91.733304 -193.299964) (xy 91.92314 -193.31803)
			(xy 92.112046 -193.344083) (xy 92.299685 -193.378076) (xy 92.485725 -193.419949) (xy 92.669834 -193.469628)
			(xy 92.851685 -193.527024) (xy 93.030955 -193.592035) (xy 93.207325 -193.664546) (xy 93.380481 -193.744427)
			(xy 93.550116 -193.831537) (xy 93.715928 -193.925721) (xy 93.877622 -194.026812) (xy 94.03491 -194.134628)
			(xy 94.187513 -194.24898) (xy 94.335161 -194.369663) (xy 94.477589 -194.496464) (xy 94.614545 -194.629155)
			(xy 94.745786 -194.767503) (xy 94.871078 -194.91126) (xy 94.990198 -195.060171) (xy 95.102934 -195.213972)
			(xy 95.209087 -195.372388) (xy 95.308467 -195.535139) (xy 95.400897 -195.701934) (xy 95.486214 -195.872478)
			(xy 95.564266 -196.046466) (xy 95.634913 -196.223591) (xy 95.698031 -196.403536) (xy 95.753507 -196.585982)
			(xy 95.801242 -196.770605) (xy 95.841152 -196.957075) (xy 95.873165 -197.145063) (xy 95.897225 -197.334233)
			(xy 95.913288 -197.524249) (xy 95.921327 -197.714773) (xy 95.92183 -197.81012) (xy 95.921327 -197.905467)
			(xy 95.913288 -198.095991) (xy 95.897225 -198.286007) (xy 95.873165 -198.475177) (xy 95.841152 -198.663165)
			(xy 95.801242 -198.849635) (xy 95.753507 -199.034258) (xy 95.698031 -199.216704) (xy 95.634913 -199.396649)
			(xy 95.564266 -199.573774) (xy 95.486214 -199.747762) (xy 95.400897 -199.918306) (xy 95.308467 -200.085101)
			(xy 95.209087 -200.247852) (xy 95.102934 -200.406268) (xy 94.990198 -200.560069) (xy 94.871078 -200.70898)
			(xy 94.745786 -200.852737) (xy 94.614545 -200.991085) (xy 94.477589 -201.123776) (xy 94.335161 -201.250577)
			(xy 94.187513 -201.37126) (xy 94.03491 -201.485612) (xy 93.877622 -201.593428) (xy 93.715928 -201.694519)
			(xy 93.550116 -201.788703) (xy 93.380481 -201.875813) (xy 93.207325 -201.955694) (xy 93.030955 -202.028205)
			(xy 92.851685 -202.093216) (xy 92.669834 -202.150612) (xy 92.485725 -202.200291) (xy 92.299685 -202.242164)
			(xy 92.112046 -202.276157) (xy 91.92314 -202.30221) (xy 91.733304 -202.320276) (xy 91.542875 -202.330323)
			(xy 91.352192 -202.332333) (xy 91.161593 -202.326303) (xy 90.971419 -202.312244) (xy 90.782006 -202.290179)
			(xy 90.593691 -202.26015) (xy 90.40681 -202.222208) (xy 90.221694 -202.176422) (xy 90.038674 -202.122873)
			(xy 89.858073 -202.061655) (xy 89.680214 -201.992879) (xy 89.505412 -201.916666) (xy 89.333978 -201.833152)
			(xy 89.166218 -201.742485) (xy 89.002429 -201.644826) (xy 88.842902 -201.540349) (xy 88.687921 -201.42924)
			(xy 88.537763 -201.311697) (xy 88.392693 -201.187927) (xy 88.252969 -201.058152) (xy 88.118841 -200.922603)
			(xy 87.990547 -200.781519) (xy 87.868313 -200.635152) (xy 87.752359 -200.483763) (xy 87.64289 -200.32762)
			(xy 87.540101 -200.167001) (xy 87.444175 -200.002191) (xy 87.355281 -199.833484) (xy 87.273579 -199.661179)
			(xy 87.199213 -199.485584) (xy 87.132315 -199.307009) (xy 87.073005 -199.125773) (xy 87.021388 -198.942198)
			(xy 86.977556 -198.75661) (xy 86.941587 -198.56934) (xy 86.913544 -198.380719) (xy 86.893478 -198.191084)
			(xy 86.881424 -198.000771) (xy 86.877404 -197.81012) (xy 0.509016 -197.81012) (xy 0.509016 -206.99984)
			(xy 14.086591 -206.99984) (xy 14.090616 -206.857648) (xy 14.102679 -206.715912) (xy 14.122742 -206.575086)
			(xy 14.15074 -206.43562) (xy 14.186584 -206.297961) (xy 14.230158 -206.162551) (xy 14.281323 -206.029823)
			(xy 14.339916 -205.900202) (xy 14.405747 -205.774104) (xy 14.478608 -205.651932) (xy 14.558263 -205.534078)
			(xy 14.644459 -205.420919) (xy 14.736918 -205.312817) (xy 14.835346 -205.21012) (xy 14.939425 -205.113156)
			(xy 15.048824 -205.022236) (xy 15.163192 -204.93765) (xy 15.282161 -204.85967) (xy 15.405352 -204.788546)
			(xy 15.532369 -204.724505) (xy 15.662806 -204.667753) (xy 15.796245 -204.618471) (xy 15.932258 -204.576817)
			(xy 16.07041 -204.542925) (xy 16.210259 -204.516904) (xy 16.351355 -204.498836) (xy 16.493247 -204.488779)
			(xy 16.635482 -204.486766) (xy 16.777602 -204.492803) (xy 16.919153 -204.506871) (xy 17.059682 -204.528925)
			(xy 17.198737 -204.558894) (xy 17.335875 -204.596682) (xy 17.470655 -204.642168) (xy 17.602646 -204.695206)
			(xy 17.731425 -204.755627) (xy 17.856579 -204.823236) (xy 17.977707 -204.897818) (xy 18.094423 -204.979134)
			(xy 18.206351 -205.066922) (xy 18.313133 -205.160902) (xy 18.414427 -205.260772) (xy 18.509908 -205.366214)
			(xy 18.599272 -205.476888) (xy 18.68223 -205.592441) (xy 18.758519 -205.712502) (xy 18.827893 -205.836687)
			(xy 18.89013 -205.964598) (xy 18.945031 -206.095825) (xy 18.992419 -206.229948) (xy 19.032144 -206.366537)
			(xy 19.064077 -206.505155) (xy 19.088118 -206.645357) (xy 19.104187 -206.786695) (xy 19.112235 -206.928716)
			(xy 19.112738 -206.99984) (xy 19.112235 -207.070964) (xy 19.104187 -207.212985) (xy 19.088118 -207.354323)
			(xy 19.064077 -207.494525) (xy 19.032144 -207.633143) (xy 18.992419 -207.769732) (xy 18.945031 -207.903855)
			(xy 18.89013 -208.035082) (xy 18.827893 -208.162993) (xy 18.758519 -208.287178) (xy 18.68223 -208.407239)
			(xy 18.599272 -208.522792) (xy 18.509908 -208.633466) (xy 18.414427 -208.738908) (xy 18.313133 -208.838778)
			(xy 18.206351 -208.932758) (xy 18.094423 -209.020546) (xy 17.977707 -209.101862) (xy 17.856579 -209.176444)
			(xy 17.731425 -209.244053) (xy 17.602646 -209.304474) (xy 17.470655 -209.357512) (xy 17.335875 -209.402998)
			(xy 17.198737 -209.440786) (xy 17.059682 -209.470755) (xy 16.919153 -209.492809) (xy 16.777602 -209.506877)
			(xy 16.635482 -209.512914) (xy 16.493247 -209.510901) (xy 16.351355 -209.500844) (xy 16.210259 -209.482776)
			(xy 16.07041 -209.456755) (xy 15.932258 -209.422863) (xy 15.796245 -209.381209) (xy 15.662806 -209.331927)
			(xy 15.532369 -209.275175) (xy 15.405352 -209.211134) (xy 15.282161 -209.14001) (xy 15.163192 -209.06203)
			(xy 15.048824 -208.977444) (xy 14.939425 -208.886524) (xy 14.835346 -208.78956) (xy 14.736918 -208.686863)
			(xy 14.644459 -208.578761) (xy 14.558263 -208.465602) (xy 14.478608 -208.347748) (xy 14.405747 -208.225576)
			(xy 14.339916 -208.099478) (xy 14.281323 -207.969857) (xy 14.230158 -207.837129) (xy 14.186584 -207.701719)
			(xy 14.15074 -207.56406) (xy 14.122742 -207.424594) (xy 14.102679 -207.283768) (xy 14.090616 -207.142032)
			(xy 14.086591 -206.99984) (xy 0.509016 -206.99984) (xy 0.509016 -210.09991) (xy 75.486519 -210.09991)
			(xy 75.490544 -209.957718) (xy 75.502607 -209.815982) (xy 75.52267 -209.675156) (xy 75.550668 -209.53569)
			(xy 75.586512 -209.398031) (xy 75.630086 -209.262621) (xy 75.681251 -209.129893) (xy 75.739844 -209.000272)
			(xy 75.805675 -208.874174) (xy 75.878536 -208.752002) (xy 75.958191 -208.634148) (xy 76.044387 -208.520989)
			(xy 76.136846 -208.412887) (xy 76.235274 -208.31019) (xy 76.339353 -208.213226) (xy 76.448752 -208.122306)
			(xy 76.56312 -208.03772) (xy 76.682089 -207.95974) (xy 76.80528 -207.888616) (xy 76.932297 -207.824575)
			(xy 77.062734 -207.767823) (xy 77.196173 -207.718541) (xy 77.332186 -207.676887) (xy 77.470338 -207.642995)
			(xy 77.610187 -207.616974) (xy 77.751283 -207.598906) (xy 77.893175 -207.588849) (xy 78.03541 -207.586836)
			(xy 78.17753 -207.592873) (xy 78.319081 -207.606941) (xy 78.45961 -207.628995) (xy 78.598665 -207.658964)
			(xy 78.735803 -207.696752) (xy 78.870583 -207.742238) (xy 79.002574 -207.795276) (xy 79.131353 -207.855697)
			(xy 79.256507 -207.923306) (xy 79.377635 -207.997888) (xy 79.494351 -208.079204) (xy 79.606279 -208.166992)
			(xy 79.713061 -208.260972) (xy 79.814355 -208.360842) (xy 79.909836 -208.466284) (xy 79.9992 -208.576958)
			(xy 80.082158 -208.692511) (xy 80.158447 -208.812572) (xy 80.227821 -208.936757) (xy 80.290058 -209.064668)
			(xy 80.344959 -209.195895) (xy 80.392347 -209.330018) (xy 80.432072 -209.466607) (xy 80.464005 -209.605225)
			(xy 80.488046 -209.745427) (xy 80.504115 -209.886765) (xy 80.512163 -210.028786) (xy 80.512666 -210.09991)
			(xy 80.512163 -210.171034) (xy 80.504115 -210.313055) (xy 80.488046 -210.454393) (xy 80.464005 -210.594595)
			(xy 80.432072 -210.733213) (xy 80.392347 -210.869802) (xy 80.344959 -211.003925) (xy 80.290058 -211.135152)
			(xy 80.227821 -211.263063) (xy 80.158447 -211.387248) (xy 80.082158 -211.507309) (xy 79.9992 -211.622862)
			(xy 79.909836 -211.733536) (xy 79.814355 -211.838978) (xy 79.713061 -211.938848) (xy 79.606279 -212.032828)
			(xy 79.494351 -212.120616) (xy 79.377635 -212.201932) (xy 79.256507 -212.276514) (xy 79.131353 -212.344123)
			(xy 79.002574 -212.404544) (xy 78.870583 -212.457582) (xy 78.735803 -212.503068) (xy 78.598665 -212.540856)
			(xy 78.45961 -212.570825) (xy 78.319081 -212.592879) (xy 78.17753 -212.606947) (xy 78.03541 -212.612984)
			(xy 77.893175 -212.610971) (xy 77.751283 -212.600914) (xy 77.610187 -212.582846) (xy 77.470338 -212.556825)
			(xy 77.332186 -212.522933) (xy 77.196173 -212.481279) (xy 77.062734 -212.431997) (xy 76.932297 -212.375245)
			(xy 76.80528 -212.311204) (xy 76.682089 -212.24008) (xy 76.56312 -212.1621) (xy 76.448752 -212.077514)
			(xy 76.339353 -211.986594) (xy 76.235274 -211.88963) (xy 76.136846 -211.786933) (xy 76.044387 -211.678831)
			(xy 75.958191 -211.565672) (xy 75.878536 -211.447818) (xy 75.805675 -211.325646) (xy 75.739844 -211.199548)
			(xy 75.681251 -211.069927) (xy 75.630086 -210.937199) (xy 75.586512 -210.801789) (xy 75.550668 -210.66413)
			(xy 75.52267 -210.524664) (xy 75.502607 -210.383838) (xy 75.490544 -210.242102) (xy 75.486519 -210.09991)
			(xy 0.509016 -210.09991) (xy 0.509016 -229.16007) (xy 39.818063 -229.16007) (xy 39.82207 -229.044046)
			(xy 39.834072 -228.928574) (xy 39.854012 -228.814206) (xy 39.881795 -228.701486) (xy 39.917289 -228.590952)
			(xy 39.960324 -228.483129) (xy 40.010695 -228.378532) (xy 40.068162 -228.27766) (xy 40.132452 -228.180993)
			(xy 40.203257 -228.088992) (xy 40.280241 -228.002095) (xy 40.363037 -227.920716) (xy 40.45125 -227.845243)
			(xy 40.54446 -227.776036) (xy 40.642223 -227.713424) (xy 40.744072 -227.657707) (xy 40.849522 -227.609149)
			(xy 40.958071 -227.567981) (xy 41.069202 -227.534401) (xy 41.182385 -227.508568) (xy 41.29708 -227.490605)
			(xy 41.412742 -227.480597) (xy 41.528818 -227.478594) (xy 41.644756 -227.484603) (xy 41.760003 -227.498596)
			(xy 41.874009 -227.520507) (xy 41.986233 -227.550232) (xy 42.096139 -227.587628) (xy 42.203202 -227.632517)
			(xy 42.306914 -227.684686) (xy 42.406779 -227.743886) (xy 42.502322 -227.809835) (xy 42.593088 -227.882218)
			(xy 42.678643 -227.960691) (xy 42.758581 -228.044879) (xy 42.83252 -228.134381) (xy 42.900108 -228.228772)
			(xy 42.961022 -228.3276) (xy 43.014974 -228.430396) (xy 43.061704 -228.536669) (xy 43.100992 -228.645913)
			(xy 43.132649 -228.757606) (xy 43.156525 -228.871218) (xy 43.172506 -228.986206) (xy 43.180515 -229.102023)
			(xy 43.181016 -229.16007) (xy 43.180515 -229.218117) (xy 43.172506 -229.333934) (xy 43.156525 -229.448922)
			(xy 43.132649 -229.562534) (xy 43.100992 -229.674227) (xy 43.061704 -229.783471) (xy 43.014974 -229.889744)
			(xy 42.961022 -229.99254) (xy 42.900108 -230.091368) (xy 42.83252 -230.185759) (xy 42.758581 -230.275261)
			(xy 42.678643 -230.359449) (xy 42.593088 -230.437922) (xy 42.502604 -230.51008) (xy 93.154506 -230.51008)
			(xy 93.158522 -230.39381) (xy 93.170549 -230.278095) (xy 93.190531 -230.163485) (xy 93.218373 -230.050526)
			(xy 93.253942 -229.939758) (xy 93.297068 -229.831707) (xy 93.347545 -229.726889) (xy 93.405134 -229.625804)
			(xy 93.46956 -229.528932) (xy 93.540515 -229.436736) (xy 93.617662 -229.349655) (xy 93.700633 -229.268104)
			(xy 93.789033 -229.192472) (xy 93.88244 -229.123118) (xy 93.980409 -229.060375) (xy 94.082473 -229.004539)
			(xy 94.188147 -228.955878) (xy 94.296926 -228.914624) (xy 94.408291 -228.880973) (xy 94.521714 -228.855085)
			(xy 94.636651 -228.837084) (xy 94.752557 -228.827055) (xy 94.868879 -228.825047) (xy 94.985062 -228.831069)
			(xy 95.100553 -228.845092) (xy 95.214801 -228.86705) (xy 95.327262 -228.896837) (xy 95.4374 -228.934312)
			(xy 95.54469 -228.979297) (xy 95.648621 -229.031576) (xy 95.748697 -229.090901) (xy 95.844443 -229.156989)
			(xy 95.9354 -229.229525) (xy 96.021136 -229.308164) (xy 96.101243 -229.39253) (xy 96.175339 -229.482222)
			(xy 96.243069 -229.576812) (xy 96.304113 -229.67585) (xy 96.358178 -229.778863) (xy 96.405008 -229.88536)
			(xy 96.444379 -229.994835) (xy 96.476103 -230.106765) (xy 96.500029 -230.220617) (xy 96.516043 -230.335849)
			(xy 96.52407 -230.451911) (xy 96.524572 -230.51008) (xy 96.52407 -230.568249) (xy 96.516043 -230.684311)
			(xy 96.500029 -230.799543) (xy 96.476103 -230.913395) (xy 96.444379 -231.025325) (xy 96.405008 -231.1348)
			(xy 96.358178 -231.241297) (xy 96.304113 -231.34431) (xy 96.243069 -231.443348) (xy 96.175339 -231.537938)
			(xy 96.101243 -231.62763) (xy 96.021136 -231.711996) (xy 95.9354 -231.790635) (xy 95.844443 -231.863171)
			(xy 95.748697 -231.929259) (xy 95.648621 -231.988584) (xy 95.54469 -232.040863) (xy 95.4374 -232.085848)
			(xy 95.327262 -232.123323) (xy 95.214801 -232.15311) (xy 95.100553 -232.175068) (xy 94.985062 -232.189091)
			(xy 94.868879 -232.195113) (xy 94.752557 -232.193105) (xy 94.636651 -232.183076) (xy 94.521714 -232.165075)
			(xy 94.408291 -232.139187) (xy 94.296926 -232.105536) (xy 94.188147 -232.064282) (xy 94.082473 -232.015621)
			(xy 93.980409 -231.959785) (xy 93.88244 -231.897042) (xy 93.789033 -231.827688) (xy 93.700633 -231.752056)
			(xy 93.617662 -231.670505) (xy 93.540515 -231.583424) (xy 93.46956 -231.491228) (xy 93.405134 -231.394356)
			(xy 93.347545 -231.293271) (xy 93.297068 -231.188453) (xy 93.253942 -231.080402) (xy 93.218373 -230.969634)
			(xy 93.190531 -230.856675) (xy 93.170549 -230.742065) (xy 93.158522 -230.62635) (xy 93.154506 -230.51008)
			(xy 42.502604 -230.51008) (xy 42.502322 -230.510305) (xy 42.406779 -230.576254) (xy 42.306914 -230.635454)
			(xy 42.203202 -230.687623) (xy 42.096139 -230.732512) (xy 41.986233 -230.769908) (xy 41.874009 -230.799633)
			(xy 41.760003 -230.821544) (xy 41.644756 -230.835537) (xy 41.528818 -230.841546) (xy 41.412742 -230.839543)
			(xy 41.29708 -230.829535) (xy 41.182385 -230.811572) (xy 41.069202 -230.785739) (xy 40.958071 -230.752159)
			(xy 40.849522 -230.710991) (xy 40.744072 -230.662433) (xy 40.642223 -230.606716) (xy 40.54446 -230.544104)
			(xy 40.45125 -230.474897) (xy 40.363037 -230.399424) (xy 40.280241 -230.318045) (xy 40.203257 -230.231148)
			(xy 40.132452 -230.139147) (xy 40.068162 -230.04248) (xy 40.010695 -229.941608) (xy 39.960324 -229.837011)
			(xy 39.917289 -229.729188) (xy 39.881795 -229.618654) (xy 39.854012 -229.505934) (xy 39.834072 -229.391566)
			(xy 39.82207 -229.276094) (xy 39.818063 -229.16007) (xy 0.509016 -229.16007) (xy 0.509016 -242.26012)
			(xy 86.877404 -242.26012) (xy 86.881424 -242.069469) (xy 86.893478 -241.879156) (xy 86.913544 -241.689521)
			(xy 86.941587 -241.5009) (xy 86.977556 -241.31363) (xy 87.021388 -241.128042) (xy 87.073005 -240.944467)
			(xy 87.132315 -240.763231) (xy 87.199213 -240.584656) (xy 87.273579 -240.409061) (xy 87.355281 -240.236756)
			(xy 87.444175 -240.068049) (xy 87.540101 -239.903239) (xy 87.64289 -239.74262) (xy 87.752359 -239.586477)
			(xy 87.868313 -239.435088) (xy 87.990547 -239.288721) (xy 88.118841 -239.147637) (xy 88.252969 -239.012088)
			(xy 88.392693 -238.882313) (xy 88.537763 -238.758543) (xy 88.687921 -238.641) (xy 88.842902 -238.529891)
			(xy 89.002429 -238.425414) (xy 89.166218 -238.327755) (xy 89.333978 -238.237088) (xy 89.505412 -238.153574)
			(xy 89.680214 -238.077361) (xy 89.858073 -238.008585) (xy 90.038674 -237.947367) (xy 90.221694 -237.893818)
			(xy 90.40681 -237.848032) (xy 90.593691 -237.81009) (xy 90.782006 -237.780061) (xy 90.971419 -237.757996)
			(xy 91.161593 -237.743937) (xy 91.352192 -237.737907) (xy 91.542875 -237.739917) (xy 91.733304 -237.749964)
			(xy 91.92314 -237.76803) (xy 92.112046 -237.794083) (xy 92.299685 -237.828076) (xy 92.485725 -237.869949)
			(xy 92.669834 -237.919628) (xy 92.851685 -237.977024) (xy 93.030955 -238.042035) (xy 93.207325 -238.114546)
			(xy 93.380481 -238.194427) (xy 93.550116 -238.281537) (xy 93.715928 -238.375721) (xy 93.877622 -238.476812)
			(xy 94.03491 -238.584628) (xy 94.187513 -238.69898) (xy 94.335161 -238.819663) (xy 94.477589 -238.946464)
			(xy 94.614545 -239.079155) (xy 94.745786 -239.217503) (xy 94.871078 -239.36126) (xy 94.990198 -239.510171)
			(xy 95.102934 -239.663972) (xy 95.209087 -239.822388) (xy 95.308467 -239.985139) (xy 95.400897 -240.151934)
			(xy 95.486214 -240.322478) (xy 95.564266 -240.496466) (xy 95.634913 -240.673591) (xy 95.698031 -240.853536)
			(xy 95.753507 -241.035982) (xy 95.801242 -241.220605) (xy 95.841152 -241.407075) (xy 95.873165 -241.595063)
			(xy 95.897225 -241.784233) (xy 95.913288 -241.974249) (xy 95.921327 -242.164773) (xy 95.92183 -242.26012)
			(xy 95.921327 -242.355467) (xy 95.913288 -242.545991) (xy 95.897225 -242.736007) (xy 95.873165 -242.925177)
			(xy 95.841152 -243.113165) (xy 95.801242 -243.299635) (xy 95.753507 -243.484258) (xy 95.698031 -243.666704)
			(xy 95.634913 -243.846649) (xy 95.564266 -244.023774) (xy 95.486214 -244.197762) (xy 95.400897 -244.368306)
			(xy 95.308467 -244.535101) (xy 95.209087 -244.697852) (xy 95.102934 -244.856268) (xy 94.990198 -245.010069)
			(xy 94.871078 -245.15898) (xy 94.745786 -245.302737) (xy 94.614545 -245.441085) (xy 94.477589 -245.573776)
			(xy 94.335161 -245.700577) (xy 94.187513 -245.82126) (xy 94.03491 -245.935612) (xy 93.877622 -246.043428)
			(xy 93.715928 -246.144519) (xy 93.550116 -246.238703) (xy 93.380481 -246.325813) (xy 93.207325 -246.405694)
			(xy 93.030955 -246.478205) (xy 92.851685 -246.543216) (xy 92.669834 -246.600612) (xy 92.485725 -246.650291)
			(xy 92.299685 -246.692164) (xy 92.112046 -246.726157) (xy 91.92314 -246.75221) (xy 91.733304 -246.770276)
			(xy 91.542875 -246.780323) (xy 91.352192 -246.782333) (xy 91.161593 -246.776303) (xy 90.971419 -246.762244)
			(xy 90.782006 -246.740179) (xy 90.593691 -246.71015) (xy 90.40681 -246.672208) (xy 90.221694 -246.626422)
			(xy 90.038674 -246.572873) (xy 89.858073 -246.511655) (xy 89.680214 -246.442879) (xy 89.505412 -246.366666)
			(xy 89.333978 -246.283152) (xy 89.166218 -246.192485) (xy 89.002429 -246.094826) (xy 88.842902 -245.990349)
			(xy 88.687921 -245.87924) (xy 88.537763 -245.761697) (xy 88.392693 -245.637927) (xy 88.252969 -245.508152)
			(xy 88.118841 -245.372603) (xy 87.990547 -245.231519) (xy 87.868313 -245.085152) (xy 87.752359 -244.933763)
			(xy 87.64289 -244.77762) (xy 87.540101 -244.617001) (xy 87.444175 -244.452191) (xy 87.355281 -244.283484)
			(xy 87.273579 -244.111179) (xy 87.199213 -243.935584) (xy 87.132315 -243.757009) (xy 87.073005 -243.575773)
			(xy 87.021388 -243.392198) (xy 86.977556 -243.20661) (xy 86.941587 -243.01934) (xy 86.913544 -242.830719)
			(xy 86.893478 -242.641084) (xy 86.881424 -242.450771) (xy 86.877404 -242.26012) (xy 0.509016 -242.26012)
			(xy 0.509016 -250.020582) (xy 3.582162 -250.020582) (xy 3.582659 -249.96334) (xy 3.590757 -249.849142)
			(xy 3.606915 -249.735803) (xy 3.631052 -249.623892) (xy 3.663046 -249.513969) (xy 3.702737 -249.406585)
			(xy 3.749927 -249.302279) (xy 3.804379 -249.201573) (xy 3.865819 -249.104971) (xy 3.93394 -249.012959)
			(xy 4.008401 -248.925998) (xy 4.088828 -248.844523) (xy 4.174818 -248.768942) (xy 4.26594 -248.699635)
			(xy 4.361737 -248.636949) (xy 4.46173 -248.581198) (xy 4.565416 -248.532661) (xy 4.672277 -248.491582)
			(xy 4.781777 -248.458167) (xy 4.893366 -248.432584) (xy 5.006486 -248.414959) (xy 5.120569 -248.405383)
			(xy 5.235044 -248.403902) (xy 5.349337 -248.410524) (xy 5.462875 -248.425217) (xy 5.575088 -248.447906)
			(xy 5.685416 -248.478477) (xy 5.793303 -248.516778) (xy 5.898211 -248.562616) (xy 5.999612 -248.615762)
			(xy 6.096999 -248.67595) (xy 6.189883 -248.742876) (xy 6.277799 -248.816208) (xy 6.360307 -248.895575)
			(xy 6.436992 -248.980582) (xy 6.50747 -249.070801) (xy 6.571389 -249.16578) (xy 6.628427 -249.265044)
			(xy 6.678299 -249.368095) (xy 6.720755 -249.474417) (xy 6.755581 -249.583475) (xy 6.782604 -249.694725)
			(xy 6.801689 -249.807607) (xy 6.812738 -249.921558) (xy 6.815698 -250.036004) (xy 6.810552 -250.150373)
			(xy 6.797328 -250.264091) (xy 6.77609 -250.376588) (xy 6.746947 -250.487301) (xy 6.710043 -250.595675)
			(xy 6.665563 -250.701165) (xy 6.613732 -250.803245) (xy 6.554808 -250.901401) (xy 6.489086 -250.995142)
			(xy 6.453378 -251.039884) (xy 6.059424 -251.039884) (xy 6.020367 -251.072253) (xy 5.938107 -251.131626)
			(xy 5.895086 -251.158502) (xy 5.881509 -251.167452) (xy 5.858992 -251.190897) (xy 5.843109 -251.219259)
			(xy 5.834884 -251.250707) (xy 5.83438 -251.26696) (xy 5.83438 -251.50699) (xy 5.779686 -251.529797)
			(xy 5.667599 -251.568292) (xy 5.552993 -251.598476) (xy 5.436486 -251.620186) (xy 5.318701 -251.633307)
			(xy 5.200272 -251.637768) (xy 5.081834 -251.633545) (xy 4.964023 -251.62066) (xy 4.847473 -251.599183)
			(xy 4.732807 -251.569229) (xy 4.620643 -251.530959) (xy 4.565904 -251.50826) (xy 4.565904 -251.26823)
			(xy 4.56544 -251.25195) (xy 4.557181 -251.220454) (xy 4.541219 -251.192074) (xy 4.518594 -251.168658)
			(xy 4.504944 -251.159772) (xy 4.45885 -251.131059) (xy 4.370982 -251.067228) (xy 4.32943 -251.032264)
			(xy 3.937762 -251.032264) (xy 3.903919 -250.989342) (xy 3.841441 -250.89964) (xy 3.785164 -250.805923)
			(xy 3.735346 -250.708619) (xy 3.692214 -250.608172) (xy 3.655964 -250.505042) (xy 3.626762 -250.399698)
			(xy 3.604742 -250.292623) (xy 3.590005 -250.184306) (xy 3.582617 -250.07524) (xy 3.582162 -250.020582)
			(xy 0.509016 -250.020582) (xy 0.509016 -267.869924) (xy 3.584453 -267.869924) (xy 3.588477 -267.755973)
			(xy 3.600528 -267.642589) (xy 3.620548 -267.530339) (xy 3.648436 -267.419779) (xy 3.684054 -267.311463)
			(xy 3.727223 -267.205929) (xy 3.777729 -267.103702) (xy 3.83532 -267.005294) (xy 3.899709 -266.911192)
			(xy 3.970576 -266.821867) (xy 4.047567 -266.737763) (xy 4.130299 -266.6593) (xy 4.218359 -266.586868)
			(xy 4.31131 -266.520828) (xy 4.408687 -266.461509) (xy 4.510006 -266.409207) (xy 4.614762 -266.364182)
			(xy 4.722433 -266.326658) (xy 4.832482 -266.296824) (xy 4.944363 -266.274826) (xy 5.057516 -266.260775)
			(xy 5.171378 -266.25474) (xy 5.285382 -266.256752) (xy 5.398961 -266.266801) (xy 5.511548 -266.284837)
			(xy 5.622582 -266.31077) (xy 5.73151 -266.34447) (xy 5.83779 -266.38577) (xy 5.940891 -266.434464)
			(xy 6.040301 -266.490309) (xy 6.135524 -266.553028) (xy 6.226086 -266.622307) (xy 6.311536 -266.697801)
			(xy 6.391447 -266.779136) (xy 6.465422 -266.865904) (xy 6.533092 -266.957675) (xy 6.59412 -267.05399)
			(xy 6.648202 -267.15437) (xy 6.695069 -267.258315) (xy 6.734487 -267.365307) (xy 6.766259 -267.474813)
			(xy 6.790228 -267.586287) (xy 6.806274 -267.699175) (xy 6.814317 -267.812913) (xy 6.81482 -267.869924)
			(xy 6.814317 -267.926935) (xy 6.806274 -268.040673) (xy 6.790228 -268.153561) (xy 6.766259 -268.265035)
			(xy 6.734487 -268.374541) (xy 6.695069 -268.481533) (xy 6.648202 -268.585478) (xy 6.59412 -268.685858)
			(xy 6.533092 -268.782173) (xy 6.465422 -268.873944) (xy 6.391447 -268.960712) (xy 6.311536 -269.042047)
			(xy 6.226086 -269.117541) (xy 6.135524 -269.18682) (xy 6.040301 -269.249539) (xy 5.940891 -269.305384)
			(xy 5.83779 -269.354078) (xy 5.73151 -269.395378) (xy 5.622582 -269.429078) (xy 5.511548 -269.455011)
			(xy 5.398961 -269.473047) (xy 5.285382 -269.483096) (xy 5.171378 -269.485108) (xy 5.057516 -269.479073)
			(xy 4.944363 -269.465022) (xy 4.832482 -269.443024) (xy 4.722433 -269.41319) (xy 4.614762 -269.375666)
			(xy 4.510006 -269.330641) (xy 4.408687 -269.278339) (xy 4.31131 -269.21902) (xy 4.218359 -269.15298)
			(xy 4.130299 -269.080548) (xy 4.047567 -269.002085) (xy 3.970576 -268.917981) (xy 3.899709 -268.828656)
			(xy 3.83532 -268.734554) (xy 3.777729 -268.636146) (xy 3.727223 -268.533919) (xy 3.684054 -268.428385)
			(xy 3.648436 -268.320069) (xy 3.620548 -268.209509) (xy 3.600528 -268.097259) (xy 3.588477 -267.983875)
			(xy 3.584453 -267.869924) (xy 0.509016 -267.869924) (xy 0.509016 -273.61007) (xy 39.818063 -273.61007)
			(xy 39.82207 -273.494046) (xy 39.834072 -273.378574) (xy 39.854012 -273.264206) (xy 39.881795 -273.151486)
			(xy 39.917289 -273.040952) (xy 39.960324 -272.933129) (xy 40.010695 -272.828532) (xy 40.068162 -272.72766)
			(xy 40.132452 -272.630993) (xy 40.203257 -272.538992) (xy 40.280241 -272.452095) (xy 40.363037 -272.370716)
			(xy 40.45125 -272.295243) (xy 40.54446 -272.226036) (xy 40.642223 -272.163424) (xy 40.744072 -272.107707)
			(xy 40.849522 -272.059149) (xy 40.958071 -272.017981) (xy 41.069202 -271.984401) (xy 41.182385 -271.958568)
			(xy 41.29708 -271.940605) (xy 41.412742 -271.930597) (xy 41.528818 -271.928594) (xy 41.644756 -271.934603)
			(xy 41.760003 -271.948596) (xy 41.874009 -271.970507) (xy 41.986233 -272.000232) (xy 42.096139 -272.037628)
			(xy 42.203202 -272.082517) (xy 42.306914 -272.134686) (xy 42.406779 -272.193886) (xy 42.502322 -272.259835)
			(xy 42.593088 -272.332218) (xy 42.678643 -272.410691) (xy 42.758581 -272.494879) (xy 42.83252 -272.584381)
			(xy 42.900108 -272.678772) (xy 42.961022 -272.7776) (xy 43.014974 -272.880396) (xy 43.061704 -272.986669)
			(xy 43.100992 -273.095913) (xy 43.132649 -273.207606) (xy 43.156525 -273.321218) (xy 43.172506 -273.436206)
			(xy 43.180515 -273.552023) (xy 43.181016 -273.61007) (xy 43.180515 -273.668117) (xy 43.172506 -273.783934)
			(xy 43.156525 -273.898922) (xy 43.132649 -274.012534) (xy 43.100992 -274.124227) (xy 43.061704 -274.233471)
			(xy 43.014974 -274.339744) (xy 42.961022 -274.44254) (xy 42.900108 -274.541368) (xy 42.83252 -274.635759)
			(xy 42.758581 -274.725261) (xy 42.678643 -274.809449) (xy 42.593088 -274.887922) (xy 42.502604 -274.96008)
			(xy 93.154506 -274.96008) (xy 93.158522 -274.84381) (xy 93.170549 -274.728095) (xy 93.190531 -274.613485)
			(xy 93.218373 -274.500526) (xy 93.253942 -274.389758) (xy 93.297068 -274.281707) (xy 93.347545 -274.176889)
			(xy 93.405134 -274.075804) (xy 93.46956 -273.978932) (xy 93.540515 -273.886736) (xy 93.617662 -273.799655)
			(xy 93.700633 -273.718104) (xy 93.789033 -273.642472) (xy 93.88244 -273.573118) (xy 93.980409 -273.510375)
			(xy 94.082473 -273.454539) (xy 94.188147 -273.405878) (xy 94.296926 -273.364624) (xy 94.408291 -273.330973)
			(xy 94.521714 -273.305085) (xy 94.636651 -273.287084) (xy 94.752557 -273.277055) (xy 94.868879 -273.275047)
			(xy 94.985062 -273.281069) (xy 95.100553 -273.295092) (xy 95.214801 -273.31705) (xy 95.327262 -273.346837)
			(xy 95.4374 -273.384312) (xy 95.54469 -273.429297) (xy 95.648621 -273.481576) (xy 95.748697 -273.540901)
			(xy 95.844443 -273.606989) (xy 95.9354 -273.679525) (xy 96.021136 -273.758164) (xy 96.101243 -273.84253)
			(xy 96.175339 -273.932222) (xy 96.243069 -274.026812) (xy 96.304113 -274.12585) (xy 96.358178 -274.228863)
			(xy 96.405008 -274.33536) (xy 96.444379 -274.444835) (xy 96.476103 -274.556765) (xy 96.500029 -274.670617)
			(xy 96.516043 -274.785849) (xy 96.52407 -274.901911) (xy 96.524572 -274.96008) (xy 96.52407 -275.018249)
			(xy 96.516043 -275.134311) (xy 96.500029 -275.249543) (xy 96.476103 -275.363395) (xy 96.444379 -275.475325)
			(xy 96.405008 -275.5848) (xy 96.358178 -275.691297) (xy 96.304113 -275.79431) (xy 96.243069 -275.893348)
			(xy 96.175339 -275.987938) (xy 96.101243 -276.07763) (xy 96.021136 -276.161996) (xy 95.9354 -276.240635)
			(xy 95.844443 -276.313171) (xy 95.748697 -276.379259) (xy 95.648621 -276.438584) (xy 95.54469 -276.490863)
			(xy 95.4374 -276.535848) (xy 95.327262 -276.573323) (xy 95.214801 -276.60311) (xy 95.100553 -276.625068)
			(xy 94.985062 -276.639091) (xy 94.868879 -276.645113) (xy 94.752557 -276.643105) (xy 94.636651 -276.633076)
			(xy 94.521714 -276.615075) (xy 94.408291 -276.589187) (xy 94.296926 -276.555536) (xy 94.188147 -276.514282)
			(xy 94.082473 -276.465621) (xy 93.980409 -276.409785) (xy 93.88244 -276.347042) (xy 93.789033 -276.277688)
			(xy 93.700633 -276.202056) (xy 93.617662 -276.120505) (xy 93.540515 -276.033424) (xy 93.46956 -275.941228)
			(xy 93.405134 -275.844356) (xy 93.347545 -275.743271) (xy 93.297068 -275.638453) (xy 93.253942 -275.530402)
			(xy 93.218373 -275.419634) (xy 93.190531 -275.306675) (xy 93.170549 -275.192065) (xy 93.158522 -275.07635)
			(xy 93.154506 -274.96008) (xy 42.502604 -274.96008) (xy 42.502322 -274.960305) (xy 42.406779 -275.026254)
			(xy 42.306914 -275.085454) (xy 42.203202 -275.137623) (xy 42.096139 -275.182512) (xy 41.986233 -275.219908)
			(xy 41.874009 -275.249633) (xy 41.760003 -275.271544) (xy 41.644756 -275.285537) (xy 41.528818 -275.291546)
			(xy 41.412742 -275.289543) (xy 41.29708 -275.279535) (xy 41.182385 -275.261572) (xy 41.069202 -275.235739)
			(xy 40.958071 -275.202159) (xy 40.849522 -275.160991) (xy 40.744072 -275.112433) (xy 40.642223 -275.056716)
			(xy 40.54446 -274.994104) (xy 40.45125 -274.924897) (xy 40.363037 -274.849424) (xy 40.280241 -274.768045)
			(xy 40.203257 -274.681148) (xy 40.132452 -274.589147) (xy 40.068162 -274.49248) (xy 40.010695 -274.391608)
			(xy 39.960324 -274.287011) (xy 39.917289 -274.179188) (xy 39.881795 -274.068654) (xy 39.854012 -273.955934)
			(xy 39.834072 -273.841566) (xy 39.82207 -273.726094) (xy 39.818063 -273.61007) (xy 0.509016 -273.61007)
			(xy 0.509016 -286.709866) (xy 86.877404 -286.709866) (xy 86.881424 -286.519215) (xy 86.893478 -286.328902)
			(xy 86.913544 -286.139267) (xy 86.941587 -285.950646) (xy 86.977556 -285.763376) (xy 87.021388 -285.577788)
			(xy 87.073005 -285.394213) (xy 87.132315 -285.212977) (xy 87.199213 -285.034402) (xy 87.273579 -284.858807)
			(xy 87.355281 -284.686502) (xy 87.444175 -284.517795) (xy 87.540101 -284.352985) (xy 87.64289 -284.192366)
			(xy 87.752359 -284.036223) (xy 87.868313 -283.884834) (xy 87.990547 -283.738467) (xy 88.118841 -283.597383)
			(xy 88.252969 -283.461834) (xy 88.392693 -283.332059) (xy 88.537763 -283.208289) (xy 88.687921 -283.090746)
			(xy 88.842902 -282.979637) (xy 89.002429 -282.87516) (xy 89.166218 -282.777501) (xy 89.333978 -282.686834)
			(xy 89.505412 -282.60332) (xy 89.680214 -282.527107) (xy 89.858073 -282.458331) (xy 90.038674 -282.397113)
			(xy 90.221694 -282.343564) (xy 90.40681 -282.297778) (xy 90.593691 -282.259836) (xy 90.782006 -282.229807)
			(xy 90.971419 -282.207742) (xy 91.161593 -282.193683) (xy 91.352192 -282.187653) (xy 91.542875 -282.189663)
			(xy 91.733304 -282.19971) (xy 91.92314 -282.217776) (xy 92.112046 -282.243829) (xy 92.299685 -282.277822)
			(xy 92.485725 -282.319695) (xy 92.669834 -282.369374) (xy 92.851685 -282.42677) (xy 93.030955 -282.491781)
			(xy 93.207325 -282.564292) (xy 93.380481 -282.644173) (xy 93.550116 -282.731283) (xy 93.715928 -282.825467)
			(xy 93.877622 -282.926558) (xy 94.03491 -283.034374) (xy 94.187513 -283.148726) (xy 94.335161 -283.269409)
			(xy 94.477589 -283.39621) (xy 94.614545 -283.528901) (xy 94.745786 -283.667249) (xy 94.871078 -283.811006)
			(xy 94.990198 -283.959917) (xy 95.102934 -284.113718) (xy 95.209087 -284.272134) (xy 95.308467 -284.434885)
			(xy 95.400897 -284.60168) (xy 95.486214 -284.772224) (xy 95.564266 -284.946212) (xy 95.634913 -285.123337)
			(xy 95.698031 -285.303282) (xy 95.753507 -285.485728) (xy 95.801242 -285.670351) (xy 95.841152 -285.856821)
			(xy 95.873165 -286.044809) (xy 95.897225 -286.233979) (xy 95.913288 -286.423995) (xy 95.921327 -286.614519)
			(xy 95.92183 -286.709866) (xy 95.921327 -286.805213) (xy 95.913288 -286.995737) (xy 95.897225 -287.185753)
			(xy 95.873165 -287.374923) (xy 95.841152 -287.562911) (xy 95.801242 -287.749381) (xy 95.753507 -287.934004)
			(xy 95.698031 -288.11645) (xy 95.634913 -288.296395) (xy 95.564266 -288.47352) (xy 95.486214 -288.647508)
			(xy 95.400897 -288.818052) (xy 95.308467 -288.984847) (xy 95.209087 -289.147598) (xy 95.102934 -289.306014)
			(xy 94.990198 -289.459815) (xy 94.871078 -289.608726) (xy 94.745786 -289.752483) (xy 94.614545 -289.890831)
			(xy 94.477589 -290.023522) (xy 94.335161 -290.150323) (xy 94.187513 -290.271006) (xy 94.03491 -290.385358)
			(xy 93.877622 -290.493174) (xy 93.715928 -290.594265) (xy 93.550116 -290.688449) (xy 93.380481 -290.775559)
			(xy 93.207325 -290.85544) (xy 93.030955 -290.927951) (xy 92.851685 -290.992962) (xy 92.669834 -291.050358)
			(xy 92.485725 -291.100037) (xy 92.299685 -291.14191) (xy 92.112046 -291.175903) (xy 91.92314 -291.201956)
			(xy 91.733304 -291.220022) (xy 91.542875 -291.230069) (xy 91.352192 -291.232079) (xy 91.161593 -291.226049)
			(xy 90.971419 -291.21199) (xy 90.782006 -291.189925) (xy 90.593691 -291.159896) (xy 90.40681 -291.121954)
			(xy 90.221694 -291.076168) (xy 90.038674 -291.022619) (xy 89.858073 -290.961401) (xy 89.680214 -290.892625)
			(xy 89.505412 -290.816412) (xy 89.333978 -290.732898) (xy 89.166218 -290.642231) (xy 89.002429 -290.544572)
			(xy 88.842902 -290.440095) (xy 88.687921 -290.328986) (xy 88.537763 -290.211443) (xy 88.392693 -290.087673)
			(xy 88.252969 -289.957898) (xy 88.118841 -289.822349) (xy 87.990547 -289.681265) (xy 87.868313 -289.534898)
			(xy 87.752359 -289.383509) (xy 87.64289 -289.227366) (xy 87.540101 -289.066747) (xy 87.444175 -288.901937)
			(xy 87.355281 -288.73323) (xy 87.273579 -288.560925) (xy 87.199213 -288.38533) (xy 87.132315 -288.206755)
			(xy 87.073005 -288.025519) (xy 87.021388 -287.841944) (xy 86.977556 -287.656356) (xy 86.941587 -287.469086)
			(xy 86.913544 -287.280465) (xy 86.893478 -287.09083) (xy 86.881424 -286.900517) (xy 86.877404 -286.709866)
			(xy 0.509016 -286.709866) (xy 0.509016 -295.89984) (xy 14.086591 -295.89984) (xy 14.090616 -295.757648)
			(xy 14.102679 -295.615912) (xy 14.122742 -295.475086) (xy 14.15074 -295.33562) (xy 14.186584 -295.197961)
			(xy 14.230158 -295.062551) (xy 14.281323 -294.929823) (xy 14.339916 -294.800202) (xy 14.405747 -294.674104)
			(xy 14.478608 -294.551932) (xy 14.558263 -294.434078) (xy 14.644459 -294.320919) (xy 14.736918 -294.212817)
			(xy 14.835346 -294.11012) (xy 14.939425 -294.013156) (xy 15.048824 -293.922236) (xy 15.163192 -293.83765)
			(xy 15.282161 -293.75967) (xy 15.405352 -293.688546) (xy 15.532369 -293.624505) (xy 15.662806 -293.567753)
			(xy 15.796245 -293.518471) (xy 15.932258 -293.476817) (xy 16.07041 -293.442925) (xy 16.210259 -293.416904)
			(xy 16.351355 -293.398836) (xy 16.493247 -293.388779) (xy 16.635482 -293.386766) (xy 16.777602 -293.392803)
			(xy 16.919153 -293.406871) (xy 17.059682 -293.428925) (xy 17.198737 -293.458894) (xy 17.335875 -293.496682)
			(xy 17.470655 -293.542168) (xy 17.602646 -293.595206) (xy 17.731425 -293.655627) (xy 17.856579 -293.723236)
			(xy 17.977707 -293.797818) (xy 18.094423 -293.879134) (xy 18.206351 -293.966922) (xy 18.313133 -294.060902)
			(xy 18.414427 -294.160772) (xy 18.509908 -294.266214) (xy 18.599272 -294.376888) (xy 18.68223 -294.492441)
			(xy 18.758519 -294.612502) (xy 18.827893 -294.736687) (xy 18.89013 -294.864598) (xy 18.945031 -294.995825)
			(xy 18.992419 -295.129948) (xy 19.032144 -295.266537) (xy 19.064077 -295.405155) (xy 19.088118 -295.545357)
			(xy 19.104187 -295.686695) (xy 19.112235 -295.828716) (xy 19.112738 -295.89984) (xy 19.112235 -295.970964)
			(xy 19.104187 -296.112985) (xy 19.088118 -296.254323) (xy 19.064077 -296.394525) (xy 19.032144 -296.533143)
			(xy 18.992419 -296.669732) (xy 18.945031 -296.803855) (xy 18.89013 -296.935082) (xy 18.827893 -297.062993)
			(xy 18.758519 -297.187178) (xy 18.68223 -297.307239) (xy 18.599272 -297.422792) (xy 18.509908 -297.533466)
			(xy 18.414427 -297.638908) (xy 18.313133 -297.738778) (xy 18.206351 -297.832758) (xy 18.094423 -297.920546)
			(xy 17.977707 -298.001862) (xy 17.856579 -298.076444) (xy 17.731425 -298.144053) (xy 17.602646 -298.204474)
			(xy 17.470655 -298.257512) (xy 17.335875 -298.302998) (xy 17.198737 -298.340786) (xy 17.059682 -298.370755)
			(xy 16.919153 -298.392809) (xy 16.777602 -298.406877) (xy 16.635482 -298.412914) (xy 16.493247 -298.410901)
			(xy 16.351355 -298.400844) (xy 16.210259 -298.382776) (xy 16.07041 -298.356755) (xy 15.932258 -298.322863)
			(xy 15.796245 -298.281209) (xy 15.662806 -298.231927) (xy 15.532369 -298.175175) (xy 15.405352 -298.111134)
			(xy 15.282161 -298.04001) (xy 15.163192 -297.96203) (xy 15.048824 -297.877444) (xy 14.939425 -297.786524)
			(xy 14.835346 -297.68956) (xy 14.736918 -297.586863) (xy 14.644459 -297.478761) (xy 14.558263 -297.365602)
			(xy 14.478608 -297.247748) (xy 14.405747 -297.125576) (xy 14.339916 -296.999478) (xy 14.281323 -296.869857)
			(xy 14.230158 -296.737129) (xy 14.186584 -296.601719) (xy 14.15074 -296.46406) (xy 14.122742 -296.324594)
			(xy 14.102679 -296.183768) (xy 14.090616 -296.042032) (xy 14.086591 -295.89984) (xy 0.509016 -295.89984)
			(xy 0.509016 -318.06007) (xy 39.818063 -318.06007) (xy 39.82207 -317.944046) (xy 39.834072 -317.828574)
			(xy 39.854012 -317.714206) (xy 39.881795 -317.601486) (xy 39.917289 -317.490952) (xy 39.960324 -317.383129)
			(xy 40.010695 -317.278532) (xy 40.068162 -317.17766) (xy 40.132452 -317.080993) (xy 40.203257 -316.988992)
			(xy 40.280241 -316.902095) (xy 40.363037 -316.820716) (xy 40.45125 -316.745243) (xy 40.54446 -316.676036)
			(xy 40.642223 -316.613424) (xy 40.744072 -316.557707) (xy 40.849522 -316.509149) (xy 40.958071 -316.467981)
			(xy 41.069202 -316.434401) (xy 41.182385 -316.408568) (xy 41.29708 -316.390605) (xy 41.412742 -316.380597)
			(xy 41.528818 -316.378594) (xy 41.644756 -316.384603) (xy 41.760003 -316.398596) (xy 41.874009 -316.420507)
			(xy 41.986233 -316.450232) (xy 42.096139 -316.487628) (xy 42.203202 -316.532517) (xy 42.306914 -316.584686)
			(xy 42.406779 -316.643886) (xy 42.502322 -316.709835) (xy 42.593088 -316.782218) (xy 42.678643 -316.860691)
			(xy 42.758581 -316.944879) (xy 42.83252 -317.034381) (xy 42.900108 -317.128772) (xy 42.961022 -317.2276)
			(xy 43.014974 -317.330396) (xy 43.061704 -317.436669) (xy 43.100992 -317.545913) (xy 43.132649 -317.657606)
			(xy 43.156525 -317.771218) (xy 43.172506 -317.886206) (xy 43.180515 -318.002023) (xy 43.181016 -318.06007)
			(xy 43.180515 -318.118117) (xy 43.172506 -318.233934) (xy 43.156525 -318.348922) (xy 43.132649 -318.462534)
			(xy 43.100992 -318.574227) (xy 43.061704 -318.683471) (xy 43.014974 -318.789744) (xy 42.961022 -318.89254)
			(xy 42.900108 -318.991368) (xy 42.83252 -319.085759) (xy 42.758581 -319.175261) (xy 42.678643 -319.259449)
			(xy 42.593088 -319.337922) (xy 42.502604 -319.41008) (xy 93.154506 -319.41008) (xy 93.158522 -319.29381)
			(xy 93.170549 -319.178095) (xy 93.190531 -319.063485) (xy 93.218373 -318.950526) (xy 93.253942 -318.839758)
			(xy 93.297068 -318.731707) (xy 93.347545 -318.626889) (xy 93.405134 -318.525804) (xy 93.46956 -318.428932)
			(xy 93.540515 -318.336736) (xy 93.617662 -318.249655) (xy 93.700633 -318.168104) (xy 93.789033 -318.092472)
			(xy 93.88244 -318.023118) (xy 93.980409 -317.960375) (xy 94.082473 -317.904539) (xy 94.188147 -317.855878)
			(xy 94.296926 -317.814624) (xy 94.408291 -317.780973) (xy 94.521714 -317.755085) (xy 94.636651 -317.737084)
			(xy 94.752557 -317.727055) (xy 94.868879 -317.725047) (xy 94.985062 -317.731069) (xy 95.100553 -317.745092)
			(xy 95.214801 -317.76705) (xy 95.327262 -317.796837) (xy 95.4374 -317.834312) (xy 95.54469 -317.879297)
			(xy 95.648621 -317.931576) (xy 95.748697 -317.990901) (xy 95.844443 -318.056989) (xy 95.9354 -318.129525)
			(xy 96.021136 -318.208164) (xy 96.101243 -318.29253) (xy 96.175339 -318.382222) (xy 96.243069 -318.476812)
			(xy 96.304113 -318.57585) (xy 96.358178 -318.678863) (xy 96.405008 -318.78536) (xy 96.444379 -318.894835)
			(xy 96.476103 -319.006765) (xy 96.500029 -319.120617) (xy 96.516043 -319.235849) (xy 96.52407 -319.351911)
			(xy 96.524572 -319.41008) (xy 96.52407 -319.468249) (xy 96.516043 -319.584311) (xy 96.500029 -319.699543)
			(xy 96.476103 -319.813395) (xy 96.444379 -319.925325) (xy 96.405008 -320.0348) (xy 96.358178 -320.141297)
			(xy 96.304113 -320.24431) (xy 96.243069 -320.343348) (xy 96.175339 -320.437938) (xy 96.101243 -320.52763)
			(xy 96.021136 -320.611996) (xy 95.9354 -320.690635) (xy 95.844443 -320.763171) (xy 95.748697 -320.829259)
			(xy 95.648621 -320.888584) (xy 95.54469 -320.940863) (xy 95.4374 -320.985848) (xy 95.327262 -321.023323)
			(xy 95.214801 -321.05311) (xy 95.100553 -321.075068) (xy 94.985062 -321.089091) (xy 94.868879 -321.095113)
			(xy 94.752557 -321.093105) (xy 94.636651 -321.083076) (xy 94.521714 -321.065075) (xy 94.408291 -321.039187)
			(xy 94.296926 -321.005536) (xy 94.188147 -320.964282) (xy 94.082473 -320.915621) (xy 93.980409 -320.859785)
			(xy 93.88244 -320.797042) (xy 93.789033 -320.727688) (xy 93.700633 -320.652056) (xy 93.617662 -320.570505)
			(xy 93.540515 -320.483424) (xy 93.46956 -320.391228) (xy 93.405134 -320.294356) (xy 93.347545 -320.193271)
			(xy 93.297068 -320.088453) (xy 93.253942 -319.980402) (xy 93.218373 -319.869634) (xy 93.190531 -319.756675)
			(xy 93.170549 -319.642065) (xy 93.158522 -319.52635) (xy 93.154506 -319.41008) (xy 42.502604 -319.41008)
			(xy 42.502322 -319.410305) (xy 42.406779 -319.476254) (xy 42.306914 -319.535454) (xy 42.203202 -319.587623)
			(xy 42.096139 -319.632512) (xy 41.986233 -319.669908) (xy 41.874009 -319.699633) (xy 41.760003 -319.721544)
			(xy 41.644756 -319.735537) (xy 41.528818 -319.741546) (xy 41.412742 -319.739543) (xy 41.29708 -319.729535)
			(xy 41.182385 -319.711572) (xy 41.069202 -319.685739) (xy 40.958071 -319.652159) (xy 40.849522 -319.610991)
			(xy 40.744072 -319.562433) (xy 40.642223 -319.506716) (xy 40.54446 -319.444104) (xy 40.45125 -319.374897)
			(xy 40.363037 -319.299424) (xy 40.280241 -319.218045) (xy 40.203257 -319.131148) (xy 40.132452 -319.039147)
			(xy 40.068162 -318.94248) (xy 40.010695 -318.841608) (xy 39.960324 -318.737011) (xy 39.917289 -318.629188)
			(xy 39.881795 -318.518654) (xy 39.854012 -318.405934) (xy 39.834072 -318.291566) (xy 39.82207 -318.176094)
			(xy 39.818063 -318.06007) (xy 0.509016 -318.06007) (xy 0.509016 -331.16012) (xy 86.877404 -331.16012)
			(xy 86.881424 -330.969469) (xy 86.893478 -330.779156) (xy 86.913544 -330.589521) (xy 86.941587 -330.4009)
			(xy 86.977556 -330.21363) (xy 87.021388 -330.028042) (xy 87.073005 -329.844467) (xy 87.132315 -329.663231)
			(xy 87.199213 -329.484656) (xy 87.273579 -329.309061) (xy 87.355281 -329.136756) (xy 87.444175 -328.968049)
			(xy 87.540101 -328.803239) (xy 87.64289 -328.64262) (xy 87.752359 -328.486477) (xy 87.868313 -328.335088)
			(xy 87.990547 -328.188721) (xy 88.118841 -328.047637) (xy 88.252969 -327.912088) (xy 88.392693 -327.782313)
			(xy 88.537763 -327.658543) (xy 88.687921 -327.541) (xy 88.842902 -327.429891) (xy 89.002429 -327.325414)
			(xy 89.166218 -327.227755) (xy 89.333978 -327.137088) (xy 89.505412 -327.053574) (xy 89.680214 -326.977361)
			(xy 89.858073 -326.908585) (xy 90.038674 -326.847367) (xy 90.221694 -326.793818) (xy 90.40681 -326.748032)
			(xy 90.593691 -326.71009) (xy 90.782006 -326.680061) (xy 90.971419 -326.657996) (xy 91.161593 -326.643937)
			(xy 91.352192 -326.637907) (xy 91.542875 -326.639917) (xy 91.733304 -326.649964) (xy 91.92314 -326.66803)
			(xy 92.112046 -326.694083) (xy 92.299685 -326.728076) (xy 92.485725 -326.769949) (xy 92.669834 -326.819628)
			(xy 92.851685 -326.877024) (xy 93.030955 -326.942035) (xy 93.207325 -327.014546) (xy 93.380481 -327.094427)
			(xy 93.550116 -327.181537) (xy 93.715928 -327.275721) (xy 93.877622 -327.376812) (xy 94.03491 -327.484628)
			(xy 94.187513 -327.59898) (xy 94.335161 -327.719663) (xy 94.477589 -327.846464) (xy 94.614545 -327.979155)
			(xy 94.745786 -328.117503) (xy 94.871078 -328.26126) (xy 94.990198 -328.410171) (xy 95.102934 -328.563972)
			(xy 95.209087 -328.722388) (xy 95.308467 -328.885139) (xy 95.400897 -329.051934) (xy 95.486214 -329.222478)
			(xy 95.564266 -329.396466) (xy 95.634913 -329.573591) (xy 95.698031 -329.753536) (xy 95.753507 -329.935982)
			(xy 95.801242 -330.120605) (xy 95.841152 -330.307075) (xy 95.873165 -330.495063) (xy 95.897225 -330.684233)
			(xy 95.913288 -330.874249) (xy 95.921327 -331.064773) (xy 95.92183 -331.16012) (xy 95.921327 -331.255467)
			(xy 95.913288 -331.445991) (xy 95.897225 -331.636007) (xy 95.873165 -331.825177) (xy 95.841152 -332.013165)
			(xy 95.801242 -332.199635) (xy 95.753507 -332.384258) (xy 95.698031 -332.566704) (xy 95.634913 -332.746649)
			(xy 95.564266 -332.923774) (xy 95.486214 -333.097762) (xy 95.400897 -333.268306) (xy 95.308467 -333.435101)
			(xy 95.209087 -333.597852) (xy 95.102934 -333.756268) (xy 94.990198 -333.910069) (xy 94.871078 -334.05898)
			(xy 94.745786 -334.202737) (xy 94.614545 -334.341085) (xy 94.477589 -334.473776) (xy 94.335161 -334.600577)
			(xy 94.187513 -334.72126) (xy 94.03491 -334.835612) (xy 93.877622 -334.943428) (xy 93.715928 -335.044519)
			(xy 93.550116 -335.138703) (xy 93.380481 -335.225813) (xy 93.207325 -335.305694) (xy 93.030955 -335.378205)
			(xy 92.851685 -335.443216) (xy 92.669834 -335.500612) (xy 92.485725 -335.550291) (xy 92.299685 -335.592164)
			(xy 92.112046 -335.626157) (xy 91.92314 -335.65221) (xy 91.733304 -335.670276) (xy 91.542875 -335.680323)
			(xy 91.352192 -335.682333) (xy 91.161593 -335.676303) (xy 90.971419 -335.662244) (xy 90.782006 -335.640179)
			(xy 90.593691 -335.61015) (xy 90.40681 -335.572208) (xy 90.221694 -335.526422) (xy 90.038674 -335.472873)
			(xy 89.858073 -335.411655) (xy 89.680214 -335.342879) (xy 89.505412 -335.266666) (xy 89.333978 -335.183152)
			(xy 89.166218 -335.092485) (xy 89.002429 -334.994826) (xy 88.842902 -334.890349) (xy 88.687921 -334.77924)
			(xy 88.537763 -334.661697) (xy 88.392693 -334.537927) (xy 88.252969 -334.408152) (xy 88.118841 -334.272603)
			(xy 87.990547 -334.131519) (xy 87.868313 -333.985152) (xy 87.752359 -333.833763) (xy 87.64289 -333.67762)
			(xy 87.540101 -333.517001) (xy 87.444175 -333.352191) (xy 87.355281 -333.183484) (xy 87.273579 -333.011179)
			(xy 87.199213 -332.835584) (xy 87.132315 -332.657009) (xy 87.073005 -332.475773) (xy 87.021388 -332.292198)
			(xy 86.977556 -332.10661) (xy 86.941587 -331.91934) (xy 86.913544 -331.730719) (xy 86.893478 -331.541084)
			(xy 86.881424 -331.350771) (xy 86.877404 -331.16012) (xy 0.509016 -331.16012) (xy 0.509016 -341.019892)
			(xy 3.583178 -341.019892) (xy 3.583678 -340.962646) (xy 3.59178 -340.848441) (xy 3.607943 -340.735095)
			(xy 3.632086 -340.623177) (xy 3.664086 -340.513247) (xy 3.703785 -340.405858) (xy 3.750982 -340.301546)
			(xy 3.805442 -340.200836) (xy 3.866891 -340.104231) (xy 3.935021 -340.012216) (xy 4.009491 -339.925252)
			(xy 4.089928 -339.843775) (xy 4.175928 -339.768194) (xy 4.26706 -339.698887) (xy 4.362867 -339.636202)
			(xy 4.46287 -339.580453) (xy 4.566566 -339.531919) (xy 4.673437 -339.490844) (xy 4.782946 -339.457434)
			(xy 4.894545 -339.431855) (xy 5.007674 -339.414237) (xy 5.121765 -339.404668) (xy 5.236248 -339.403195)
			(xy 5.350548 -339.409826) (xy 5.464093 -339.424528) (xy 5.576313 -339.447227) (xy 5.686645 -339.477809)
			(xy 5.794537 -339.516121) (xy 5.899448 -339.561971) (xy 6.000852 -339.615129) (xy 6.09824 -339.675328)
			(xy 6.191125 -339.742268) (xy 6.279041 -339.815611) (xy 6.361547 -339.894992) (xy 6.43823 -339.980011)
			(xy 6.508705 -340.070243) (xy 6.572619 -340.165235) (xy 6.629651 -340.264511) (xy 6.679516 -340.367574)
			(xy 6.721964 -340.473907) (xy 6.756783 -340.582977) (xy 6.783796 -340.694236) (xy 6.80287 -340.807129)
			(xy 6.813908 -340.921088) (xy 6.816855 -341.035542) (xy 6.811697 -341.149918) (xy 6.800045 -341.250016)
			(xy 75.486519 -341.250016) (xy 75.490544 -341.107824) (xy 75.502607 -340.966088) (xy 75.52267 -340.825262)
			(xy 75.550668 -340.685796) (xy 75.586512 -340.548137) (xy 75.630086 -340.412727) (xy 75.681251 -340.279999)
			(xy 75.739844 -340.150378) (xy 75.805675 -340.02428) (xy 75.878536 -339.902108) (xy 75.958191 -339.784254)
			(xy 76.044387 -339.671095) (xy 76.136846 -339.562993) (xy 76.235274 -339.460296) (xy 76.339353 -339.363332)
			(xy 76.448752 -339.272412) (xy 76.56312 -339.187826) (xy 76.682089 -339.109846) (xy 76.80528 -339.038722)
			(xy 76.932297 -338.974681) (xy 77.062734 -338.917929) (xy 77.196173 -338.868647) (xy 77.332186 -338.826993)
			(xy 77.470338 -338.793101) (xy 77.610187 -338.76708) (xy 77.751283 -338.749012) (xy 77.893175 -338.738955)
			(xy 78.03541 -338.736942) (xy 78.17753 -338.742979) (xy 78.319081 -338.757047) (xy 78.45961 -338.779101)
			(xy 78.598665 -338.80907) (xy 78.735803 -338.846858) (xy 78.870583 -338.892344) (xy 79.002574 -338.945382)
			(xy 79.131353 -339.005803) (xy 79.256507 -339.073412) (xy 79.377635 -339.147994) (xy 79.494351 -339.22931)
			(xy 79.606279 -339.317098) (xy 79.713061 -339.411078) (xy 79.814355 -339.510948) (xy 79.909836 -339.61639)
			(xy 79.9992 -339.727064) (xy 80.082158 -339.842617) (xy 80.158447 -339.962678) (xy 80.227821 -340.086863)
			(xy 80.290058 -340.214774) (xy 80.344959 -340.346001) (xy 80.392347 -340.480124) (xy 80.432072 -340.616713)
			(xy 80.464005 -340.755331) (xy 80.488046 -340.895533) (xy 80.504115 -341.036871) (xy 80.512163 -341.178892)
			(xy 80.512666 -341.250016) (xy 80.512163 -341.32114) (xy 80.504115 -341.463161) (xy 80.488046 -341.604499)
			(xy 80.464005 -341.744701) (xy 80.432072 -341.883319) (xy 80.392347 -342.019908) (xy 80.344959 -342.154031)
			(xy 80.290058 -342.285258) (xy 80.227821 -342.413169) (xy 80.158447 -342.537354) (xy 80.082158 -342.657415)
			(xy 79.9992 -342.772968) (xy 79.909836 -342.883642) (xy 79.814355 -342.989084) (xy 79.713061 -343.088954)
			(xy 79.606279 -343.182934) (xy 79.494351 -343.270722) (xy 79.377635 -343.352038) (xy 79.256507 -343.42662)
			(xy 79.131353 -343.494229) (xy 79.002574 -343.55465) (xy 78.870583 -343.607688) (xy 78.735803 -343.653174)
			(xy 78.598665 -343.690962) (xy 78.45961 -343.720931) (xy 78.319081 -343.742985) (xy 78.17753 -343.757053)
			(xy 78.03541 -343.76309) (xy 77.893175 -343.761077) (xy 77.751283 -343.75102) (xy 77.610187 -343.732952)
			(xy 77.470338 -343.706931) (xy 77.332186 -343.673039) (xy 77.196173 -343.631385) (xy 77.062734 -343.582103)
			(xy 76.932297 -343.525351) (xy 76.80528 -343.46131) (xy 76.682089 -343.390186) (xy 76.56312 -343.312206)
			(xy 76.448752 -343.22762) (xy 76.339353 -343.1367) (xy 76.235274 -343.039736) (xy 76.136846 -342.937039)
			(xy 76.044387 -342.828937) (xy 75.958191 -342.715778) (xy 75.878536 -342.597924) (xy 75.805675 -342.475752)
			(xy 75.739844 -342.349654) (xy 75.681251 -342.220033) (xy 75.630086 -342.087305) (xy 75.586512 -341.951895)
			(xy 75.550668 -341.814236) (xy 75.52267 -341.67477) (xy 75.502607 -341.533944) (xy 75.490544 -341.392208)
			(xy 75.486519 -341.250016) (xy 6.800045 -341.250016) (xy 6.798459 -341.263643) (xy 6.777208 -341.376146)
			(xy 6.748049 -341.486863) (xy 6.71113 -341.595239) (xy 6.666635 -341.700732) (xy 6.614788 -341.802812)
			(xy 6.555848 -341.900968) (xy 6.49011 -341.994707) (xy 6.454394 -342.039448) (xy 6.060186 -342.039448)
			(xy 6.021179 -342.071737) (xy 5.939048 -342.130983) (xy 5.896102 -342.157812) (xy 5.882524 -342.166761)
			(xy 5.860006 -342.190206) (xy 5.844123 -342.218568) (xy 5.8359 -342.250017) (xy 5.835396 -342.26627)
			(xy 5.835396 -342.5063) (xy 5.780703 -342.52911) (xy 5.668615 -342.567604) (xy 5.55401 -342.597788)
			(xy 5.437502 -342.619498) (xy 5.319718 -342.632619) (xy 5.201288 -342.63708) (xy 5.08285 -342.632856)
			(xy 4.96504 -342.619971) (xy 4.848489 -342.598494) (xy 4.733823 -342.56854) (xy 4.621659 -342.53027)
			(xy 4.56692 -342.50757) (xy 4.56692 -342.26754) (xy 4.566441 -342.251261) (xy 4.558186 -342.219766)
			(xy 4.542229 -342.191387) (xy 4.519608 -342.167969) (xy 4.50596 -342.159082) (xy 4.459776 -342.130343)
			(xy 4.371783 -342.066378) (xy 4.330192 -342.03132) (xy 3.938778 -342.03132) (xy 3.904941 -341.988409)
			(xy 3.842477 -341.898728) (xy 3.78621 -341.805035) (xy 3.736399 -341.707756) (xy 3.69327 -341.607335)
			(xy 3.657021 -341.504231) (xy 3.627816 -341.398915) (xy 3.60579 -341.291867) (xy 3.591042 -341.183577)
			(xy 3.583641 -341.074537) (xy 3.583178 -341.019892) (xy 0.509016 -341.019892) (xy 0.509016 -362.51007)
			(xy 39.818063 -362.51007) (xy 39.82207 -362.394046) (xy 39.834072 -362.278574) (xy 39.854012 -362.164206)
			(xy 39.881795 -362.051486) (xy 39.917289 -361.940952) (xy 39.960324 -361.833129) (xy 40.010695 -361.728532)
			(xy 40.068162 -361.62766) (xy 40.132452 -361.530993) (xy 40.203257 -361.438992) (xy 40.280241 -361.352095)
			(xy 40.363037 -361.270716) (xy 40.45125 -361.195243) (xy 40.54446 -361.126036) (xy 40.642223 -361.063424)
			(xy 40.744072 -361.007707) (xy 40.849522 -360.959149) (xy 40.958071 -360.917981) (xy 41.069202 -360.884401)
			(xy 41.182385 -360.858568) (xy 41.29708 -360.840605) (xy 41.412742 -360.830597) (xy 41.528818 -360.828594)
			(xy 41.644756 -360.834603) (xy 41.760003 -360.848596) (xy 41.874009 -360.870507) (xy 41.986233 -360.900232)
			(xy 42.096139 -360.937628) (xy 42.203202 -360.982517) (xy 42.306914 -361.034686) (xy 42.406779 -361.093886)
			(xy 42.502322 -361.159835) (xy 42.593088 -361.232218) (xy 42.678643 -361.310691) (xy 42.758581 -361.394879)
			(xy 42.83252 -361.484381) (xy 42.900108 -361.578772) (xy 42.961022 -361.6776) (xy 43.014974 -361.780396)
			(xy 43.061704 -361.886669) (xy 43.100992 -361.995913) (xy 43.132649 -362.107606) (xy 43.156525 -362.221218)
			(xy 43.172506 -362.336206) (xy 43.180515 -362.452023) (xy 43.181016 -362.51007) (xy 43.180515 -362.568117)
			(xy 43.172506 -362.683934) (xy 43.156525 -362.798922) (xy 43.132649 -362.912534) (xy 43.100992 -363.024227)
			(xy 43.061704 -363.133471) (xy 43.014974 -363.239744) (xy 42.961022 -363.34254) (xy 42.900108 -363.441368)
			(xy 42.83252 -363.535759) (xy 42.758581 -363.625261) (xy 42.678643 -363.709449) (xy 42.593088 -363.787922)
			(xy 42.502604 -363.86008) (xy 93.154506 -363.86008) (xy 93.158522 -363.74381) (xy 93.170549 -363.628095)
			(xy 93.190531 -363.513485) (xy 93.218373 -363.400526) (xy 93.253942 -363.289758) (xy 93.297068 -363.181707)
			(xy 93.347545 -363.076889) (xy 93.405134 -362.975804) (xy 93.46956 -362.878932) (xy 93.540515 -362.786736)
			(xy 93.617662 -362.699655) (xy 93.700633 -362.618104) (xy 93.789033 -362.542472) (xy 93.88244 -362.473118)
			(xy 93.980409 -362.410375) (xy 94.082473 -362.354539) (xy 94.188147 -362.305878) (xy 94.296926 -362.264624)
			(xy 94.408291 -362.230973) (xy 94.521714 -362.205085) (xy 94.636651 -362.187084) (xy 94.752557 -362.177055)
			(xy 94.868879 -362.175047) (xy 94.985062 -362.181069) (xy 95.100553 -362.195092) (xy 95.214801 -362.21705)
			(xy 95.327262 -362.246837) (xy 95.4374 -362.284312) (xy 95.54469 -362.329297) (xy 95.648621 -362.381576)
			(xy 95.748697 -362.440901) (xy 95.844443 -362.506989) (xy 95.9354 -362.579525) (xy 96.021136 -362.658164)
			(xy 96.101243 -362.74253) (xy 96.175339 -362.832222) (xy 96.243069 -362.926812) (xy 96.304113 -363.02585)
			(xy 96.358178 -363.128863) (xy 96.405008 -363.23536) (xy 96.444379 -363.344835) (xy 96.476103 -363.456765)
			(xy 96.500029 -363.570617) (xy 96.516043 -363.685849) (xy 96.52407 -363.801911) (xy 96.524572 -363.86008)
			(xy 96.52407 -363.918249) (xy 96.516043 -364.034311) (xy 96.500029 -364.149543) (xy 96.476103 -364.263395)
			(xy 96.444379 -364.375325) (xy 96.405008 -364.4848) (xy 96.358178 -364.591297) (xy 96.304113 -364.69431)
			(xy 96.243069 -364.793348) (xy 96.175339 -364.887938) (xy 96.101243 -364.97763) (xy 96.021136 -365.061996)
			(xy 95.9354 -365.140635) (xy 95.844443 -365.213171) (xy 95.748697 -365.279259) (xy 95.648621 -365.338584)
			(xy 95.54469 -365.390863) (xy 95.4374 -365.435848) (xy 95.327262 -365.473323) (xy 95.214801 -365.50311)
			(xy 95.100553 -365.525068) (xy 94.985062 -365.539091) (xy 94.868879 -365.545113) (xy 94.752557 -365.543105)
			(xy 94.636651 -365.533076) (xy 94.521714 -365.515075) (xy 94.408291 -365.489187) (xy 94.296926 -365.455536)
			(xy 94.188147 -365.414282) (xy 94.082473 -365.365621) (xy 93.980409 -365.309785) (xy 93.88244 -365.247042)
			(xy 93.789033 -365.177688) (xy 93.700633 -365.102056) (xy 93.617662 -365.020505) (xy 93.540515 -364.933424)
			(xy 93.46956 -364.841228) (xy 93.405134 -364.744356) (xy 93.347545 -364.643271) (xy 93.297068 -364.538453)
			(xy 93.253942 -364.430402) (xy 93.218373 -364.319634) (xy 93.190531 -364.206675) (xy 93.170549 -364.092065)
			(xy 93.158522 -363.97635) (xy 93.154506 -363.86008) (xy 42.502604 -363.86008) (xy 42.502322 -363.860305)
			(xy 42.406779 -363.926254) (xy 42.306914 -363.985454) (xy 42.203202 -364.037623) (xy 42.096139 -364.082512)
			(xy 41.986233 -364.119908) (xy 41.874009 -364.149633) (xy 41.760003 -364.171544) (xy 41.644756 -364.185537)
			(xy 41.528818 -364.191546) (xy 41.412742 -364.189543) (xy 41.29708 -364.179535) (xy 41.182385 -364.161572)
			(xy 41.069202 -364.135739) (xy 40.958071 -364.102159) (xy 40.849522 -364.060991) (xy 40.744072 -364.012433)
			(xy 40.642223 -363.956716) (xy 40.54446 -363.894104) (xy 40.45125 -363.824897) (xy 40.363037 -363.749424)
			(xy 40.280241 -363.668045) (xy 40.203257 -363.581148) (xy 40.132452 -363.489147) (xy 40.068162 -363.39248)
			(xy 40.010695 -363.291608) (xy 39.960324 -363.187011) (xy 39.917289 -363.079188) (xy 39.881795 -362.968654)
			(xy 39.854012 -362.855934) (xy 39.834072 -362.741566) (xy 39.82207 -362.626094) (xy 39.818063 -362.51007)
			(xy 0.509016 -362.51007) (xy 0.509016 -375.61012) (xy 86.877404 -375.61012) (xy 86.881424 -375.419469)
			(xy 86.893478 -375.229156) (xy 86.913544 -375.039521) (xy 86.941587 -374.8509) (xy 86.977556 -374.66363)
			(xy 87.021388 -374.478042) (xy 87.073005 -374.294467) (xy 87.132315 -374.113231) (xy 87.199213 -373.934656)
			(xy 87.273579 -373.759061) (xy 87.355281 -373.586756) (xy 87.444175 -373.418049) (xy 87.540101 -373.253239)
			(xy 87.64289 -373.09262) (xy 87.752359 -372.936477) (xy 87.868313 -372.785088) (xy 87.990547 -372.638721)
			(xy 88.118841 -372.497637) (xy 88.252969 -372.362088) (xy 88.392693 -372.232313) (xy 88.537763 -372.108543)
			(xy 88.687921 -371.991) (xy 88.842902 -371.879891) (xy 89.002429 -371.775414) (xy 89.166218 -371.677755)
			(xy 89.333978 -371.587088) (xy 89.505412 -371.503574) (xy 89.680214 -371.427361) (xy 89.858073 -371.358585)
			(xy 90.038674 -371.297367) (xy 90.221694 -371.243818) (xy 90.40681 -371.198032) (xy 90.593691 -371.16009)
			(xy 90.782006 -371.130061) (xy 90.971419 -371.107996) (xy 91.161593 -371.093937) (xy 91.352192 -371.087907)
			(xy 91.542875 -371.089917) (xy 91.733304 -371.099964) (xy 91.92314 -371.11803) (xy 92.112046 -371.144083)
			(xy 92.299685 -371.178076) (xy 92.485725 -371.219949) (xy 92.669834 -371.269628) (xy 92.851685 -371.327024)
			(xy 93.030955 -371.392035) (xy 93.207325 -371.464546) (xy 93.380481 -371.544427) (xy 93.550116 -371.631537)
			(xy 93.715928 -371.725721) (xy 93.877622 -371.826812) (xy 94.03491 -371.934628) (xy 94.187513 -372.04898)
			(xy 94.335161 -372.169663) (xy 94.477589 -372.296464) (xy 94.614545 -372.429155) (xy 94.745786 -372.567503)
			(xy 94.871078 -372.71126) (xy 94.990198 -372.860171) (xy 95.102934 -373.013972) (xy 95.209087 -373.172388)
			(xy 95.308467 -373.335139) (xy 95.400897 -373.501934) (xy 95.486214 -373.672478) (xy 95.564266 -373.846466)
			(xy 95.634913 -374.023591) (xy 95.698031 -374.203536) (xy 95.753507 -374.385982) (xy 95.801242 -374.570605)
			(xy 95.841152 -374.757075) (xy 95.873165 -374.945063) (xy 95.897225 -375.134233) (xy 95.913288 -375.324249)
			(xy 95.921327 -375.514773) (xy 95.92183 -375.61012) (xy 95.921327 -375.705467) (xy 95.913288 -375.895991)
			(xy 95.897225 -376.086007) (xy 95.873165 -376.275177) (xy 95.841152 -376.463165) (xy 95.801242 -376.649635)
			(xy 95.753507 -376.834258) (xy 95.698031 -377.016704) (xy 95.634913 -377.196649) (xy 95.564266 -377.373774)
			(xy 95.486214 -377.547762) (xy 95.400897 -377.718306) (xy 95.308467 -377.885101) (xy 95.209087 -378.047852)
			(xy 95.102934 -378.206268) (xy 94.990198 -378.360069) (xy 94.871078 -378.50898) (xy 94.745786 -378.652737)
			(xy 94.614545 -378.791085) (xy 94.477589 -378.923776) (xy 94.335161 -379.050577) (xy 94.187513 -379.17126)
			(xy 94.03491 -379.285612) (xy 93.877622 -379.393428) (xy 93.715928 -379.494519) (xy 93.550116 -379.588703)
			(xy 93.380481 -379.675813) (xy 93.207325 -379.755694) (xy 93.030955 -379.828205) (xy 92.851685 -379.893216)
			(xy 92.669834 -379.950612) (xy 92.485725 -380.000291) (xy 92.299685 -380.042164) (xy 92.112046 -380.076157)
			(xy 91.92314 -380.10221) (xy 91.733304 -380.120276) (xy 91.542875 -380.130323) (xy 91.352192 -380.132333)
			(xy 91.161593 -380.126303) (xy 90.971419 -380.112244) (xy 90.782006 -380.090179) (xy 90.593691 -380.06015)
			(xy 90.40681 -380.022208) (xy 90.221694 -379.976422) (xy 90.038674 -379.922873) (xy 89.858073 -379.861655)
			(xy 89.680214 -379.792879) (xy 89.505412 -379.716666) (xy 89.333978 -379.633152) (xy 89.166218 -379.542485)
			(xy 89.002429 -379.444826) (xy 88.842902 -379.340349) (xy 88.687921 -379.22924) (xy 88.537763 -379.111697)
			(xy 88.392693 -378.987927) (xy 88.252969 -378.858152) (xy 88.118841 -378.722603) (xy 87.990547 -378.581519)
			(xy 87.868313 -378.435152) (xy 87.752359 -378.283763) (xy 87.64289 -378.12762) (xy 87.540101 -377.967001)
			(xy 87.444175 -377.802191) (xy 87.355281 -377.633484) (xy 87.273579 -377.461179) (xy 87.199213 -377.285584)
			(xy 87.132315 -377.107009) (xy 87.073005 -376.925773) (xy 87.021388 -376.742198) (xy 86.977556 -376.55661)
			(xy 86.941587 -376.36934) (xy 86.913544 -376.180719) (xy 86.893478 -375.991084) (xy 86.881424 -375.800771)
			(xy 86.877404 -375.61012) (xy 0.509016 -375.61012) (xy 0.509016 -384.79984) (xy 14.086591 -384.79984)
			(xy 14.090616 -384.657648) (xy 14.102679 -384.515912) (xy 14.122742 -384.375086) (xy 14.15074 -384.23562)
			(xy 14.186584 -384.097961) (xy 14.230158 -383.962551) (xy 14.281323 -383.829823) (xy 14.339916 -383.700202)
			(xy 14.405747 -383.574104) (xy 14.478608 -383.451932) (xy 14.558263 -383.334078) (xy 14.644459 -383.220919)
			(xy 14.736918 -383.112817) (xy 14.835346 -383.01012) (xy 14.939425 -382.913156) (xy 15.048824 -382.822236)
			(xy 15.163192 -382.73765) (xy 15.282161 -382.65967) (xy 15.405352 -382.588546) (xy 15.532369 -382.524505)
			(xy 15.662806 -382.467753) (xy 15.796245 -382.418471) (xy 15.932258 -382.376817) (xy 16.07041 -382.342925)
			(xy 16.210259 -382.316904) (xy 16.351355 -382.298836) (xy 16.493247 -382.288779) (xy 16.635482 -382.286766)
			(xy 16.777602 -382.292803) (xy 16.919153 -382.306871) (xy 17.059682 -382.328925) (xy 17.198737 -382.358894)
			(xy 17.335875 -382.396682) (xy 17.470655 -382.442168) (xy 17.602646 -382.495206) (xy 17.731425 -382.555627)
			(xy 17.856579 -382.623236) (xy 17.977707 -382.697818) (xy 18.094423 -382.779134) (xy 18.206351 -382.866922)
			(xy 18.313133 -382.960902) (xy 18.414427 -383.060772) (xy 18.509908 -383.166214) (xy 18.599272 -383.276888)
			(xy 18.68223 -383.392441) (xy 18.758519 -383.512502) (xy 18.827893 -383.636687) (xy 18.89013 -383.764598)
			(xy 18.945031 -383.895825) (xy 18.992419 -384.029948) (xy 19.032144 -384.166537) (xy 19.064077 -384.305155)
			(xy 19.088118 -384.445357) (xy 19.104187 -384.586695) (xy 19.112235 -384.728716) (xy 19.112738 -384.79984)
			(xy 19.112235 -384.870964) (xy 19.104187 -385.012985) (xy 19.088118 -385.154323) (xy 19.064077 -385.294525)
			(xy 19.032144 -385.433143) (xy 18.992419 -385.569732) (xy 18.945031 -385.703855) (xy 18.89013 -385.835082)
			(xy 18.827893 -385.962993) (xy 18.758519 -386.087178) (xy 18.68223 -386.207239) (xy 18.599272 -386.322792)
			(xy 18.509908 -386.433466) (xy 18.414427 -386.538908) (xy 18.313133 -386.638778) (xy 18.206351 -386.732758)
			(xy 18.094423 -386.820546) (xy 17.977707 -386.901862) (xy 17.856579 -386.976444) (xy 17.731425 -387.044053)
			(xy 17.602646 -387.104474) (xy 17.470655 -387.157512) (xy 17.335875 -387.202998) (xy 17.198737 -387.240786)
			(xy 17.059682 -387.270755) (xy 16.919153 -387.292809) (xy 16.777602 -387.306877) (xy 16.635482 -387.312914)
			(xy 16.493247 -387.310901) (xy 16.351355 -387.300844) (xy 16.210259 -387.282776) (xy 16.07041 -387.256755)
			(xy 15.932258 -387.222863) (xy 15.796245 -387.181209) (xy 15.662806 -387.131927) (xy 15.532369 -387.075175)
			(xy 15.405352 -387.011134) (xy 15.282161 -386.94001) (xy 15.163192 -386.86203) (xy 15.048824 -386.777444)
			(xy 14.939425 -386.686524) (xy 14.835346 -386.58956) (xy 14.736918 -386.486863) (xy 14.644459 -386.378761)
			(xy 14.558263 -386.265602) (xy 14.478608 -386.147748) (xy 14.405747 -386.025576) (xy 14.339916 -385.899478)
			(xy 14.281323 -385.769857) (xy 14.230158 -385.637129) (xy 14.186584 -385.501719) (xy 14.15074 -385.36406)
			(xy 14.122742 -385.224594) (xy 14.102679 -385.083768) (xy 14.090616 -384.942032) (xy 14.086591 -384.79984)
			(xy 0.509016 -384.79984) (xy 0.509016 -403.413036) (xy 1.547863 -403.413036) (xy 1.547863 -403.2869)
			(xy 1.555783 -403.161012) (xy 1.571593 -403.03587) (xy 1.595228 -402.911967) (xy 1.626597 -402.789794)
			(xy 1.665575 -402.669831) (xy 1.712009 -402.552552) (xy 1.765716 -402.43842) (xy 1.826483 -402.327885)
			(xy 1.89407 -402.221385) (xy 1.968211 -402.119338) (xy 2.048614 -402.022148) (xy 2.13496 -401.930198)
			(xy 2.22691 -401.843852) (xy 2.3241 -401.763449) (xy 2.426147 -401.689308) (xy 2.532647 -401.621721)
			(xy 2.643182 -401.560954) (xy 2.757314 -401.507247) (xy 2.874593 -401.460813) (xy 2.994556 -401.421835)
			(xy 3.116729 -401.390466) (xy 3.240632 -401.366831) (xy 3.365774 -401.351021) (xy 3.491662 -401.343101)
			(xy 3.617798 -401.343101) (xy 3.743686 -401.351021) (xy 3.868828 -401.366831) (xy 3.992731 -401.390466)
			(xy 4.114904 -401.421835) (xy 4.234867 -401.460813) (xy 4.352146 -401.507247) (xy 4.466278 -401.560954)
			(xy 4.576813 -401.621721) (xy 4.683313 -401.689308) (xy 4.78536 -401.763449) (xy 4.88255 -401.843852)
			(xy 4.9745 -401.930198) (xy 5.060846 -402.022148) (xy 5.141249 -402.119338) (xy 5.21539 -402.221385)
			(xy 5.282977 -402.327885) (xy 5.343744 -402.43842) (xy 5.397451 -402.552552) (xy 5.443885 -402.669831)
			(xy 5.482863 -402.789794) (xy 5.514232 -402.911967) (xy 5.537867 -403.03587) (xy 5.553677 -403.161012)
			(xy 5.561597 -403.2869) (xy 5.562092 -403.349968) (xy 5.561597 -403.413036) (xy 12.977863 -403.413036)
			(xy 12.977863 -403.2869) (xy 12.985783 -403.161012) (xy 13.001593 -403.03587) (xy 13.025228 -402.911967)
			(xy 13.056597 -402.789794) (xy 13.095575 -402.669831) (xy 13.142009 -402.552552) (xy 13.195716 -402.43842)
			(xy 13.256483 -402.327885) (xy 13.32407 -402.221385) (xy 13.398211 -402.119338) (xy 13.478614 -402.022148)
			(xy 13.56496 -401.930198) (xy 13.65691 -401.843852) (xy 13.7541 -401.763449) (xy 13.856147 -401.689308)
			(xy 13.962647 -401.621721) (xy 14.073182 -401.560954) (xy 14.187314 -401.507247) (xy 14.304593 -401.460813)
			(xy 14.424556 -401.421835) (xy 14.546729 -401.390466) (xy 14.670632 -401.366831) (xy 14.795774 -401.351021)
			(xy 14.921662 -401.343101) (xy 15.047798 -401.343101) (xy 15.173686 -401.351021) (xy 15.298828 -401.366831)
			(xy 15.422731 -401.390466) (xy 15.544904 -401.421835) (xy 15.664867 -401.460813) (xy 15.782146 -401.507247)
			(xy 15.896278 -401.560954) (xy 16.006813 -401.621721) (xy 16.113313 -401.689308) (xy 16.21536 -401.763449)
			(xy 16.31255 -401.843852) (xy 16.4045 -401.930198) (xy 16.490846 -402.022148) (xy 16.571249 -402.119338)
			(xy 16.64539 -402.221385) (xy 16.712977 -402.327885) (xy 16.773744 -402.43842) (xy 16.827451 -402.552552)
			(xy 16.873885 -402.669831) (xy 16.912863 -402.789794) (xy 16.944232 -402.911967) (xy 16.967867 -403.03587)
			(xy 16.983677 -403.161012) (xy 16.991597 -403.2869) (xy 16.992092 -403.349968) (xy 16.991597 -403.413036)
			(xy 16.983677 -403.538924) (xy 16.967867 -403.664066) (xy 16.944232 -403.787969) (xy 16.912863 -403.910142)
			(xy 16.873885 -404.030105) (xy 16.827451 -404.147384) (xy 16.773744 -404.261516) (xy 16.712977 -404.372051)
			(xy 16.64539 -404.478551) (xy 16.571249 -404.580598) (xy 16.490846 -404.677788) (xy 16.4045 -404.769738)
			(xy 16.31255 -404.856084) (xy 16.21536 -404.936487) (xy 16.113313 -405.010628) (xy 16.006813 -405.078215)
			(xy 15.896278 -405.138982) (xy 15.782146 -405.192689) (xy 15.664867 -405.239123) (xy 15.544904 -405.278101)
			(xy 15.422731 -405.30947) (xy 15.298828 -405.333105) (xy 15.173686 -405.348915) (xy 15.047798 -405.356835)
			(xy 14.921662 -405.356835) (xy 14.795774 -405.348915) (xy 14.670632 -405.333105) (xy 14.546729 -405.30947)
			(xy 14.424556 -405.278101) (xy 14.304593 -405.239123) (xy 14.187314 -405.192689) (xy 14.073182 -405.138982)
			(xy 13.962647 -405.078215) (xy 13.856147 -405.010628) (xy 13.7541 -404.936487) (xy 13.65691 -404.856084)
			(xy 13.56496 -404.769738) (xy 13.478614 -404.677788) (xy 13.398211 -404.580598) (xy 13.32407 -404.478551)
			(xy 13.256483 -404.372051) (xy 13.195716 -404.261516) (xy 13.142009 -404.147384) (xy 13.095575 -404.030105)
			(xy 13.056597 -403.910142) (xy 13.025228 -403.787969) (xy 13.001593 -403.664066) (xy 12.985783 -403.538924)
			(xy 12.977863 -403.413036) (xy 5.561597 -403.413036) (xy 5.553677 -403.538924) (xy 5.537867 -403.664066)
			(xy 5.514232 -403.787969) (xy 5.482863 -403.910142) (xy 5.443885 -404.030105) (xy 5.397451 -404.147384)
			(xy 5.343744 -404.261516) (xy 5.282977 -404.372051) (xy 5.21539 -404.478551) (xy 5.141249 -404.580598)
			(xy 5.060846 -404.677788) (xy 4.9745 -404.769738) (xy 4.88255 -404.856084) (xy 4.78536 -404.936487)
			(xy 4.683313 -405.010628) (xy 4.576813 -405.078215) (xy 4.466278 -405.138982) (xy 4.352146 -405.192689)
			(xy 4.234867 -405.239123) (xy 4.114904 -405.278101) (xy 3.992731 -405.30947) (xy 3.868828 -405.333105)
			(xy 3.743686 -405.348915) (xy 3.617798 -405.356835) (xy 3.491662 -405.356835) (xy 3.365774 -405.348915)
			(xy 3.240632 -405.333105) (xy 3.116729 -405.30947) (xy 2.994556 -405.278101) (xy 2.874593 -405.239123)
			(xy 2.757314 -405.192689) (xy 2.643182 -405.138982) (xy 2.532647 -405.078215) (xy 2.426147 -405.010628)
			(xy 2.3241 -404.936487) (xy 2.22691 -404.856084) (xy 2.13496 -404.769738) (xy 2.048614 -404.677788)
			(xy 1.968211 -404.580598) (xy 1.89407 -404.478551) (xy 1.826483 -404.372051) (xy 1.765716 -404.261516)
			(xy 1.712009 -404.147384) (xy 1.665575 -404.030105) (xy 1.626597 -403.910142) (xy 1.595228 -403.787969)
			(xy 1.571593 -403.664066) (xy 1.555783 -403.538924) (xy 1.547863 -403.413036) (xy 0.509016 -403.413036)
			(xy 0.509016 -406.96007) (xy 39.818063 -406.96007) (xy 39.82207 -406.844046) (xy 39.834072 -406.728574)
			(xy 39.854012 -406.614206) (xy 39.881795 -406.501486) (xy 39.917289 -406.390952) (xy 39.960324 -406.283129)
			(xy 40.010695 -406.178532) (xy 40.068162 -406.07766) (xy 40.132452 -405.980993) (xy 40.203257 -405.888992)
			(xy 40.280241 -405.802095) (xy 40.363037 -405.720716) (xy 40.45125 -405.645243) (xy 40.54446 -405.576036)
			(xy 40.642223 -405.513424) (xy 40.744072 -405.457707) (xy 40.849522 -405.409149) (xy 40.958071 -405.367981)
			(xy 41.069202 -405.334401) (xy 41.182385 -405.308568) (xy 41.29708 -405.290605) (xy 41.412742 -405.280597)
			(xy 41.528818 -405.278594) (xy 41.644756 -405.284603) (xy 41.760003 -405.298596) (xy 41.874009 -405.320507)
			(xy 41.986233 -405.350232) (xy 42.096139 -405.387628) (xy 42.203202 -405.432517) (xy 42.306914 -405.484686)
			(xy 42.406779 -405.543886) (xy 42.502322 -405.609835) (xy 42.593088 -405.682218) (xy 42.678643 -405.760691)
			(xy 42.758581 -405.844879) (xy 42.83252 -405.934381) (xy 42.900108 -406.028772) (xy 42.961022 -406.1276)
			(xy 43.014974 -406.230396) (xy 43.061704 -406.336669) (xy 43.100992 -406.445913) (xy 43.132649 -406.557606)
			(xy 43.156525 -406.671218) (xy 43.172506 -406.786206) (xy 43.180515 -406.902023) (xy 43.181016 -406.96007)
			(xy 43.180515 -407.018117) (xy 43.172506 -407.133934) (xy 43.156525 -407.248922) (xy 43.132649 -407.362534)
			(xy 43.100992 -407.474227) (xy 43.061704 -407.583471) (xy 43.014974 -407.689744) (xy 42.961022 -407.79254)
			(xy 42.900108 -407.891368) (xy 42.83252 -407.985759) (xy 42.758581 -408.075261) (xy 42.678643 -408.159449)
			(xy 42.593088 -408.237922) (xy 42.502604 -408.31008) (xy 93.154506 -408.31008) (xy 93.158522 -408.19381)
			(xy 93.170549 -408.078095) (xy 93.190531 -407.963485) (xy 93.218373 -407.850526) (xy 93.253942 -407.739758)
			(xy 93.297068 -407.631707) (xy 93.347545 -407.526889) (xy 93.405134 -407.425804) (xy 93.46956 -407.328932)
			(xy 93.540515 -407.236736) (xy 93.617662 -407.149655) (xy 93.700633 -407.068104) (xy 93.789033 -406.992472)
			(xy 93.88244 -406.923118) (xy 93.980409 -406.860375) (xy 94.082473 -406.804539) (xy 94.188147 -406.755878)
			(xy 94.296926 -406.714624) (xy 94.408291 -406.680973) (xy 94.521714 -406.655085) (xy 94.636651 -406.637084)
			(xy 94.752557 -406.627055) (xy 94.868879 -406.625047) (xy 94.985062 -406.631069) (xy 95.100553 -406.645092)
			(xy 95.214801 -406.66705) (xy 95.327262 -406.696837) (xy 95.4374 -406.734312) (xy 95.54469 -406.779297)
			(xy 95.648621 -406.831576) (xy 95.748697 -406.890901) (xy 95.844443 -406.956989) (xy 95.9354 -407.029525)
			(xy 96.021136 -407.108164) (xy 96.101243 -407.19253) (xy 96.175339 -407.282222) (xy 96.243069 -407.376812)
			(xy 96.304113 -407.47585) (xy 96.358178 -407.578863) (xy 96.405008 -407.68536) (xy 96.444379 -407.794835)
			(xy 96.476103 -407.906765) (xy 96.500029 -408.020617) (xy 96.516043 -408.135849) (xy 96.52407 -408.251911)
			(xy 96.524572 -408.31008) (xy 96.52407 -408.368249) (xy 96.516043 -408.484311) (xy 96.500029 -408.599543)
			(xy 96.476103 -408.713395) (xy 96.444379 -408.825325) (xy 96.405008 -408.9348) (xy 96.358178 -409.041297)
			(xy 96.304113 -409.14431) (xy 96.243069 -409.243348) (xy 96.175339 -409.337938) (xy 96.101243 -409.42763)
			(xy 96.021136 -409.511996) (xy 95.9354 -409.590635) (xy 95.844443 -409.663171) (xy 95.748697 -409.729259)
			(xy 95.648621 -409.788584) (xy 95.54469 -409.840863) (xy 95.4374 -409.885848) (xy 95.327262 -409.923323)
			(xy 95.214801 -409.95311) (xy 95.100553 -409.975068) (xy 94.985062 -409.989091) (xy 94.868879 -409.995113)
			(xy 94.752557 -409.993105) (xy 94.636651 -409.983076) (xy 94.521714 -409.965075) (xy 94.408291 -409.939187)
			(xy 94.296926 -409.905536) (xy 94.188147 -409.864282) (xy 94.082473 -409.815621) (xy 93.980409 -409.759785)
			(xy 93.88244 -409.697042) (xy 93.789033 -409.627688) (xy 93.700633 -409.552056) (xy 93.617662 -409.470505)
			(xy 93.540515 -409.383424) (xy 93.46956 -409.291228) (xy 93.405134 -409.194356) (xy 93.347545 -409.093271)
			(xy 93.297068 -408.988453) (xy 93.253942 -408.880402) (xy 93.218373 -408.769634) (xy 93.190531 -408.656675)
			(xy 93.170549 -408.542065) (xy 93.158522 -408.42635) (xy 93.154506 -408.31008) (xy 42.502604 -408.31008)
			(xy 42.502322 -408.310305) (xy 42.406779 -408.376254) (xy 42.306914 -408.435454) (xy 42.203202 -408.487623)
			(xy 42.096139 -408.532512) (xy 41.986233 -408.569908) (xy 41.874009 -408.599633) (xy 41.760003 -408.621544)
			(xy 41.644756 -408.635537) (xy 41.528818 -408.641546) (xy 41.412742 -408.639543) (xy 41.29708 -408.629535)
			(xy 41.182385 -408.611572) (xy 41.069202 -408.585739) (xy 40.958071 -408.552159) (xy 40.849522 -408.510991)
			(xy 40.744072 -408.462433) (xy 40.642223 -408.406716) (xy 40.54446 -408.344104) (xy 40.45125 -408.274897)
			(xy 40.363037 -408.199424) (xy 40.280241 -408.118045) (xy 40.203257 -408.031148) (xy 40.132452 -407.939147)
			(xy 40.068162 -407.84248) (xy 40.010695 -407.741608) (xy 39.960324 -407.637011) (xy 39.917289 -407.529188)
			(xy 39.881795 -407.418654) (xy 39.854012 -407.305934) (xy 39.834072 -407.191566) (xy 39.82207 -407.076094)
			(xy 39.818063 -406.96007) (xy 0.509016 -406.96007) (xy 0.509016 -420.06012) (xy 86.877404 -420.06012)
			(xy 86.881424 -419.869469) (xy 86.893478 -419.679156) (xy 86.913544 -419.489521) (xy 86.941587 -419.3009)
			(xy 86.977556 -419.11363) (xy 87.021388 -418.928042) (xy 87.073005 -418.744467) (xy 87.132315 -418.563231)
			(xy 87.199213 -418.384656) (xy 87.273579 -418.209061) (xy 87.355281 -418.036756) (xy 87.444175 -417.868049)
			(xy 87.540101 -417.703239) (xy 87.64289 -417.54262) (xy 87.752359 -417.386477) (xy 87.868313 -417.235088)
			(xy 87.990547 -417.088721) (xy 88.118841 -416.947637) (xy 88.252969 -416.812088) (xy 88.392693 -416.682313)
			(xy 88.537763 -416.558543) (xy 88.687921 -416.441) (xy 88.842902 -416.329891) (xy 89.002429 -416.225414)
			(xy 89.166218 -416.127755) (xy 89.333978 -416.037088) (xy 89.505412 -415.953574) (xy 89.680214 -415.877361)
			(xy 89.858073 -415.808585) (xy 90.038674 -415.747367) (xy 90.221694 -415.693818) (xy 90.40681 -415.648032)
			(xy 90.593691 -415.61009) (xy 90.782006 -415.580061) (xy 90.971419 -415.557996) (xy 91.161593 -415.543937)
			(xy 91.352192 -415.537907) (xy 91.542875 -415.539917) (xy 91.733304 -415.549964) (xy 91.92314 -415.56803)
			(xy 92.112046 -415.594083) (xy 92.299685 -415.628076) (xy 92.485725 -415.669949) (xy 92.669834 -415.719628)
			(xy 92.851685 -415.777024) (xy 93.030955 -415.842035) (xy 93.207325 -415.914546) (xy 93.380481 -415.994427)
			(xy 93.550116 -416.081537) (xy 93.715928 -416.175721) (xy 93.877622 -416.276812) (xy 94.03491 -416.384628)
			(xy 94.187513 -416.49898) (xy 94.335161 -416.619663) (xy 94.477589 -416.746464) (xy 94.614545 -416.879155)
			(xy 94.745786 -417.017503) (xy 94.871078 -417.16126) (xy 94.990198 -417.310171) (xy 95.102934 -417.463972)
			(xy 95.209087 -417.622388) (xy 95.308467 -417.785139) (xy 95.400897 -417.951934) (xy 95.486214 -418.122478)
			(xy 95.564266 -418.296466) (xy 95.634913 -418.473591) (xy 95.698031 -418.653536) (xy 95.753507 -418.835982)
			(xy 95.801242 -419.020605) (xy 95.841152 -419.207075) (xy 95.873165 -419.395063) (xy 95.897225 -419.584233)
			(xy 95.913288 -419.774249) (xy 95.921327 -419.964773) (xy 95.92183 -420.06012) (xy 95.921327 -420.155467)
			(xy 95.913288 -420.345991) (xy 95.897225 -420.536007) (xy 95.873165 -420.725177) (xy 95.841152 -420.913165)
			(xy 95.801242 -421.099635) (xy 95.753507 -421.284258) (xy 95.698031 -421.466704) (xy 95.634913 -421.646649)
			(xy 95.564266 -421.823774) (xy 95.486214 -421.997762) (xy 95.400897 -422.168306) (xy 95.308467 -422.335101)
			(xy 95.209087 -422.497852) (xy 95.102934 -422.656268) (xy 94.990198 -422.810069) (xy 94.871078 -422.95898)
			(xy 94.745786 -423.102737) (xy 94.614545 -423.241085) (xy 94.477589 -423.373776) (xy 94.335161 -423.500577)
			(xy 94.187513 -423.62126) (xy 94.03491 -423.735612) (xy 93.877622 -423.843428) (xy 93.715928 -423.944519)
			(xy 93.550116 -424.038703) (xy 93.380481 -424.125813) (xy 93.207325 -424.205694) (xy 93.030955 -424.278205)
			(xy 92.851685 -424.343216) (xy 92.669834 -424.400612) (xy 92.485725 -424.450291) (xy 92.299685 -424.492164)
			(xy 92.112046 -424.526157) (xy 91.92314 -424.55221) (xy 91.733304 -424.570276) (xy 91.542875 -424.580323)
			(xy 91.352192 -424.582333) (xy 91.161593 -424.576303) (xy 90.971419 -424.562244) (xy 90.782006 -424.540179)
			(xy 90.593691 -424.51015) (xy 90.40681 -424.472208) (xy 90.221694 -424.426422) (xy 90.038674 -424.372873)
			(xy 89.858073 -424.311655) (xy 89.680214 -424.242879) (xy 89.505412 -424.166666) (xy 89.333978 -424.083152)
			(xy 89.166218 -423.992485) (xy 89.002429 -423.894826) (xy 88.842902 -423.790349) (xy 88.687921 -423.67924)
			(xy 88.537763 -423.561697) (xy 88.392693 -423.437927) (xy 88.252969 -423.308152) (xy 88.118841 -423.172603)
			(xy 87.990547 -423.031519) (xy 87.868313 -422.885152) (xy 87.752359 -422.733763) (xy 87.64289 -422.57762)
			(xy 87.540101 -422.417001) (xy 87.444175 -422.252191) (xy 87.355281 -422.083484) (xy 87.273579 -421.911179)
			(xy 87.199213 -421.735584) (xy 87.132315 -421.557009) (xy 87.073005 -421.375773) (xy 87.021388 -421.192198)
			(xy 86.977556 -421.00661) (xy 86.941587 -420.81934) (xy 86.913544 -420.630719) (xy 86.893478 -420.441084)
			(xy 86.881424 -420.250771) (xy 86.877404 -420.06012) (xy 0.509016 -420.06012) (xy 0.509016 -430.150016)
			(xy 75.486519 -430.150016) (xy 75.490544 -430.007824) (xy 75.502607 -429.866088) (xy 75.52267 -429.725262)
			(xy 75.550668 -429.585796) (xy 75.586512 -429.448137) (xy 75.630086 -429.312727) (xy 75.681251 -429.179999)
			(xy 75.739844 -429.050378) (xy 75.805675 -428.92428) (xy 75.878536 -428.802108) (xy 75.958191 -428.684254)
			(xy 76.044387 -428.571095) (xy 76.136846 -428.462993) (xy 76.235274 -428.360296) (xy 76.339353 -428.263332)
			(xy 76.448752 -428.172412) (xy 76.56312 -428.087826) (xy 76.682089 -428.009846) (xy 76.80528 -427.938722)
			(xy 76.932297 -427.874681) (xy 77.062734 -427.817929) (xy 77.196173 -427.768647) (xy 77.332186 -427.726993)
			(xy 77.470338 -427.693101) (xy 77.610187 -427.66708) (xy 77.751283 -427.649012) (xy 77.893175 -427.638955)
			(xy 78.03541 -427.636942) (xy 78.17753 -427.642979) (xy 78.319081 -427.657047) (xy 78.45961 -427.679101)
			(xy 78.598665 -427.70907) (xy 78.735803 -427.746858) (xy 78.870583 -427.792344) (xy 79.002574 -427.845382)
			(xy 79.131353 -427.905803) (xy 79.256507 -427.973412) (xy 79.377635 -428.047994) (xy 79.494351 -428.12931)
			(xy 79.606279 -428.217098) (xy 79.713061 -428.311078) (xy 79.814355 -428.410948) (xy 79.909836 -428.51639)
			(xy 79.9992 -428.627064) (xy 80.082158 -428.742617) (xy 80.158447 -428.862678) (xy 80.227821 -428.986863)
			(xy 80.290058 -429.114774) (xy 80.344959 -429.246001) (xy 80.392347 -429.380124) (xy 80.432072 -429.516713)
			(xy 80.464005 -429.655331) (xy 80.488046 -429.795533) (xy 80.504115 -429.936871) (xy 80.512163 -430.078892)
			(xy 80.512666 -430.150016) (xy 80.512163 -430.22114) (xy 80.504115 -430.363161) (xy 80.488046 -430.504499)
			(xy 80.464005 -430.644701) (xy 80.432072 -430.783319) (xy 80.392347 -430.919908) (xy 80.344959 -431.054031)
			(xy 80.290058 -431.185258) (xy 80.227821 -431.313169) (xy 80.158447 -431.437354) (xy 80.082158 -431.557415)
			(xy 79.9992 -431.672968) (xy 79.909836 -431.783642) (xy 79.814355 -431.889084) (xy 79.713061 -431.988954)
			(xy 79.606279 -432.082934) (xy 79.494351 -432.170722) (xy 79.377635 -432.252038) (xy 79.256507 -432.32662)
			(xy 79.131353 -432.394229) (xy 79.002574 -432.45465) (xy 78.870583 -432.507688) (xy 78.735803 -432.553174)
			(xy 78.598665 -432.590962) (xy 78.45961 -432.620931) (xy 78.319081 -432.642985) (xy 78.17753 -432.657053)
			(xy 78.03541 -432.66309) (xy 77.893175 -432.661077) (xy 77.751283 -432.65102) (xy 77.610187 -432.632952)
			(xy 77.470338 -432.606931) (xy 77.332186 -432.573039) (xy 77.196173 -432.531385) (xy 77.062734 -432.482103)
			(xy 76.932297 -432.425351) (xy 76.80528 -432.36131) (xy 76.682089 -432.290186) (xy 76.56312 -432.212206)
			(xy 76.448752 -432.12762) (xy 76.339353 -432.0367) (xy 76.235274 -431.939736) (xy 76.136846 -431.837039)
			(xy 76.044387 -431.728937) (xy 75.958191 -431.615778) (xy 75.878536 -431.497924) (xy 75.805675 -431.375752)
			(xy 75.739844 -431.249654) (xy 75.681251 -431.120033) (xy 75.630086 -430.987305) (xy 75.586512 -430.851895)
			(xy 75.550668 -430.714236) (xy 75.52267 -430.57477) (xy 75.502607 -430.433944) (xy 75.490544 -430.292208)
			(xy 75.486519 -430.150016) (xy 0.509016 -430.150016) (xy 0.509016 -451.41007) (xy 39.818063 -451.41007)
			(xy 39.82207 -451.294046) (xy 39.834072 -451.178574) (xy 39.854012 -451.064206) (xy 39.881795 -450.951486)
			(xy 39.917289 -450.840952) (xy 39.960324 -450.733129) (xy 40.010695 -450.628532) (xy 40.068162 -450.52766)
			(xy 40.132452 -450.430993) (xy 40.203257 -450.338992) (xy 40.280241 -450.252095) (xy 40.363037 -450.170716)
			(xy 40.45125 -450.095243) (xy 40.54446 -450.026036) (xy 40.642223 -449.963424) (xy 40.744072 -449.907707)
			(xy 40.849522 -449.859149) (xy 40.958071 -449.817981) (xy 41.069202 -449.784401) (xy 41.182385 -449.758568)
			(xy 41.29708 -449.740605) (xy 41.412742 -449.730597) (xy 41.528818 -449.728594) (xy 41.644756 -449.734603)
			(xy 41.760003 -449.748596) (xy 41.874009 -449.770507) (xy 41.986233 -449.800232) (xy 42.096139 -449.837628)
			(xy 42.203202 -449.882517) (xy 42.306914 -449.934686) (xy 42.406779 -449.993886) (xy 42.502322 -450.059835)
			(xy 42.593088 -450.132218) (xy 42.678643 -450.210691) (xy 42.758581 -450.294879) (xy 42.83252 -450.384381)
			(xy 42.900108 -450.478772) (xy 42.961022 -450.5776) (xy 43.014974 -450.680396) (xy 43.061704 -450.786669)
			(xy 43.100992 -450.895913) (xy 43.132649 -451.007606) (xy 43.156525 -451.121218) (xy 43.172506 -451.236206)
			(xy 43.180515 -451.352023) (xy 43.181016 -451.41007) (xy 43.180515 -451.468117) (xy 43.172506 -451.583934)
			(xy 43.156525 -451.698922) (xy 43.132649 -451.812534) (xy 43.100992 -451.924227) (xy 43.061704 -452.033471)
			(xy 43.014974 -452.139744) (xy 42.961022 -452.24254) (xy 42.900108 -452.341368) (xy 42.83252 -452.435759)
			(xy 42.758581 -452.525261) (xy 42.678643 -452.609449) (xy 42.593088 -452.687922) (xy 42.502604 -452.76008)
			(xy 93.154506 -452.76008) (xy 93.158522 -452.64381) (xy 93.170549 -452.528095) (xy 93.190531 -452.413485)
			(xy 93.218373 -452.300526) (xy 93.253942 -452.189758) (xy 93.297068 -452.081707) (xy 93.347545 -451.976889)
			(xy 93.405134 -451.875804) (xy 93.46956 -451.778932) (xy 93.540515 -451.686736) (xy 93.617662 -451.599655)
			(xy 93.700633 -451.518104) (xy 93.789033 -451.442472) (xy 93.88244 -451.373118) (xy 93.980409 -451.310375)
			(xy 94.082473 -451.254539) (xy 94.188147 -451.205878) (xy 94.296926 -451.164624) (xy 94.408291 -451.130973)
			(xy 94.521714 -451.105085) (xy 94.636651 -451.087084) (xy 94.752557 -451.077055) (xy 94.868879 -451.075047)
			(xy 94.985062 -451.081069) (xy 95.100553 -451.095092) (xy 95.214801 -451.11705) (xy 95.327262 -451.146837)
			(xy 95.4374 -451.184312) (xy 95.54469 -451.229297) (xy 95.648621 -451.281576) (xy 95.748697 -451.340901)
			(xy 95.844443 -451.406989) (xy 95.9354 -451.479525) (xy 96.021136 -451.558164) (xy 96.101243 -451.64253)
			(xy 96.175339 -451.732222) (xy 96.243069 -451.826812) (xy 96.304113 -451.92585) (xy 96.358178 -452.028863)
			(xy 96.405008 -452.13536) (xy 96.444379 -452.244835) (xy 96.476103 -452.356765) (xy 96.500029 -452.470617)
			(xy 96.516043 -452.585849) (xy 96.52407 -452.701911) (xy 96.524572 -452.76008) (xy 96.52407 -452.818249)
			(xy 96.516043 -452.934311) (xy 96.500029 -453.049543) (xy 96.476103 -453.163395) (xy 96.444379 -453.275325)
			(xy 96.405008 -453.3848) (xy 96.358178 -453.491297) (xy 96.304113 -453.59431) (xy 96.243069 -453.693348)
			(xy 96.175339 -453.787938) (xy 96.101243 -453.87763) (xy 96.021136 -453.961996) (xy 95.9354 -454.040635)
			(xy 95.844443 -454.113171) (xy 95.748697 -454.179259) (xy 95.648621 -454.238584) (xy 95.54469 -454.290863)
			(xy 95.4374 -454.335848) (xy 95.327262 -454.373323) (xy 95.214801 -454.40311) (xy 95.100553 -454.425068)
			(xy 94.985062 -454.439091) (xy 94.868879 -454.445113) (xy 94.752557 -454.443105) (xy 94.636651 -454.433076)
			(xy 94.521714 -454.415075) (xy 94.408291 -454.389187) (xy 94.296926 -454.355536) (xy 94.188147 -454.314282)
			(xy 94.082473 -454.265621) (xy 93.980409 -454.209785) (xy 93.88244 -454.147042) (xy 93.789033 -454.077688)
			(xy 93.700633 -454.002056) (xy 93.617662 -453.920505) (xy 93.540515 -453.833424) (xy 93.46956 -453.741228)
			(xy 93.405134 -453.644356) (xy 93.347545 -453.543271) (xy 93.297068 -453.438453) (xy 93.253942 -453.330402)
			(xy 93.218373 -453.219634) (xy 93.190531 -453.106675) (xy 93.170549 -452.992065) (xy 93.158522 -452.87635)
			(xy 93.154506 -452.76008) (xy 42.502604 -452.76008) (xy 42.502322 -452.760305) (xy 42.406779 -452.826254)
			(xy 42.306914 -452.885454) (xy 42.203202 -452.937623) (xy 42.096139 -452.982512) (xy 41.986233 -453.019908)
			(xy 41.874009 -453.049633) (xy 41.760003 -453.071544) (xy 41.644756 -453.085537) (xy 41.528818 -453.091546)
			(xy 41.412742 -453.089543) (xy 41.29708 -453.079535) (xy 41.182385 -453.061572) (xy 41.069202 -453.035739)
			(xy 40.958071 -453.002159) (xy 40.849522 -452.960991) (xy 40.744072 -452.912433) (xy 40.642223 -452.856716)
			(xy 40.54446 -452.794104) (xy 40.45125 -452.724897) (xy 40.363037 -452.649424) (xy 40.280241 -452.568045)
			(xy 40.203257 -452.481148) (xy 40.132452 -452.389147) (xy 40.068162 -452.29248) (xy 40.010695 -452.191608)
			(xy 39.960324 -452.087011) (xy 39.917289 -451.979188) (xy 39.881795 -451.868654) (xy 39.854012 -451.755934)
			(xy 39.834072 -451.641566) (xy 39.82207 -451.526094) (xy 39.818063 -451.41007) (xy 0.509016 -451.41007)
			(xy 0.509016 -464.509866) (xy 86.877404 -464.509866) (xy 86.881424 -464.319215) (xy 86.893478 -464.128902)
			(xy 86.913544 -463.939267) (xy 86.941587 -463.750646) (xy 86.977556 -463.563376) (xy 87.021388 -463.377788)
			(xy 87.073005 -463.194213) (xy 87.132315 -463.012977) (xy 87.199213 -462.834402) (xy 87.273579 -462.658807)
			(xy 87.355281 -462.486502) (xy 87.444175 -462.317795) (xy 87.540101 -462.152985) (xy 87.64289 -461.992366)
			(xy 87.752359 -461.836223) (xy 87.868313 -461.684834) (xy 87.990547 -461.538467) (xy 88.118841 -461.397383)
			(xy 88.252969 -461.261834) (xy 88.392693 -461.132059) (xy 88.537763 -461.008289) (xy 88.687921 -460.890746)
			(xy 88.842902 -460.779637) (xy 89.002429 -460.67516) (xy 89.166218 -460.577501) (xy 89.333978 -460.486834)
			(xy 89.505412 -460.40332) (xy 89.680214 -460.327107) (xy 89.858073 -460.258331) (xy 90.038674 -460.197113)
			(xy 90.221694 -460.143564) (xy 90.40681 -460.097778) (xy 90.593691 -460.059836) (xy 90.782006 -460.029807)
			(xy 90.971419 -460.007742) (xy 91.161593 -459.993683) (xy 91.352192 -459.987653) (xy 91.542875 -459.989663)
			(xy 91.733304 -459.99971) (xy 91.92314 -460.017776) (xy 92.112046 -460.043829) (xy 92.299685 -460.077822)
			(xy 92.485725 -460.119695) (xy 92.669834 -460.169374) (xy 92.851685 -460.22677) (xy 93.030955 -460.291781)
			(xy 93.207325 -460.364292) (xy 93.380481 -460.444173) (xy 93.550116 -460.531283) (xy 93.715928 -460.625467)
			(xy 93.877622 -460.726558) (xy 94.03491 -460.834374) (xy 94.187513 -460.948726) (xy 94.335161 -461.069409)
			(xy 94.477589 -461.19621) (xy 94.614545 -461.328901) (xy 94.745786 -461.467249) (xy 94.871078 -461.611006)
			(xy 94.990198 -461.759917) (xy 95.102934 -461.913718) (xy 95.209087 -462.072134) (xy 95.308467 -462.234885)
			(xy 95.400897 -462.40168) (xy 95.486214 -462.572224) (xy 95.564266 -462.746212) (xy 95.634913 -462.923337)
			(xy 95.698031 -463.103282) (xy 95.753507 -463.285728) (xy 95.801242 -463.470351) (xy 95.841152 -463.656821)
			(xy 95.873165 -463.844809) (xy 95.897225 -464.033979) (xy 95.913288 -464.223995) (xy 95.921327 -464.414519)
			(xy 95.92183 -464.509866) (xy 95.921327 -464.605213) (xy 95.913288 -464.795737) (xy 95.897225 -464.985753)
			(xy 95.873165 -465.174923) (xy 95.841152 -465.362911) (xy 95.801242 -465.549381) (xy 95.753507 -465.734004)
			(xy 95.698031 -465.91645) (xy 95.634913 -466.096395) (xy 95.564266 -466.27352) (xy 95.486214 -466.447508)
			(xy 95.400897 -466.618052) (xy 95.308467 -466.784847) (xy 95.209087 -466.947598) (xy 95.102934 -467.106014)
			(xy 94.990198 -467.259815) (xy 94.871078 -467.408726) (xy 94.745786 -467.552483) (xy 94.614545 -467.690831)
			(xy 94.477589 -467.823522) (xy 94.335161 -467.950323) (xy 94.187513 -468.071006) (xy 94.03491 -468.185358)
			(xy 93.877622 -468.293174) (xy 93.715928 -468.394265) (xy 93.550116 -468.488449) (xy 93.380481 -468.575559)
			(xy 93.207325 -468.65544) (xy 93.030955 -468.727951) (xy 92.851685 -468.792962) (xy 92.669834 -468.850358)
			(xy 92.485725 -468.900037) (xy 92.299685 -468.94191) (xy 92.112046 -468.975903) (xy 91.92314 -469.001956)
			(xy 91.733304 -469.020022) (xy 91.542875 -469.030069) (xy 91.352192 -469.032079) (xy 91.161593 -469.026049)
			(xy 90.971419 -469.01199) (xy 90.782006 -468.989925) (xy 90.593691 -468.959896) (xy 90.40681 -468.921954)
			(xy 90.221694 -468.876168) (xy 90.038674 -468.822619) (xy 89.858073 -468.761401) (xy 89.680214 -468.692625)
			(xy 89.505412 -468.616412) (xy 89.333978 -468.532898) (xy 89.166218 -468.442231) (xy 89.002429 -468.344572)
			(xy 88.842902 -468.240095) (xy 88.687921 -468.128986) (xy 88.537763 -468.011443) (xy 88.392693 -467.887673)
			(xy 88.252969 -467.757898) (xy 88.118841 -467.622349) (xy 87.990547 -467.481265) (xy 87.868313 -467.334898)
			(xy 87.752359 -467.183509) (xy 87.64289 -467.027366) (xy 87.540101 -466.866747) (xy 87.444175 -466.701937)
			(xy 87.355281 -466.53323) (xy 87.273579 -466.360925) (xy 87.199213 -466.18533) (xy 87.132315 -466.006755)
			(xy 87.073005 -465.825519) (xy 87.021388 -465.641944) (xy 86.977556 -465.456356) (xy 86.941587 -465.269086)
			(xy 86.913544 -465.080465) (xy 86.893478 -464.89083) (xy 86.881424 -464.700517) (xy 86.877404 -464.509866)
			(xy 0.509016 -464.509866) (xy 0.509016 -473.69984) (xy 14.086591 -473.69984) (xy 14.090616 -473.557648)
			(xy 14.102679 -473.415912) (xy 14.122742 -473.275086) (xy 14.15074 -473.13562) (xy 14.186584 -472.997961)
			(xy 14.230158 -472.862551) (xy 14.281323 -472.729823) (xy 14.339916 -472.600202) (xy 14.405747 -472.474104)
			(xy 14.478608 -472.351932) (xy 14.558263 -472.234078) (xy 14.644459 -472.120919) (xy 14.736918 -472.012817)
			(xy 14.835346 -471.91012) (xy 14.939425 -471.813156) (xy 15.048824 -471.722236) (xy 15.163192 -471.63765)
			(xy 15.282161 -471.55967) (xy 15.405352 -471.488546) (xy 15.532369 -471.424505) (xy 15.662806 -471.367753)
			(xy 15.796245 -471.318471) (xy 15.932258 -471.276817) (xy 16.07041 -471.242925) (xy 16.210259 -471.216904)
			(xy 16.351355 -471.198836) (xy 16.493247 -471.188779) (xy 16.635482 -471.186766) (xy 16.777602 -471.192803)
			(xy 16.919153 -471.206871) (xy 17.059682 -471.228925) (xy 17.198737 -471.258894) (xy 17.335875 -471.296682)
			(xy 17.470655 -471.342168) (xy 17.602646 -471.395206) (xy 17.731425 -471.455627) (xy 17.856579 -471.523236)
			(xy 17.977707 -471.597818) (xy 18.094423 -471.679134) (xy 18.206351 -471.766922) (xy 18.313133 -471.860902)
			(xy 18.414427 -471.960772) (xy 18.509908 -472.066214) (xy 18.599272 -472.176888) (xy 18.68223 -472.292441)
			(xy 18.758519 -472.412502) (xy 18.827893 -472.536687) (xy 18.89013 -472.664598) (xy 18.945031 -472.795825)
			(xy 18.992419 -472.929948) (xy 19.032144 -473.066537) (xy 19.064077 -473.205155) (xy 19.088118 -473.345357)
			(xy 19.104187 -473.486695) (xy 19.112235 -473.628716) (xy 19.112738 -473.69984) (xy 19.112235 -473.770964)
			(xy 19.104187 -473.912985) (xy 19.088118 -474.054323) (xy 19.064077 -474.194525) (xy 19.032144 -474.333143)
			(xy 18.992419 -474.469732) (xy 18.945031 -474.603855) (xy 18.89013 -474.735082) (xy 18.827893 -474.862993)
			(xy 18.758519 -474.987178) (xy 18.68223 -475.107239) (xy 18.599272 -475.222792) (xy 18.509908 -475.333466)
			(xy 18.414427 -475.438908) (xy 18.313133 -475.538778) (xy 18.206351 -475.632758) (xy 18.094423 -475.720546)
			(xy 17.977707 -475.801862) (xy 17.856579 -475.876444) (xy 17.731425 -475.944053) (xy 17.602646 -476.004474)
			(xy 17.470655 -476.057512) (xy 17.335875 -476.102998) (xy 17.198737 -476.140786) (xy 17.059682 -476.170755)
			(xy 16.919153 -476.192809) (xy 16.777602 -476.206877) (xy 16.635482 -476.212914) (xy 16.493247 -476.210901)
			(xy 16.351355 -476.200844) (xy 16.210259 -476.182776) (xy 16.07041 -476.156755) (xy 15.932258 -476.122863)
			(xy 15.796245 -476.081209) (xy 15.662806 -476.031927) (xy 15.532369 -475.975175) (xy 15.405352 -475.911134)
			(xy 15.282161 -475.84001) (xy 15.163192 -475.76203) (xy 15.048824 -475.677444) (xy 14.939425 -475.586524)
			(xy 14.835346 -475.48956) (xy 14.736918 -475.386863) (xy 14.644459 -475.278761) (xy 14.558263 -475.165602)
			(xy 14.478608 -475.047748) (xy 14.405747 -474.925576) (xy 14.339916 -474.799478) (xy 14.281323 -474.669857)
			(xy 14.230158 -474.537129) (xy 14.186584 -474.401719) (xy 14.15074 -474.26406) (xy 14.122742 -474.124594)
			(xy 14.102679 -473.983768) (xy 14.090616 -473.842032) (xy 14.086591 -473.69984) (xy 0.509016 -473.69984)
			(xy 0.509016 -478.795334) (xy 74.887836 -478.795334) (xy 74.887836 -477.804734) (xy 74.888335 -477.725886)
			(xy 74.896323 -477.568392) (xy 74.912276 -477.411504) (xy 74.936156 -477.255626) (xy 74.9679 -477.101158)
			(xy 75.007427 -476.948495) (xy 75.054636 -476.798031) (xy 75.109405 -476.650151) (xy 75.171593 -476.505234)
			(xy 75.241042 -476.363653) (xy 75.317572 -476.225772) (xy 75.400988 -476.091944) (xy 75.491075 -475.962512)
			(xy 75.587602 -475.83781) (xy 75.690321 -475.718156) (xy 75.798969 -475.603859) (xy 75.913266 -475.495211)
			(xy 76.03292 -475.392492) (xy 76.157622 -475.295965) (xy 76.287054 -475.205878) (xy 76.420882 -475.122462)
			(xy 76.558763 -475.045932) (xy 76.700344 -474.976483) (xy 76.845261 -474.914295) (xy 76.993141 -474.859526)
			(xy 77.143605 -474.812317) (xy 77.296268 -474.77279) (xy 77.450736 -474.741046) (xy 77.606614 -474.717166)
			(xy 77.763502 -474.701213) (xy 77.920996 -474.693225) (xy 78.078692 -474.693225) (xy 78.236186 -474.701213)
			(xy 78.393074 -474.717166) (xy 78.548952 -474.741046) (xy 78.70342 -474.77279) (xy 78.856083 -474.812317)
			(xy 79.006547 -474.859526) (xy 79.154427 -474.914295) (xy 79.299344 -474.976483) (xy 79.440925 -475.045932)
			(xy 79.578806 -475.122462) (xy 79.712634 -475.205878) (xy 79.842066 -475.295965) (xy 79.966768 -475.392492)
			(xy 80.086422 -475.495211) (xy 80.200719 -475.603859) (xy 80.309367 -475.718156) (xy 80.412086 -475.83781)
			(xy 80.508613 -475.962512) (xy 80.5987 -476.091944) (xy 80.682116 -476.225772) (xy 80.758646 -476.363653)
			(xy 80.828095 -476.505234) (xy 80.890283 -476.650151) (xy 80.945052 -476.798031) (xy 80.992261 -476.948495)
			(xy 81.031788 -477.101158) (xy 81.063532 -477.255626) (xy 81.087412 -477.411504) (xy 81.103365 -477.568392)
			(xy 81.111353 -477.725886) (xy 81.111852 -477.804734) (xy 81.111852 -478.310532) (xy 91.326196 -478.310532)
			(xy 91.326196 -478.16152) (xy 91.334127 -478.01272) (xy 91.349966 -477.864552) (xy 91.373668 -477.717437)
			(xy 91.405166 -477.571793) (xy 91.444372 -477.428031) (xy 91.491173 -477.28656) (xy 91.545437 -477.147779)
			(xy 91.607011 -477.012084) (xy 91.675719 -476.879858) (xy 91.751367 -476.751477) (xy 91.833741 -476.627303)
			(xy 91.922606 -476.507689) (xy 92.017712 -476.392975) (xy 92.118789 -476.283485) (xy 92.225549 -476.17953)
			(xy 92.337691 -476.081404) (xy 92.454897 -475.989385) (xy 92.576833 -475.903735) (xy 92.703156 -475.824696)
			(xy 92.833506 -475.752493) (xy 92.967514 -475.687329) (xy 93.1048 -475.629389) (xy 93.244976 -475.578839)
			(xy 93.387643 -475.53582) (xy 93.532397 -475.500456) (xy 93.678829 -475.472846) (xy 93.826522 -475.453068)
			(xy 93.975059 -475.441179) (xy 94.124018 -475.437212) (xy 94.272977 -475.441179) (xy 94.421514 -475.453068)
			(xy 94.569207 -475.472846) (xy 94.715639 -475.500456) (xy 94.860393 -475.53582) (xy 95.00306 -475.578839)
			(xy 95.143236 -475.629389) (xy 95.280522 -475.687329) (xy 95.41453 -475.752493) (xy 95.54488 -475.824696)
			(xy 95.671203 -475.903735) (xy 95.793139 -475.989385) (xy 95.910345 -476.081404) (xy 96.022487 -476.17953)
			(xy 96.129247 -476.283485) (xy 96.230324 -476.392975) (xy 96.32543 -476.507689) (xy 96.414295 -476.627303)
			(xy 96.496669 -476.751477) (xy 96.572317 -476.879858) (xy 96.641025 -477.012084) (xy 96.702599 -477.147779)
			(xy 96.756863 -477.28656) (xy 96.803664 -477.428031) (xy 96.84287 -477.571793) (xy 96.874368 -477.717437)
			(xy 96.89807 -477.864552) (xy 96.913909 -478.01272) (xy 96.92184 -478.16152) (xy 96.922336 -478.236026)
			(xy 96.92184 -478.310532) (xy 96.913909 -478.459332) (xy 96.89807 -478.6075) (xy 96.874368 -478.754615)
			(xy 96.84287 -478.900259) (xy 96.803664 -479.044021) (xy 96.756863 -479.185492) (xy 96.702599 -479.324273)
			(xy 96.641025 -479.459968) (xy 96.572317 -479.592194) (xy 96.496669 -479.720575) (xy 96.414295 -479.844749)
			(xy 96.32543 -479.964363) (xy 96.230324 -480.079077) (xy 96.129247 -480.188567) (xy 96.022487 -480.292522)
			(xy 95.910345 -480.390648) (xy 95.793139 -480.482667) (xy 95.671203 -480.568317) (xy 95.54488 -480.647356)
			(xy 95.41453 -480.719559) (xy 95.280522 -480.784723) (xy 95.143236 -480.842663) (xy 95.00306 -480.893213)
			(xy 94.860393 -480.936232) (xy 94.715639 -480.971596) (xy 94.569207 -480.999206) (xy 94.421514 -481.018984)
			(xy 94.272977 -481.030873) (xy 94.124018 -481.03484) (xy 93.975059 -481.030873) (xy 93.826522 -481.018984)
			(xy 93.678829 -480.999206) (xy 93.532397 -480.971596) (xy 93.387643 -480.936232) (xy 93.244976 -480.893213)
			(xy 93.1048 -480.842663) (xy 92.967514 -480.784723) (xy 92.833506 -480.719559) (xy 92.703156 -480.647356)
			(xy 92.576833 -480.568317) (xy 92.454897 -480.482667) (xy 92.337691 -480.390648) (xy 92.225549 -480.292522)
			(xy 92.118789 -480.188567) (xy 92.017712 -480.079077) (xy 91.922606 -479.964363) (xy 91.833741 -479.844749)
			(xy 91.751367 -479.720575) (xy 91.675719 -479.592194) (xy 91.607011 -479.459968) (xy 91.545437 -479.324273)
			(xy 91.491173 -479.185492) (xy 91.444372 -479.044021) (xy 91.405166 -478.900259) (xy 91.373668 -478.754615)
			(xy 91.349966 -478.6075) (xy 91.334127 -478.459332) (xy 91.326196 -478.310532) (xy 81.111852 -478.310532)
			(xy 81.111852 -478.795334) (xy 81.111353 -478.874182) (xy 81.103365 -479.031676) (xy 81.087412 -479.188564)
			(xy 81.063532 -479.344442) (xy 81.031788 -479.49891) (xy 80.992261 -479.651573) (xy 80.945052 -479.802037)
			(xy 80.890283 -479.949917) (xy 80.828095 -480.094834) (xy 80.758646 -480.236415) (xy 80.682116 -480.374296)
			(xy 80.5987 -480.508124) (xy 80.508613 -480.637556) (xy 80.412086 -480.762258) (xy 80.309367 -480.881912)
			(xy 80.200719 -480.996209) (xy 80.086422 -481.104857) (xy 79.966768 -481.207576) (xy 79.842066 -481.304103)
			(xy 79.712634 -481.39419) (xy 79.578806 -481.477606) (xy 79.440925 -481.554136) (xy 79.299344 -481.623585)
			(xy 79.154427 -481.685773) (xy 79.006547 -481.740542) (xy 78.856083 -481.787751) (xy 78.70342 -481.827278)
			(xy 78.548952 -481.859022) (xy 78.393074 -481.882902) (xy 78.236186 -481.898855) (xy 78.078692 -481.906843)
			(xy 77.920996 -481.906843) (xy 77.763502 -481.898855) (xy 77.606614 -481.882902) (xy 77.450736 -481.859022)
			(xy 77.296268 -481.827278) (xy 77.143605 -481.787751) (xy 76.993141 -481.740542) (xy 76.845261 -481.685773)
			(xy 76.700344 -481.623585) (xy 76.558763 -481.554136) (xy 76.420882 -481.477606) (xy 76.287054 -481.39419)
			(xy 76.157622 -481.304103) (xy 76.03292 -481.207576) (xy 75.913266 -481.104857) (xy 75.798969 -480.996209)
			(xy 75.690321 -480.881912) (xy 75.587602 -480.762258) (xy 75.491075 -480.637556) (xy 75.400988 -480.508124)
			(xy 75.317572 -480.374296) (xy 75.241042 -480.236415) (xy 75.171593 -480.094834) (xy 75.109405 -479.949917)
			(xy 75.054636 -479.802037) (xy 75.007427 -479.651573) (xy 74.9679 -479.49891) (xy 74.936156 -479.344442)
			(xy 74.912276 -479.188564) (xy 74.896323 -479.031676) (xy 74.888335 -478.874182) (xy 74.887836 -478.795334)
			(xy 0.509016 -478.795334) (xy 0.509016 -488.261914) (xy 1.150624 -488.261914) (xy 1.154655 -488.132348)
			(xy 1.166734 -488.003284) (xy 1.186813 -487.87522) (xy 1.214815 -487.748653) (xy 1.250632 -487.62407)
			(xy 1.294124 -487.501956) (xy 1.345124 -487.382782) (xy 1.403435 -487.267009) (xy 1.46883 -487.155085)
			(xy 1.541057 -487.047443) (xy 1.619837 -486.9445) (xy 1.704864 -486.846654) (xy 1.795809 -486.754282)
			(xy 1.892321 -486.667744) (xy 1.994027 -486.587373) (xy 2.100533 -486.513481) (xy 2.211426 -486.446353)
			(xy 2.326278 -486.386249) (xy 2.444645 -486.333402) (xy 2.566068 -486.288015) (xy 2.690078 -486.250266)
			(xy 2.816195 -486.220299) (xy 2.943931 -486.19823) (xy 3.072792 -486.184146) (xy 3.202279 -486.1781)
			(xy 3.331892 -486.180116) (xy 3.461128 -486.190186) (xy 3.589489 -486.208271) (xy 3.716477 -486.234301)
			(xy 3.841601 -486.268176) (xy 3.964377 -486.309764) (xy 4.08433 -486.358905) (xy 4.200995 -486.415408)
			(xy 4.313923 -486.479055) (xy 4.422675 -486.549599) (xy 4.526831 -486.626768) (xy 4.625988 -486.710263)
			(xy 4.719762 -486.799761) (xy 4.807791 -486.894916) (xy 4.889734 -486.995359) (xy 4.965273 -487.100702)
			(xy 5.034118 -487.210538) (xy 5.096001 -487.324442) (xy 5.150682 -487.441972) (xy 5.197952 -487.562675)
			(xy 5.237625 -487.686083) (xy 5.26955 -487.811719) (xy 5.293602 -487.939096) (xy 5.309689 -488.067722)
			(xy 5.317748 -488.1971) (xy 5.318252 -488.261914) (xy 12.580624 -488.261914) (xy 12.584655 -488.132348)
			(xy 12.596734 -488.003284) (xy 12.616813 -487.87522) (xy 12.644815 -487.748653) (xy 12.680632 -487.62407)
			(xy 12.724124 -487.501956) (xy 12.775124 -487.382782) (xy 12.833435 -487.267009) (xy 12.89883 -487.155085)
			(xy 12.971057 -487.047443) (xy 13.049837 -486.9445) (xy 13.134864 -486.846654) (xy 13.225809 -486.754282)
			(xy 13.322321 -486.667744) (xy 13.424027 -486.587373) (xy 13.530533 -486.513481) (xy 13.641426 -486.446353)
			(xy 13.756278 -486.386249) (xy 13.874645 -486.333402) (xy 13.996068 -486.288015) (xy 14.120078 -486.250266)
			(xy 14.246195 -486.220299) (xy 14.373931 -486.19823) (xy 14.502792 -486.184146) (xy 14.632279 -486.1781)
			(xy 14.761892 -486.180116) (xy 14.891128 -486.190186) (xy 15.019489 -486.208271) (xy 15.146477 -486.234301)
			(xy 15.271601 -486.268176) (xy 15.394377 -486.309764) (xy 15.51433 -486.358905) (xy 15.630995 -486.415408)
			(xy 15.743923 -486.479055) (xy 15.852675 -486.549599) (xy 15.956831 -486.626768) (xy 16.055988 -486.710263)
			(xy 16.149762 -486.799761) (xy 16.237791 -486.894916) (xy 16.319734 -486.995359) (xy 16.395273 -487.100702)
			(xy 16.464118 -487.210538) (xy 16.526001 -487.324442) (xy 16.580682 -487.441972) (xy 16.627952 -487.562675)
			(xy 16.667625 -487.686083) (xy 16.69955 -487.811719) (xy 16.723602 -487.939096) (xy 16.739689 -488.067722)
			(xy 16.747748 -488.1971) (xy 16.748252 -488.261914) (xy 16.747748 -488.326728) (xy 16.739689 -488.456106)
			(xy 16.723602 -488.584732) (xy 16.69955 -488.712109) (xy 16.667625 -488.837745) (xy 16.627952 -488.961153)
			(xy 16.580682 -489.081856) (xy 16.526001 -489.199386) (xy 16.464118 -489.31329) (xy 16.395273 -489.423126)
			(xy 16.319734 -489.528469) (xy 16.237791 -489.628912) (xy 16.149762 -489.724067) (xy 16.055988 -489.813565)
			(xy 15.956831 -489.89706) (xy 15.852675 -489.974229) (xy 15.743923 -490.044773) (xy 15.630995 -490.10842)
			(xy 15.51433 -490.164923) (xy 15.394377 -490.214064) (xy 15.271601 -490.255652) (xy 15.146477 -490.289527)
			(xy 15.019489 -490.315557) (xy 14.891128 -490.333642) (xy 14.761892 -490.343712) (xy 14.632279 -490.345728)
			(xy 14.502792 -490.339682) (xy 14.373931 -490.325598) (xy 14.246195 -490.303529) (xy 14.120078 -490.273562)
			(xy 13.996068 -490.235813) (xy 13.874645 -490.190426) (xy 13.756278 -490.137579) (xy 13.641426 -490.077475)
			(xy 13.530533 -490.010347) (xy 13.424027 -489.936455) (xy 13.322321 -489.856084) (xy 13.225809 -489.769546)
			(xy 13.134864 -489.677174) (xy 13.049837 -489.579328) (xy 12.971057 -489.476385) (xy 12.89883 -489.368743)
			(xy 12.833435 -489.256819) (xy 12.775124 -489.141046) (xy 12.724124 -489.021872) (xy 12.680632 -488.899758)
			(xy 12.644815 -488.775175) (xy 12.616813 -488.648608) (xy 12.596734 -488.520544) (xy 12.584655 -488.39148)
			(xy 12.580624 -488.261914) (xy 5.318252 -488.261914) (xy 5.317748 -488.326728) (xy 5.309689 -488.456106)
			(xy 5.293602 -488.584732) (xy 5.26955 -488.712109) (xy 5.237625 -488.837745) (xy 5.197952 -488.961153)
			(xy 5.150682 -489.081856) (xy 5.096001 -489.199386) (xy 5.034118 -489.31329) (xy 4.965273 -489.423126)
			(xy 4.889734 -489.528469) (xy 4.807791 -489.628912) (xy 4.719762 -489.724067) (xy 4.625988 -489.813565)
			(xy 4.526831 -489.89706) (xy 4.422675 -489.974229) (xy 4.313923 -490.044773) (xy 4.200995 -490.10842)
			(xy 4.08433 -490.164923) (xy 3.964377 -490.214064) (xy 3.841601 -490.255652) (xy 3.716477 -490.289527)
			(xy 3.589489 -490.315557) (xy 3.461128 -490.333642) (xy 3.331892 -490.343712) (xy 3.202279 -490.345728)
			(xy 3.072792 -490.339682) (xy 2.943931 -490.325598) (xy 2.816195 -490.303529) (xy 2.690078 -490.273562)
			(xy 2.566068 -490.235813) (xy 2.444645 -490.190426) (xy 2.326278 -490.137579) (xy 2.211426 -490.077475)
			(xy 2.100533 -490.010347) (xy 1.994027 -489.936455) (xy 1.892321 -489.856084) (xy 1.795809 -489.769546)
			(xy 1.704864 -489.677174) (xy 1.619837 -489.579328) (xy 1.541057 -489.476385) (xy 1.46883 -489.368743)
			(xy 1.403435 -489.256819) (xy 1.345124 -489.141046) (xy 1.294124 -489.021872) (xy 1.250632 -488.899758)
			(xy 1.214815 -488.775175) (xy 1.186813 -488.648608) (xy 1.166734 -488.520544) (xy 1.154655 -488.39148)
			(xy 1.150624 -488.261914) (xy 0.509016 -488.261914) (xy 0.509016 -495.86007) (xy 39.818063 -495.86007)
			(xy 39.82207 -495.744046) (xy 39.834072 -495.628574) (xy 39.854012 -495.514206) (xy 39.881795 -495.401486)
			(xy 39.917289 -495.290952) (xy 39.960324 -495.183129) (xy 40.010695 -495.078532) (xy 40.068162 -494.97766)
			(xy 40.132452 -494.880993) (xy 40.203257 -494.788992) (xy 40.280241 -494.702095) (xy 40.363037 -494.620716)
			(xy 40.45125 -494.545243) (xy 40.54446 -494.476036) (xy 40.642223 -494.413424) (xy 40.744072 -494.357707)
			(xy 40.849522 -494.309149) (xy 40.958071 -494.267981) (xy 41.069202 -494.234401) (xy 41.182385 -494.208568)
			(xy 41.29708 -494.190605) (xy 41.412742 -494.180597) (xy 41.528818 -494.178594) (xy 41.644756 -494.184603)
			(xy 41.760003 -494.198596) (xy 41.874009 -494.220507) (xy 41.986233 -494.250232) (xy 42.096139 -494.287628)
			(xy 42.203202 -494.332517) (xy 42.306914 -494.384686) (xy 42.406779 -494.443886) (xy 42.502322 -494.509835)
			(xy 42.593088 -494.582218) (xy 42.678643 -494.660691) (xy 42.758581 -494.744879) (xy 42.83252 -494.834381)
			(xy 42.900108 -494.928772) (xy 42.961022 -495.0276) (xy 43.014974 -495.130396) (xy 43.061704 -495.236669)
			(xy 43.100992 -495.345913) (xy 43.132649 -495.457606) (xy 43.156525 -495.571218) (xy 43.172506 -495.686206)
			(xy 43.180515 -495.802023) (xy 43.181016 -495.86007) (xy 43.180515 -495.918117) (xy 43.172506 -496.033934)
			(xy 43.156525 -496.148922) (xy 43.132649 -496.262534) (xy 43.100992 -496.374227) (xy 43.061704 -496.483471)
			(xy 43.014974 -496.589744) (xy 42.961022 -496.69254) (xy 42.900108 -496.791368) (xy 42.83252 -496.885759)
			(xy 42.758581 -496.975261) (xy 42.678643 -497.059449) (xy 42.593088 -497.137922) (xy 42.502604 -497.21008)
			(xy 93.154506 -497.21008) (xy 93.158522 -497.09381) (xy 93.170549 -496.978095) (xy 93.190531 -496.863485)
			(xy 93.218373 -496.750526) (xy 93.253942 -496.639758) (xy 93.297068 -496.531707) (xy 93.347545 -496.426889)
			(xy 93.405134 -496.325804) (xy 93.46956 -496.228932) (xy 93.540515 -496.136736) (xy 93.617662 -496.049655)
			(xy 93.700633 -495.968104) (xy 93.789033 -495.892472) (xy 93.88244 -495.823118) (xy 93.980409 -495.760375)
			(xy 94.082473 -495.704539) (xy 94.188147 -495.655878) (xy 94.296926 -495.614624) (xy 94.408291 -495.580973)
			(xy 94.521714 -495.555085) (xy 94.636651 -495.537084) (xy 94.752557 -495.527055) (xy 94.868879 -495.525047)
			(xy 94.985062 -495.531069) (xy 95.100553 -495.545092) (xy 95.214801 -495.56705) (xy 95.327262 -495.596837)
			(xy 95.4374 -495.634312) (xy 95.54469 -495.679297) (xy 95.648621 -495.731576) (xy 95.748697 -495.790901)
			(xy 95.844443 -495.856989) (xy 95.9354 -495.929525) (xy 96.021136 -496.008164) (xy 96.101243 -496.09253)
			(xy 96.175339 -496.182222) (xy 96.243069 -496.276812) (xy 96.304113 -496.37585) (xy 96.358178 -496.478863)
			(xy 96.405008 -496.58536) (xy 96.444379 -496.694835) (xy 96.476103 -496.806765) (xy 96.500029 -496.920617)
			(xy 96.516043 -497.035849) (xy 96.52407 -497.151911) (xy 96.524572 -497.21008) (xy 96.52407 -497.268249)
			(xy 96.516043 -497.384311) (xy 96.500029 -497.499543) (xy 96.476103 -497.613395) (xy 96.444379 -497.725325)
			(xy 96.405008 -497.8348) (xy 96.358178 -497.941297) (xy 96.304113 -498.04431) (xy 96.243069 -498.143348)
			(xy 96.175339 -498.237938) (xy 96.101243 -498.32763) (xy 96.021136 -498.411996) (xy 95.9354 -498.490635)
			(xy 95.844443 -498.563171) (xy 95.748697 -498.629259) (xy 95.648621 -498.688584) (xy 95.54469 -498.740863)
			(xy 95.4374 -498.785848) (xy 95.327262 -498.823323) (xy 95.214801 -498.85311) (xy 95.100553 -498.875068)
			(xy 94.985062 -498.889091) (xy 94.868879 -498.895113) (xy 94.752557 -498.893105) (xy 94.636651 -498.883076)
			(xy 94.521714 -498.865075) (xy 94.408291 -498.839187) (xy 94.296926 -498.805536) (xy 94.188147 -498.764282)
			(xy 94.082473 -498.715621) (xy 93.980409 -498.659785) (xy 93.88244 -498.597042) (xy 93.789033 -498.527688)
			(xy 93.700633 -498.452056) (xy 93.617662 -498.370505) (xy 93.540515 -498.283424) (xy 93.46956 -498.191228)
			(xy 93.405134 -498.094356) (xy 93.347545 -497.993271) (xy 93.297068 -497.888453) (xy 93.253942 -497.780402)
			(xy 93.218373 -497.669634) (xy 93.190531 -497.556675) (xy 93.170549 -497.442065) (xy 93.158522 -497.32635)
			(xy 93.154506 -497.21008) (xy 42.502604 -497.21008) (xy 42.502322 -497.210305) (xy 42.406779 -497.276254)
			(xy 42.306914 -497.335454) (xy 42.203202 -497.387623) (xy 42.096139 -497.432512) (xy 41.986233 -497.469908)
			(xy 41.874009 -497.499633) (xy 41.760003 -497.521544) (xy 41.644756 -497.535537) (xy 41.528818 -497.541546)
			(xy 41.412742 -497.539543) (xy 41.29708 -497.529535) (xy 41.182385 -497.511572) (xy 41.069202 -497.485739)
			(xy 40.958071 -497.452159) (xy 40.849522 -497.410991) (xy 40.744072 -497.362433) (xy 40.642223 -497.306716)
			(xy 40.54446 -497.244104) (xy 40.45125 -497.174897) (xy 40.363037 -497.099424) (xy 40.280241 -497.018045)
			(xy 40.203257 -496.931148) (xy 40.132452 -496.839147) (xy 40.068162 -496.74248) (xy 40.010695 -496.641608)
			(xy 39.960324 -496.537011) (xy 39.917289 -496.429188) (xy 39.881795 -496.318654) (xy 39.854012 -496.205934)
			(xy 39.834072 -496.091566) (xy 39.82207 -495.976094) (xy 39.818063 -495.86007) (xy 0.509016 -495.86007)
			(xy 0.509016 -508.96012) (xy 86.877404 -508.96012) (xy 86.881424 -508.769469) (xy 86.893478 -508.579156)
			(xy 86.913544 -508.389521) (xy 86.941587 -508.2009) (xy 86.977556 -508.01363) (xy 87.021388 -507.828042)
			(xy 87.073005 -507.644467) (xy 87.132315 -507.463231) (xy 87.199213 -507.284656) (xy 87.273579 -507.109061)
			(xy 87.355281 -506.936756) (xy 87.444175 -506.768049) (xy 87.540101 -506.603239) (xy 87.64289 -506.44262)
			(xy 87.752359 -506.286477) (xy 87.868313 -506.135088) (xy 87.990547 -505.988721) (xy 88.118841 -505.847637)
			(xy 88.252969 -505.712088) (xy 88.392693 -505.582313) (xy 88.537763 -505.458543) (xy 88.687921 -505.341)
			(xy 88.842902 -505.229891) (xy 89.002429 -505.125414) (xy 89.166218 -505.027755) (xy 89.333978 -504.937088)
			(xy 89.505412 -504.853574) (xy 89.680214 -504.777361) (xy 89.858073 -504.708585) (xy 90.038674 -504.647367)
			(xy 90.221694 -504.593818) (xy 90.40681 -504.548032) (xy 90.593691 -504.51009) (xy 90.782006 -504.480061)
			(xy 90.971419 -504.457996) (xy 91.161593 -504.443937) (xy 91.352192 -504.437907) (xy 91.542875 -504.439917)
			(xy 91.733304 -504.449964) (xy 91.92314 -504.46803) (xy 92.112046 -504.494083) (xy 92.299685 -504.528076)
			(xy 92.485725 -504.569949) (xy 92.669834 -504.619628) (xy 92.851685 -504.677024) (xy 93.030955 -504.742035)
			(xy 93.207325 -504.814546) (xy 93.380481 -504.894427) (xy 93.550116 -504.981537) (xy 93.715928 -505.075721)
			(xy 93.877622 -505.176812) (xy 94.03491 -505.284628) (xy 94.187513 -505.39898) (xy 94.335161 -505.519663)
			(xy 94.477589 -505.646464) (xy 94.614545 -505.779155) (xy 94.745786 -505.917503) (xy 94.871078 -506.06126)
			(xy 94.990198 -506.210171) (xy 95.102934 -506.363972) (xy 95.209087 -506.522388) (xy 95.308467 -506.685139)
			(xy 95.400897 -506.851934) (xy 95.486214 -507.022478) (xy 95.564266 -507.196466) (xy 95.634913 -507.373591)
			(xy 95.698031 -507.553536) (xy 95.753507 -507.735982) (xy 95.801242 -507.920605) (xy 95.841152 -508.107075)
			(xy 95.873165 -508.295063) (xy 95.897225 -508.484233) (xy 95.913288 -508.674249) (xy 95.921327 -508.864773)
			(xy 95.92183 -508.96012) (xy 95.921327 -509.055467) (xy 95.913288 -509.245991) (xy 95.897225 -509.436007)
			(xy 95.873165 -509.625177) (xy 95.841152 -509.813165) (xy 95.801242 -509.999635) (xy 95.753507 -510.184258)
			(xy 95.698031 -510.366704) (xy 95.634913 -510.546649) (xy 95.564266 -510.723774) (xy 95.486214 -510.897762)
			(xy 95.400897 -511.068306) (xy 95.308467 -511.235101) (xy 95.209087 -511.397852) (xy 95.102934 -511.556268)
			(xy 94.990198 -511.710069) (xy 94.871078 -511.85898) (xy 94.745786 -512.002737) (xy 94.614545 -512.141085)
			(xy 94.477589 -512.273776) (xy 94.335161 -512.400577) (xy 94.187513 -512.52126) (xy 94.03491 -512.635612)
			(xy 93.877622 -512.743428) (xy 93.715928 -512.844519) (xy 93.550116 -512.938703) (xy 93.380481 -513.025813)
			(xy 93.207325 -513.105694) (xy 93.030955 -513.178205) (xy 92.851685 -513.243216) (xy 92.669834 -513.300612)
			(xy 92.485725 -513.350291) (xy 92.299685 -513.392164) (xy 92.112046 -513.426157) (xy 91.92314 -513.45221)
			(xy 91.733304 -513.470276) (xy 91.542875 -513.480323) (xy 91.352192 -513.482333) (xy 91.161593 -513.476303)
			(xy 90.971419 -513.462244) (xy 90.782006 -513.440179) (xy 90.593691 -513.41015) (xy 90.40681 -513.372208)
			(xy 90.221694 -513.326422) (xy 90.038674 -513.272873) (xy 89.858073 -513.211655) (xy 89.680214 -513.142879)
			(xy 89.505412 -513.066666) (xy 89.333978 -512.983152) (xy 89.166218 -512.892485) (xy 89.002429 -512.794826)
			(xy 88.842902 -512.690349) (xy 88.687921 -512.57924) (xy 88.537763 -512.461697) (xy 88.392693 -512.337927)
			(xy 88.252969 -512.208152) (xy 88.118841 -512.072603) (xy 87.990547 -511.931519) (xy 87.868313 -511.785152)
			(xy 87.752359 -511.633763) (xy 87.64289 -511.47762) (xy 87.540101 -511.317001) (xy 87.444175 -511.152191)
			(xy 87.355281 -510.983484) (xy 87.273579 -510.811179) (xy 87.199213 -510.635584) (xy 87.132315 -510.457009)
			(xy 87.073005 -510.275773) (xy 87.021388 -510.092198) (xy 86.977556 -509.90661) (xy 86.941587 -509.71934)
			(xy 86.913544 -509.530719) (xy 86.893478 -509.341084) (xy 86.881424 -509.150771) (xy 86.877404 -508.96012)
			(xy 0.509016 -508.96012) (xy 0.509016 -514.771894) (xy 1.150624 -514.771894) (xy 1.154655 -514.642328)
			(xy 1.166734 -514.513264) (xy 1.186813 -514.3852) (xy 1.214815 -514.258633) (xy 1.250632 -514.13405)
			(xy 1.294124 -514.011936) (xy 1.345124 -513.892762) (xy 1.403435 -513.776989) (xy 1.46883 -513.665065)
			(xy 1.541057 -513.557423) (xy 1.619837 -513.45448) (xy 1.704864 -513.356634) (xy 1.795809 -513.264262)
			(xy 1.892321 -513.177724) (xy 1.994027 -513.097353) (xy 2.100533 -513.023461) (xy 2.211426 -512.956333)
			(xy 2.326278 -512.896229) (xy 2.444645 -512.843382) (xy 2.566068 -512.797995) (xy 2.690078 -512.760246)
			(xy 2.816195 -512.730279) (xy 2.943931 -512.70821) (xy 3.072792 -512.694126) (xy 3.202279 -512.68808)
			(xy 3.331892 -512.690096) (xy 3.461128 -512.700166) (xy 3.589489 -512.718251) (xy 3.716477 -512.744281)
			(xy 3.841601 -512.778156) (xy 3.964377 -512.819744) (xy 4.08433 -512.868885) (xy 4.200995 -512.925388)
			(xy 4.313923 -512.989035) (xy 4.422675 -513.059579) (xy 4.526831 -513.136748) (xy 4.625988 -513.220243)
			(xy 4.719762 -513.309741) (xy 4.807791 -513.404896) (xy 4.889734 -513.505339) (xy 4.965273 -513.610682)
			(xy 5.034118 -513.720518) (xy 5.096001 -513.834422) (xy 5.150682 -513.951952) (xy 5.197952 -514.072655)
			(xy 5.237625 -514.196063) (xy 5.26955 -514.321699) (xy 5.293602 -514.449076) (xy 5.309689 -514.577702)
			(xy 5.317748 -514.70708) (xy 5.318252 -514.771894) (xy 12.580624 -514.771894) (xy 12.584655 -514.642328)
			(xy 12.596734 -514.513264) (xy 12.616813 -514.3852) (xy 12.644815 -514.258633) (xy 12.680632 -514.13405)
			(xy 12.724124 -514.011936) (xy 12.775124 -513.892762) (xy 12.833435 -513.776989) (xy 12.89883 -513.665065)
			(xy 12.971057 -513.557423) (xy 13.049837 -513.45448) (xy 13.134864 -513.356634) (xy 13.225809 -513.264262)
			(xy 13.322321 -513.177724) (xy 13.424027 -513.097353) (xy 13.530533 -513.023461) (xy 13.641426 -512.956333)
			(xy 13.756278 -512.896229) (xy 13.874645 -512.843382) (xy 13.996068 -512.797995) (xy 14.120078 -512.760246)
			(xy 14.246195 -512.730279) (xy 14.373931 -512.70821) (xy 14.502792 -512.694126) (xy 14.632279 -512.68808)
			(xy 14.761892 -512.690096) (xy 14.891128 -512.700166) (xy 15.019489 -512.718251) (xy 15.146477 -512.744281)
			(xy 15.271601 -512.778156) (xy 15.394377 -512.819744) (xy 15.51433 -512.868885) (xy 15.630995 -512.925388)
			(xy 15.743923 -512.989035) (xy 15.852675 -513.059579) (xy 15.956831 -513.136748) (xy 16.055988 -513.220243)
			(xy 16.149762 -513.309741) (xy 16.237791 -513.404896) (xy 16.319734 -513.505339) (xy 16.395273 -513.610682)
			(xy 16.464118 -513.720518) (xy 16.526001 -513.834422) (xy 16.580682 -513.951952) (xy 16.627952 -514.072655)
			(xy 16.667625 -514.196063) (xy 16.69955 -514.321699) (xy 16.723602 -514.449076) (xy 16.739689 -514.577702)
			(xy 16.747748 -514.70708) (xy 16.748252 -514.771894) (xy 16.747748 -514.836708) (xy 16.739689 -514.966086)
			(xy 16.723602 -515.094712) (xy 16.69955 -515.222089) (xy 16.667625 -515.347725) (xy 16.627952 -515.471133)
			(xy 16.580682 -515.591836) (xy 16.526001 -515.709366) (xy 16.464118 -515.82327) (xy 16.395273 -515.933106)
			(xy 16.319734 -516.038449) (xy 16.237791 -516.138892) (xy 16.149762 -516.234047) (xy 16.055988 -516.323545)
			(xy 15.956831 -516.40704) (xy 15.852675 -516.484209) (xy 15.743923 -516.554753) (xy 15.630995 -516.6184)
			(xy 15.51433 -516.674903) (xy 15.394377 -516.724044) (xy 15.271601 -516.765632) (xy 15.146477 -516.799507)
			(xy 15.019489 -516.825537) (xy 14.891128 -516.843622) (xy 14.761892 -516.853692) (xy 14.632279 -516.855708)
			(xy 14.502792 -516.849662) (xy 14.373931 -516.835578) (xy 14.246195 -516.813509) (xy 14.120078 -516.783542)
			(xy 13.996068 -516.745793) (xy 13.874645 -516.700406) (xy 13.756278 -516.647559) (xy 13.641426 -516.587455)
			(xy 13.530533 -516.520327) (xy 13.424027 -516.446435) (xy 13.322321 -516.366064) (xy 13.225809 -516.279526)
			(xy 13.134864 -516.187154) (xy 13.049837 -516.089308) (xy 12.971057 -515.986365) (xy 12.89883 -515.878723)
			(xy 12.833435 -515.766799) (xy 12.775124 -515.651026) (xy 12.724124 -515.531852) (xy 12.680632 -515.409738)
			(xy 12.644815 -515.285155) (xy 12.616813 -515.158588) (xy 12.596734 -515.030524) (xy 12.584655 -514.90146)
			(xy 12.580624 -514.771894) (xy 5.318252 -514.771894) (xy 5.317748 -514.836708) (xy 5.309689 -514.966086)
			(xy 5.293602 -515.094712) (xy 5.26955 -515.222089) (xy 5.237625 -515.347725) (xy 5.197952 -515.471133)
			(xy 5.150682 -515.591836) (xy 5.096001 -515.709366) (xy 5.034118 -515.82327) (xy 4.965273 -515.933106)
			(xy 4.889734 -516.038449) (xy 4.807791 -516.138892) (xy 4.719762 -516.234047) (xy 4.625988 -516.323545)
			(xy 4.526831 -516.40704) (xy 4.422675 -516.484209) (xy 4.313923 -516.554753) (xy 4.200995 -516.6184)
			(xy 4.08433 -516.674903) (xy 3.964377 -516.724044) (xy 3.841601 -516.765632) (xy 3.716477 -516.799507)
			(xy 3.589489 -516.825537) (xy 3.461128 -516.843622) (xy 3.331892 -516.853692) (xy 3.202279 -516.855708)
			(xy 3.072792 -516.849662) (xy 2.943931 -516.835578) (xy 2.816195 -516.813509) (xy 2.690078 -516.783542)
			(xy 2.566068 -516.745793) (xy 2.444645 -516.700406) (xy 2.326278 -516.647559) (xy 2.211426 -516.587455)
			(xy 2.100533 -516.520327) (xy 1.994027 -516.446435) (xy 1.892321 -516.366064) (xy 1.795809 -516.279526)
			(xy 1.704864 -516.187154) (xy 1.619837 -516.089308) (xy 1.541057 -515.986365) (xy 1.46883 -515.878723)
			(xy 1.403435 -515.766799) (xy 1.345124 -515.651026) (xy 1.294124 -515.531852) (xy 1.250632 -515.409738)
			(xy 1.214815 -515.285155) (xy 1.186813 -515.158588) (xy 1.166734 -515.030524) (xy 1.154655 -514.90146)
			(xy 1.150624 -514.771894) (xy 0.509016 -514.771894) (xy 0.509016 -519.049762) (xy 75.486773 -519.049762)
			(xy 75.490798 -518.90757) (xy 75.502861 -518.765834) (xy 75.522924 -518.625008) (xy 75.550922 -518.485542)
			(xy 75.586766 -518.347883) (xy 75.63034 -518.212473) (xy 75.681505 -518.079745) (xy 75.740098 -517.950124)
			(xy 75.805929 -517.824026) (xy 75.87879 -517.701854) (xy 75.958445 -517.584) (xy 76.044641 -517.470841)
			(xy 76.1371 -517.362739) (xy 76.235528 -517.260042) (xy 76.339607 -517.163078) (xy 76.449006 -517.072158)
			(xy 76.563374 -516.987572) (xy 76.682343 -516.909592) (xy 76.805534 -516.838468) (xy 76.932551 -516.774427)
			(xy 77.062988 -516.717675) (xy 77.196427 -516.668393) (xy 77.33244 -516.626739) (xy 77.470592 -516.592847)
			(xy 77.610441 -516.566826) (xy 77.751537 -516.548758) (xy 77.893429 -516.538701) (xy 78.035664 -516.536688)
			(xy 78.177784 -516.542725) (xy 78.319335 -516.556793) (xy 78.459864 -516.578847) (xy 78.598919 -516.608816)
			(xy 78.736057 -516.646604) (xy 78.870837 -516.69209) (xy 79.002828 -516.745128) (xy 79.131607 -516.805549)
			(xy 79.256761 -516.873158) (xy 79.377889 -516.94774) (xy 79.494605 -517.029056) (xy 79.606533 -517.116844)
			(xy 79.713315 -517.210824) (xy 79.814609 -517.310694) (xy 79.91009 -517.416136) (xy 79.999454 -517.52681)
			(xy 80.082412 -517.642363) (xy 80.158701 -517.762424) (xy 80.228075 -517.886609) (xy 80.290312 -518.01452)
			(xy 80.345213 -518.145747) (xy 80.392601 -518.27987) (xy 80.432326 -518.416459) (xy 80.464259 -518.555077)
			(xy 80.4883 -518.695279) (xy 80.504369 -518.836617) (xy 80.512417 -518.978638) (xy 80.51292 -519.049762)
			(xy 80.512417 -519.120886) (xy 80.504369 -519.262907) (xy 80.4883 -519.404245) (xy 80.464259 -519.544447)
			(xy 80.432326 -519.683065) (xy 80.392601 -519.819654) (xy 80.345213 -519.953777) (xy 80.290312 -520.085004)
			(xy 80.228075 -520.212915) (xy 80.158701 -520.3371) (xy 80.082412 -520.457161) (xy 79.999454 -520.572714)
			(xy 79.91009 -520.683388) (xy 79.814609 -520.78883) (xy 79.713315 -520.8887) (xy 79.606533 -520.98268)
			(xy 79.494605 -521.070468) (xy 79.377889 -521.151784) (xy 79.256761 -521.226366) (xy 79.131607 -521.293975)
			(xy 79.002828 -521.354396) (xy 78.870837 -521.407434) (xy 78.736057 -521.45292) (xy 78.598919 -521.490708)
			(xy 78.459864 -521.520677) (xy 78.319335 -521.542731) (xy 78.177784 -521.556799) (xy 78.035664 -521.562836)
			(xy 77.893429 -521.560823) (xy 77.751537 -521.550766) (xy 77.610441 -521.532698) (xy 77.470592 -521.506677)
			(xy 77.33244 -521.472785) (xy 77.196427 -521.431131) (xy 77.062988 -521.381849) (xy 76.932551 -521.325097)
			(xy 76.805534 -521.261056) (xy 76.682343 -521.189932) (xy 76.563374 -521.111952) (xy 76.449006 -521.027366)
			(xy 76.339607 -520.936446) (xy 76.235528 -520.839482) (xy 76.1371 -520.736785) (xy 76.044641 -520.628683)
			(xy 75.958445 -520.515524) (xy 75.87879 -520.39767) (xy 75.805929 -520.275498) (xy 75.740098 -520.1494)
			(xy 75.681505 -520.019779) (xy 75.63034 -519.887051) (xy 75.586766 -519.751641) (xy 75.550922 -519.613982)
			(xy 75.522924 -519.474516) (xy 75.502861 -519.33369) (xy 75.490798 -519.191954) (xy 75.486773 -519.049762)
			(xy 0.509016 -519.049762) (xy 0.509016 -524.500094) (xy 0.509529 -524.54588) (xy 0.517978 -524.637062)
			(xy 0.534804 -524.727075) (xy 0.559864 -524.815152) (xy 0.592944 -524.900541) (xy 0.633761 -524.982513)
			(xy 0.681968 -525.06037) (xy 0.737153 -525.133446) (xy 0.798845 -525.201119) (xy 0.866518 -525.262811)
			(xy 0.939594 -525.317996) (xy 1.017451 -525.366203) (xy 1.099423 -525.40702) (xy 1.184812 -525.4401)
			(xy 1.272889 -525.46516) (xy 1.362902 -525.481986) (xy 1.454084 -525.490435) (xy 1.49987 -525.490948)
			(xy 23.50008 -525.490948) (xy 23.563202 -525.491433) (xy 23.689196 -525.499359) (xy 23.814444 -525.515182)
			(xy 23.93845 -525.538839) (xy 24.060727 -525.570236) (xy 24.180791 -525.60925) (xy 24.298167 -525.655726)
			(xy 24.412394 -525.709482) (xy 24.523019 -525.770304) (xy 24.629607 -525.837954) (xy 24.731736 -525.912163)
			(xy 24.829004 -525.992639) (xy 24.921025 -526.079064) (xy 25.007438 -526.171097) (xy 25.087902 -526.268376)
			(xy 25.162097 -526.370515) (xy 25.229732 -526.477111) (xy 25.29054 -526.587745) (xy 25.34428 -526.701979)
			(xy 25.390741 -526.819362) (xy 25.429739 -526.93943) (xy 25.46112 -527.061711) (xy 25.48476 -527.185721)
			(xy 25.500566 -527.310971) (xy 25.508475 -527.436966) (xy 25.508966 -527.500088) (xy 25.508966 -528.500086)
			(xy 25.509507 -528.545875) (xy 25.517982 -528.637061) (xy 25.534832 -528.727076) (xy 25.559914 -528.815153)
			(xy 25.593014 -528.90054) (xy 25.633851 -528.98251) (xy 25.682074 -529.060363) (xy 25.737274 -529.133435)
			(xy 25.79898 -529.201104) (xy 25.866665 -529.262792) (xy 25.939752 -529.317973) (xy 26.017618 -529.366176)
			(xy 26.099598 -529.406991) (xy 26.184994 -529.440069) (xy 26.273077 -529.465128) (xy 26.363097 -529.481954)
			(xy 26.454285 -529.490405) (xy 26.500074 -529.49094)
		)
		(stroke
			(width 0)
			(type solid)
		)
		(fill yes)
		(layer "In1.Cu")
		(net "GND")
	)
	(gr_arc
		(start 1.500124 -3.999992)
		(mid 0.439376 -4.439368)
		(end 0 -5.500116)
		(stroke
			(width 1.016)
			(type default)
		)
		(layer "In1.Cu")
	)
	(gr_line
		(start 1.500124 -3.999992)
		(end 23.50008 -3.999992)
		(stroke
			(width 1.016)
			(type default)
		)
		(layer "In1.Cu")
	)
	(gr_line
		(start 23.50008 -525.999964)
		(end 1.500124 -525.999964)
		(stroke
			(width 1.016)
			(type default)
		)
		(layer "In1.Cu")
	)
	(gr_arc
		(start 23.50008 -3.999992)
		(mid 24.560648 -3.56069)
		(end 24.99995 -2.500122)
		(stroke
			(width 1.016)
			(type default)
		)
		(layer "In1.Cu")
	)
	(gr_line
		(start 24.99995 -528.500086)
		(end 24.99995 -527.500088)
		(stroke
			(width 1.016)
			(type default)
		)
		(layer "In1.Cu")
	)
	(gr_arc
		(start 24.99995 -528.500086)
		(mid 25.439426 -529.560658)
		(end 26.500074 -529.999956)
		(stroke
			(width 1.016)
			(type default)
		)
		(layer "In1.Cu")
	)
	(gr_arc
		(start 24.99995 -527.500088)
		(mid 24.560738 -526.439356)
		(end 23.50008 -525.999964)
		(stroke
			(width 1.016)
			(type default)
		)
		(layer "In1.Cu")
	)
	(gr_line
		(start 24.99995 -2.500122)
		(end 24.99995 -1.500124)
		(stroke
			(width 1.016)
			(type default)
		)
		(layer "In1.Cu")
	)
	(gr_arc
		(start 26.500074 0)
		(mid 25.439325 -0.439375)
		(end 24.99995 -1.500124)
		(stroke
			(width 1.016)
			(type default)
		)
		(layer "In1.Cu")
	)
	(gr_line
		(start 26.500074 0)
		(end 101.000052 0)
		(stroke
			(width 1.016)
			(type default)
		)
		(layer "In1.Cu")
	)
	(gr_line
		(start 92.607384 -478.886774)
		(end 92.607384 -477.791526)
		(stroke
			(width 0.254)
			(type default)
		)
		(layer "In1.Cu")
	)
	(gr_line
		(start 92.607384 -477.791526)
		(end 92.972382 -477.426528)
		(stroke
			(width 0.254)
			(type default)
		)
		(layer "In1.Cu")
	)
	(gr_line
		(start 92.972382 -477.836992)
		(end 92.926662 -477.882712)
		(stroke
			(width 0.254)
			(type default)
		)
		(layer "In1.Cu")
	)
	(gr_line
		(start 92.972382 -477.426528)
		(end 92.972382 -477.836992)
		(stroke
			(width 0.254)
			(type default)
		)
		(layer "In1.Cu")
	)
	(gr_line
		(start 93.291914 -479.571304)
		(end 92.607384 -478.886774)
		(stroke
			(width 0.254)
			(type default)
		)
		(layer "In1.Cu")
	)
	(gr_line
		(start 93.43898 -78.561184)
		(end 93.758512 -78.880716)
		(stroke
			(width 2.032)
			(type default)
		)
		(layer "In1.Cu")
	)
	(gr_line
		(start 93.43898 -77.968094)
		(end 93.43898 -78.561184)
		(stroke
			(width 2.032)
			(type default)
		)
		(layer "In1.Cu")
	)
	(gr_line
		(start 93.611192 -479.571304)
		(end 93.291914 -479.571304)
		(stroke
			(width 0.254)
			(type default)
		)
		(layer "In1.Cu")
	)
	(gr_line
		(start 93.758512 -78.880716)
		(end 94.055184 -78.584044)
		(stroke
			(width 2.032)
			(type default)
		)
		(layer "In1.Cu")
	)
	(gr_line
		(start 93.769942 -78.299056)
		(end 93.43898 -77.968094)
		(stroke
			(width 2.032)
			(type default)
		)
		(layer "In1.Cu")
	)
	(gr_circle
		(center 93.998034 -78.390242)
		(end 95.655384 -78.390242)
		(stroke
			(width 1.27)
			(type default)
		)
		(fill no)
		(layer "In1.Cu")
	)
	(gr_circle
		(center 93.999812 -78.300072)
		(end 96.60001 -78.300072)
		(stroke
			(width 1.016)
			(type default)
		)
		(fill no)
		(layer "In1.Cu")
	)
	(gr_line
		(start 94.055184 -78.584044)
		(end 94.055184 -78.20787)
		(stroke
			(width 2.032)
			(type default)
		)
		(layer "In1.Cu")
	)
	(gr_line
		(start 94.055184 -78.299056)
		(end 93.769942 -78.299056)
		(stroke
			(width 2.032)
			(type default)
		)
		(layer "In1.Cu")
	)
	(gr_line
		(start 94.055184 -78.20787)
		(end 94.465902 -77.797152)
		(stroke
			(width 2.032)
			(type default)
		)
		(layer "In1.Cu")
	)
	(gr_line
		(start 94.078806 -478.315782)
		(end 94.078806 -478.258886)
		(stroke
			(width 1.27)
			(type default)
		)
		(layer "In1.Cu")
	)
	(gr_line
		(start 94.078806 -478.315782)
		(end 94.181422 -478.315782)
		(stroke
			(width 1.27)
			(type default)
		)
		(layer "In1.Cu")
	)
	(gr_line
		(start 94.078806 -478.258886)
		(end 94.204282 -478.13341)
		(stroke
			(width 1.27)
			(type default)
		)
		(layer "In1.Cu")
	)
	(gr_circle
		(center 94.124018 -478.236026)
		(end 96.287082 -478.236026)
		(stroke
			(width 1.27)
			(type default)
		)
		(fill no)
		(layer "In1.Cu")
	)
	(gr_line
		(start 94.181422 -478.315782)
		(end 94.204282 -478.292922)
		(stroke
			(width 1.27)
			(type default)
		)
		(layer "In1.Cu")
	)
	(gr_circle
		(center 94.192852 -478.190306)
		(end 95.235522 -478.190306)
		(stroke
			(width 1.27)
			(type default)
		)
		(fill no)
		(layer "In1.Cu")
	)
	(gr_line
		(start 94.204282 -478.190306)
		(end 94.078806 -478.315782)
		(stroke
			(width 1.27)
			(type default)
		)
		(layer "In1.Cu")
	)
	(gr_line
		(start 94.204282 -478.13341)
		(end 94.204282 -478.190306)
		(stroke
			(width 1.27)
			(type default)
		)
		(layer "In1.Cu")
	)
	(gr_line
		(start 94.465902 -77.888338)
		(end 94.055184 -78.299056)
		(stroke
			(width 2.032)
			(type default)
		)
		(layer "In1.Cu")
	)
	(gr_line
		(start 94.465902 -77.797152)
		(end 94.465902 -77.888338)
		(stroke
			(width 2.032)
			(type default)
		)
		(layer "In1.Cu")
	)
	(gr_line
		(start 101.000052 -529.999956)
		(end 26.500074 -529.999956)
		(stroke
			(width 1.016)
			(type default)
		)
		(layer "In1.Cu")
	)
	(gr_arc
		(start 101.000052 -529.999956)
		(mid 102.41428 -529.414185)
		(end 103.000048 -527.99996)
		(stroke
			(width 1.016)
			(type default)
		)
		(layer "In1.Cu")
	)
	(gr_arc
		(start 103.000048 -1.999996)
		(mid 102.414258 -0.585805)
		(end 101.000052 0)
		(stroke
			(width 1.016)
			(type default)
		)
		(layer "In1.Cu")
	)
	(gr_line
		(start 103.000048 -1.999996)
		(end 103.000048 -527.99996)
		(stroke
			(width 1.016)
			(type default)
		)
		(layer "In1.Cu")
	)
	(gr_poly
		(pts
			(arc
				(start 0.888492 -405.748236)
				(mid 0.978295 -405.711039)
				(end 1.015492 -405.621236)
			)
			(xy 1.015492 -290.50996) (xy 0.91694 -290.411408) (xy 0.91694 -289.099244) (xy 1.015492 -289.000692)
			(xy 1.015492 -135.77697) (xy 0.509016 -135.77697)
			(arc
				(start 0.509016 -405.621236)
				(mid 0.546213 -405.711039)
				(end 0.636016 -405.748236)
			)
		)
		(stroke
			(width 0)
			(type solid)
		)
		(fill yes)
		(layer "In2.Cu")
		(net "GND")
	)
	(gr_poly
		(pts
			(arc
				(start 15.505684 -328.68235)
				(mid 15.621254 -328.895313)
				(end 15.862808 -328.914506)
			)
			(arc
				(start 15.862808 -328.914506)
				(mid 15.914447 -328.895955)
				(end 15.968218 -328.885042)
			)
			(arc
				(start 15.968218 -328.885042)
				(mid 16.126354 -328.800758)
				(end 16.189452 -328.633074)
			)
			(xy 16.189452 -324.220332)
			(arc
				(start 13.50899 -321.539616)
				(mid 13.232225 -321.484564)
				(end 13.075412 -321.719194)
			)
			(xy 13.075412 -325.420228) (xy 15.505684 -327.850754)
		)
		(stroke
			(width 0)
			(type solid)
		)
		(fill yes)
		(layer "In2.Cu")
		(net "P12V")
	)
	(gr_poly
		(pts
			(arc
				(start 60.681616 -350.513142)
				(mid 60.736619 -350.23626)
				(end 60.501784 -350.079564)
			)
			(arc
				(start 49.390046 -350.079564)
				(mid 49.177584 -350.194367)
				(end 49.157382 -350.43491)
			)
			(arc
				(start 49.157382 -350.43491)
				(mid 49.223296 -350.836348)
				(end 49.089564 -351.220532)
			)
			(arc
				(start 49.089564 -351.220532)
				(mid 49.078073 -351.480688)
				(end 49.301654 -351.614232)
			)
			(xy 59.580272 -351.614232)
		)
		(stroke
			(width 0)
			(type solid)
		)
		(fill yes)
		(layer "In2.Cu")
		(net "P12V")
	)
	(gr_poly
		(pts
			(arc
				(start 63.898526 -262.931148)
				(mid 63.947181 -262.921564)
				(end 63.988442 -262.894064)
			)
			(arc
				(start 64.850772 -262.031734)
				(mid 64.905824 -261.754969)
				(end 64.671194 -261.598156)
			)
			(arc
				(start 50.658522 -261.598156)
				(mid 50.447311 -261.711067)
				(end 50.423826 -261.949438)
			)
			(arc
				(start 50.423826 -261.949438)
				(mid 50.486974 -262.264926)
				(end 50.424842 -262.580628)
			)
			(arc
				(start 50.424842 -262.580628)
				(mid 50.448801 -262.818572)
				(end 50.659792 -262.931148)
			)
		)
		(stroke
			(width 0)
			(type solid)
		)
		(fill yes)
		(layer "In2.Cu")
		(net "P12V")
	)
	(gr_poly
		(pts
			(arc
				(start 101.000052 -529.49094)
				(mid 102.054334 -529.054242)
				(end 102.491032 -527.99996)
			)
			(arc
				(start 102.491032 -1.999996)
				(mid 102.054334 -0.945714)
				(end 101.000052 -0.509016)
			)
			(arc
				(start 26.500074 -0.509016)
				(mid 25.799255 -0.799305)
				(end 25.508966 -1.500124)
			)
			(arc
				(start 25.508966 -2.500122)
				(mid 24.920577 -3.920619)
				(end 23.50008 -4.509008)
			)
			(arc
				(start 1.500124 -4.509008)
				(mid 0.799305 -4.799297)
				(end 0.509016 -5.500116)
			)
			(xy 0.509016 -132.686298) (xy 1.015492 -132.686298)
			(arc
				(start 1.015492 -5.514594)
				(mid 1.152021 -5.162357)
				(end 1.49987 -5.01523)
			)
			(xy 1.500124 -5.01523) (xy 1.500124 -5.015484) (xy 23.266908 -5.015484) (xy 23.266908 -5.01523)
			(arc
				(start 23.50008 -5.01523)
				(mid 25.278456 -4.278498)
				(end 26.015188 -2.500122)
			)
			(arc
				(start 26.015188 -1.500124)
				(mid 26.157044 -1.157273)
				(end 26.49982 -1.015238)
			)
			(xy 26.500074 -1.015238) (xy 26.500074 -1.015492)
			(arc
				(start 101.000052 -1.015492)
				(mid 101.696201 -1.303847)
				(end 101.984556 -1.999996)
			)
			(xy 101.984556 -486.544366) (xy 101.98481 -486.544366) (xy 101.98481 -486.547414) (xy 101.984556 -486.549954)
			(arc
				(start 101.984556 -527.99996)
				(mid 101.696201 -528.696109)
				(end 101.000052 -528.984464)
			)
			(xy 26.500074 -528.984464) (xy 26.500074 -528.984718)
			(arc
				(start 26.49982 -528.984718)
				(mid 26.157133 -528.842773)
				(end 26.015188 -528.500086)
			)
			(arc
				(start 26.015188 -527.500088)
				(mid 25.8238 -526.537447)
				(end 25.278588 -525.721326)
			)
			(arc
				(start 25.278588 -525.721326)
				(mid 24.462617 -525.176018)
				(end 23.50008 -524.984472)
			)
			(arc
				(start 1.514856 -524.984472)
				(mid 1.321364 -524.950629)
				(end 1.157224 -524.84274)
			)
			(arc
				(start 1.157224 -524.84274)
				(mid 1.052318 -524.685503)
				(end 1.015492 -524.500094)
			)
			(arc
				(start 1.015492 -408.683206)
				(mid 0.978295 -408.593403)
				(end 0.888492 -408.556206)
			)
			(arc
				(start 0.636016 -408.556206)
				(mid 0.546213 -408.593403)
				(end 0.509016 -408.683206)
			)
			(arc
				(start 0.509016 -524.500094)
				(mid 0.79923 -525.200734)
				(end 1.49987 -525.490948)
			)
			(arc
				(start 23.50008 -525.490948)
				(mid 24.920667 -526.079427)
				(end 25.508966 -527.500088)
			)
			(arc
				(start 25.508966 -528.500086)
				(mid 25.799345 -529.200741)
				(end 26.500074 -529.49094)
			)
		)
		(stroke
			(width 0)
			(type solid)
		)
		(fill yes)
		(layer "In2.Cu")
		(net "GND")
	)
	(gr_poly
		(pts
			(xy 2.528824 -192.410334) (xy 2.538411 -192.430518) (xy 2.563575 -192.467438) (xy 2.594808 -192.499387)
			(xy 2.631147 -192.525382) (xy 2.671473 -192.54462) (xy 2.714542 -192.556509) (xy 2.759027 -192.560682)
			(xy 2.803555 -192.557011) (xy 2.846756 -192.545608) (xy 2.887296 -192.526825) (xy 2.923926 -192.501241)
			(xy 2.94005 -192.485772) (xy 3.242818 -192.183004) (xy 3.291078 -192.183004) (xy 3.307735 -192.182512)
			(xy 3.339915 -192.173895) (xy 3.368767 -192.157242) (xy 3.392326 -192.133688) (xy 3.408985 -192.104839)
			(xy 3.417609 -192.072661) (xy 3.418078 -192.056004) (xy 3.418078 -192.02146) (xy 3.400552 -191.991742)
			(xy 3.382818 -191.960505) (xy 3.353714 -191.894832) (xy 3.332202 -191.826297) (xy 3.318555 -191.755772)
			(xy 3.312948 -191.684158) (xy 3.315453 -191.612369) (xy 3.326037 -191.541321) (xy 3.344566 -191.471919)
			(xy 3.370802 -191.405049) (xy 3.404412 -191.341564) (xy 3.444967 -191.282274) (xy 3.491949 -191.227936)
			(xy 3.544759 -191.179242) (xy 3.602723 -191.136815) (xy 3.665102 -191.101194) (xy 3.731099 -191.072835)
			(xy 3.799874 -191.052099) (xy 3.870549 -191.039251) (xy 3.942221 -191.034454) (xy 4.013977 -191.037771)
			(xy 4.084902 -191.049158) (xy 4.15409 -191.06847) (xy 4.220659 -191.095461) (xy 4.283759 -191.129787)
			(xy 4.342586 -191.17101) (xy 4.369816 -191.194436) (xy 4.386088 -191.208219) (xy 4.422317 -191.230706)
			(xy 4.461791 -191.246832) (xy 4.503403 -191.256143) (xy 4.545985 -191.25838) (xy 4.588343 -191.253478)
			(xy 4.629289 -191.241576) (xy 4.667675 -191.223007) (xy 4.702423 -191.198293) (xy 4.717796 -191.183514)
			(xy 5.866384 -190.034926) (xy 5.881116 -189.958472) (xy 5.865368 -189.922404) (xy 5.85179 -189.889756)
			(xy 5.831127 -189.82213) (xy 5.8181 -189.752629) (xy 5.812869 -189.682111) (xy 5.815499 -189.611448)
			(xy 5.825959 -189.541514) (xy 5.844117 -189.473173) (xy 5.869751 -189.407271) (xy 5.902543 -189.344623)
			(xy 5.942087 -189.286002) (xy 5.987895 -189.232133) (xy 6.039401 -189.183684) (xy 6.095966 -189.141252)
			(xy 6.156893 -189.105362) (xy 6.221428 -189.076459) (xy 6.288773 -189.054899) (xy 6.358095 -189.040948)
			(xy 6.428538 -189.034781) (xy 6.499229 -189.036471) (xy 6.569296 -189.046) (xy 6.637872 -189.063249)
			(xy 6.704109 -189.088004) (xy 6.767188 -189.11996) (xy 6.826329 -189.158722) (xy 6.880802 -189.20381)
			(xy 6.929932 -189.254666) (xy 6.973112 -189.310663) (xy 7.009808 -189.371108) (xy 7.025132 -189.402974)
			(xy 7.034905 -189.422924) (xy 7.060337 -189.459344) (xy 7.091711 -189.49079) (xy 7.128073 -189.516305)
			(xy 7.168315 -189.535113) (xy 7.211214 -189.546642) (xy 7.255463 -189.55054) (xy 7.299717 -189.546689)
			(xy 7.342628 -189.535207) (xy 7.38289 -189.516442) (xy 7.419279 -189.490966) (xy 7.435342 -189.475618)
			(xy 7.697978 -189.212728) (xy 7.809484 -189.212728) (xy 7.826135 -189.212187) (xy 7.858304 -189.203572)
			(xy 7.887147 -189.186926) (xy 7.910699 -189.163382) (xy 7.927355 -189.134544) (xy 7.935981 -189.102379)
			(xy 7.936484 -189.085728) (xy 7.936484 -189.048136) (xy 7.91591 -189.01664) (xy 7.896926 -188.986498)
			(xy 7.865048 -188.922791) (xy 7.840495 -188.855919) (xy 7.823573 -188.786721) (xy 7.814495 -188.716064)
			(xy 7.813376 -188.644835) (xy 7.820228 -188.573928) (xy 7.834967 -188.504233) (xy 7.857407 -188.436622)
			(xy 7.887267 -188.371945) (xy 7.924173 -188.311012) (xy 7.96766 -188.254589) (xy 8.017185 -188.203383)
			(xy 8.072125 -188.158036) (xy 8.131791 -188.119117) (xy 8.195435 -188.087114) (xy 8.262259 -188.062429)
			(xy 8.331424 -188.045372) (xy 8.402063 -188.036156) (xy 8.473289 -188.034897) (xy 8.544209 -188.04161)
			(xy 8.613934 -188.056213) (xy 8.681588 -188.07852) (xy 8.746324 -188.108253) (xy 8.807329 -188.145039)
			(xy 8.863837 -188.188416) (xy 8.91514 -188.23784) (xy 8.960595 -188.292691) (xy 8.999631 -188.352281)
			(xy 9.031758 -188.415863) (xy 9.056574 -188.482638) (xy 9.073767 -188.551769) (xy 9.083121 -188.62239)
			(xy 9.08431 -188.657992) (xy 9.085072 -188.7093) (xy 9.121394 -188.745368) (xy 9.133502 -188.756826)
			(xy 9.162337 -188.773536) (xy 9.19452 -188.782187) (xy 9.227846 -188.782187) (xy 9.260029 -188.773536)
			(xy 9.288864 -188.756826) (xy 9.300972 -188.745368) (xy 9.40562 -188.640974) (xy 9.40562 -178.03495)
			(xy 18.97888 -168.46169) (xy 18.97888 -132.213604) (xy 8.853932 -122.08891) (xy 8.853932 -114.563906)
			(xy 14.021816 -109.396276) (xy 14.021816 -109.175296) (xy 14.021356 -109.153068) (xy 14.013617 -109.109291)
			(xy 13.998377 -109.067529) (xy 13.9761 -109.029057) (xy 13.947466 -108.99505) (xy 13.913351 -108.966546)
			(xy 13.874794 -108.944415) (xy 13.832975 -108.929334) (xy 13.789168 -108.921761) (xy 13.744712 -108.92193)
			(xy 13.700965 -108.929834) (xy 13.679932 -108.937044) (xy 13.641523 -108.950654) (xy 13.562645 -108.971127)
			(xy 13.482134 -108.983732) (xy 13.400774 -108.988349) (xy 13.319354 -108.984931) (xy 13.238666 -108.973511)
			(xy 13.159495 -108.954202) (xy 13.082611 -108.92719) (xy 13.00876 -108.892738) (xy 12.938661 -108.851181)
			(xy 12.872995 -108.802923) (xy 12.8124 -108.748433) (xy 12.757465 -108.688241) (xy 12.708725 -108.622932)
			(xy 12.666653 -108.553141) (xy 12.631659 -108.479545) (xy 12.604081 -108.402862) (xy 12.584189 -108.323835)
			(xy 12.572176 -108.243234) (xy 12.568159 -108.161841) (xy 12.572176 -108.080449) (xy 12.584189 -107.999848)
			(xy 12.60408 -107.920821) (xy 12.631658 -107.844137) (xy 12.666652 -107.770542) (xy 12.708724 -107.70075)
			(xy 12.757463 -107.635441) (xy 12.812398 -107.575249) (xy 12.872992 -107.520759) (xy 12.938658 -107.472501)
			(xy 13.008758 -107.430943) (xy 13.082608 -107.396491) (xy 13.159493 -107.369479) (xy 13.238664 -107.350169)
			(xy 13.319351 -107.33875) (xy 13.400771 -107.335331) (xy 13.482132 -107.339947) (xy 13.562642 -107.352553)
			(xy 13.641521 -107.373025) (xy 13.679932 -107.386628) (xy 13.700946 -107.393886) (xy 13.744696 -107.401773)
			(xy 13.789151 -107.401926) (xy 13.832955 -107.394343) (xy 13.874771 -107.379253) (xy 13.913324 -107.357118)
			(xy 13.947437 -107.328613) (xy 13.97607 -107.294607) (xy 13.99835 -107.256137) (xy 14.013596 -107.214378)
			(xy 14.021344 -107.170603) (xy 14.021816 -107.148376) (xy 14.021816 -105.136442) (xy 10.457688 -101.572314)
			(xy 10.457688 -66.173604) (xy 13.45057 -63.180468) (xy 13.465743 -63.164652) (xy 13.490963 -63.12881)
			(xy 13.509655 -63.089172) (xy 13.521267 -63.046913) (xy 13.525452 -63.003288) (xy 13.522087 -62.959593)
			(xy 13.511271 -62.917123) (xy 13.493326 -62.877141) (xy 13.468784 -62.840832) (xy 13.438373 -62.809275)
			(xy 13.402998 -62.783406) (xy 13.363707 -62.763994) (xy 13.321666 -62.751614) (xy 13.299948 -62.748668)
			(xy 13.26001 -62.743571) (xy 13.181301 -62.726597) (xy 13.104617 -62.702047) (xy 13.030685 -62.670152)
			(xy 12.960206 -62.631216) (xy 12.893851 -62.585607) (xy 12.832247 -62.533759) (xy 12.77598 -62.476163)
			(xy 12.725584 -62.413367) (xy 12.681536 -62.345965) (xy 12.644255 -62.274597) (xy 12.614095 -62.199941)
			(xy 12.59134 -62.122705) (xy 12.576208 -62.043621) (xy 12.568842 -61.96344) (xy 12.569312 -61.882923)
			(xy 12.577613 -61.802834) (xy 12.593667 -61.723932) (xy 12.617321 -61.646967) (xy 12.648352 -61.572668)
			(xy 12.686463 -61.50174) (xy 12.731294 -61.434857) (xy 12.78242 -61.372653) (xy 12.839355 -61.315718)
			(xy 12.90156 -61.264592) (xy 12.968443 -61.219761) (xy 13.039371 -61.18165) (xy 13.11367 -61.15062)
			(xy 13.190636 -61.126966) (xy 13.269538 -61.110913) (xy 13.349627 -61.102612) (xy 13.430144 -61.102142)
			(xy 13.510325 -61.109509) (xy 13.589408 -61.124641) (xy 13.666645 -61.147396) (xy 13.741301 -61.177557)
			(xy 13.812668 -61.214838) (xy 13.88007 -61.258886) (xy 13.942866 -61.309283) (xy 14.000461 -61.36555)
			(xy 14.052309 -61.427154) (xy 14.097918 -61.493509) (xy 14.136854 -61.563988) (xy 14.168748 -61.63792)
			(xy 14.193298 -61.714604) (xy 14.210271 -61.793313) (xy 14.215364 -61.833252) (xy 14.218326 -61.854963)
			(xy 14.23073 -61.896986) (xy 14.250158 -61.936259) (xy 14.276034 -61.971616) (xy 14.307592 -62.002012)
			(xy 14.343896 -62.026543) (xy 14.383869 -62.044484) (xy 14.426328 -62.055302) (xy 14.470013 -62.058677)
			(xy 14.513629 -62.054509) (xy 14.555884 -62.042921) (xy 14.595525 -62.024256) (xy 14.631377 -61.999069)
			(xy 14.647164 -61.983874) (xy 16.551148 -60.080144) (xy 16.551148 -47.895002) (xy 16.55065 -47.87208)
			(xy 16.542415 -47.826983) (xy 16.526228 -47.784092) (xy 16.502615 -47.744798) (xy 16.47234 -47.710373)
			(xy 16.436385 -47.681933) (xy 16.395914 -47.660399) (xy 16.352238 -47.64647) (xy 16.306772 -47.640595)
			(xy 16.26099 -47.642966) (xy 16.216375 -47.653506) (xy 16.174371 -47.671873) (xy 16.136341 -47.697472)
			(xy 16.119602 -47.713138) (xy 16.073268 -47.757663) (xy 15.975922 -47.84157) (xy 15.87359 -47.919316)
			(xy 15.766659 -47.990607) (xy 15.655538 -48.05517) (xy 15.540648 -48.112762) (xy 15.422427 -48.163161)
			(xy 15.301323 -48.206178) (xy 15.177798 -48.241647) (xy 15.052322 -48.269435) (xy 14.925372 -48.289436)
			(xy 14.79743 -48.301573) (xy 14.668983 -48.305801) (xy 14.54052 -48.302102) (xy 14.412529 -48.290492)
			(xy 14.285497 -48.271015) (xy 14.159908 -48.243744) (xy 14.036238 -48.208784) (xy 13.914958 -48.166267)
			(xy 13.79653 -48.116355) (xy 13.681404 -48.059237) (xy 13.570017 -47.995132) (xy 13.462794 -47.924283)
			(xy 13.360142 -47.846958) (xy 13.262452 -47.763454) (xy 13.170094 -47.674086) (xy 13.083422 -47.579195)
			(xy 13.002763 -47.479142) (xy 12.928425 -47.374308) (xy 12.86069 -47.26509) (xy 12.799817 -47.151905)
			(xy 12.746036 -47.035182) (xy 12.699553 -46.915367) (xy 12.660544 -46.792914) (xy 12.629157 -46.668289)
			(xy 12.605511 -46.541967) (xy 12.589698 -46.414427) (xy 12.581776 -46.286155) (xy 12.581776 -46.157639)
			(xy 12.589698 -46.029367) (xy 12.605512 -45.901827) (xy 12.629158 -45.775505) (xy 12.660545 -45.650881)
			(xy 12.699555 -45.528428) (xy 12.746039 -45.408612) (xy 12.79982 -45.29189) (xy 12.860693 -45.178705)
			(xy 12.928428 -45.069488) (xy 13.002766 -44.964653) (xy 13.083425 -44.864601) (xy 13.170098 -44.76971)
			(xy 13.262456 -44.680343) (xy 13.360147 -44.596838) (xy 13.462799 -44.519514) (xy 13.570022 -44.448665)
			(xy 13.681409 -44.38456) (xy 13.796535 -44.327443) (xy 13.914963 -44.277531) (xy 14.036243 -44.235014)
			(xy 14.159913 -44.200054) (xy 14.285503 -44.172784) (xy 14.412535 -44.153307) (xy 14.540525 -44.141697)
			(xy 14.668989 -44.137999) (xy 14.797435 -44.142227) (xy 14.925377 -44.154365) (xy 15.052328 -44.174366)
			(xy 15.177804 -44.202154) (xy 15.301328 -44.237624) (xy 15.422432 -44.280641) (xy 15.540653 -44.331041)
			(xy 15.655543 -44.388632) (xy 15.766664 -44.453196) (xy 15.873594 -44.524487) (xy 15.975927 -44.602234)
			(xy 16.073272 -44.686141) (xy 16.119602 -44.73067) (xy 16.136346 -44.746343) (xy 16.174365 -44.771985)
			(xy 16.216368 -44.790389) (xy 16.260991 -44.800957) (xy 16.306787 -44.803347) (xy 16.352268 -44.797481)
			(xy 16.395959 -44.783549) (xy 16.43644 -44.762004) (xy 16.472399 -44.733544) (xy 16.502667 -44.699095)
			(xy 16.526263 -44.659773) (xy 16.54242 -44.616855) (xy 16.550614 -44.571735) (xy 16.551148 -44.548806)
			(xy 16.551148 -40.972232) (xy 9.114028 -33.535366) (xy 9.114028 -12.66698) (xy 6.145784 -9.698736)
			(xy 6.133165 -9.686972) (xy 6.10312 -9.670046) (xy 6.069646 -9.661757) (xy 6.035175 -9.662706) (xy 6.01853 -9.66724)
			(xy 5.979056 -9.678899) (xy 5.898384 -9.69525) (xy 5.816485 -9.703497) (xy 5.734172 -9.703556) (xy 5.652261 -9.695429)
			(xy 5.571565 -9.679194) (xy 5.492884 -9.655014) (xy 5.416998 -9.623127) (xy 5.34466 -9.583851) (xy 5.276587 -9.537574)
			(xy 5.213454 -9.484757) (xy 5.155888 -9.425921) (xy 5.10446 -9.361652) (xy 5.059679 -9.292586) (xy 5.021989 -9.219409)
			(xy 4.991765 -9.142846) (xy 4.969306 -9.063656) (xy 4.954835 -8.982625) (xy 4.948495 -8.900557) (xy 4.95035 -8.818264)
			(xy 4.96038 -8.736565) (xy 4.978487 -8.656268) (xy 5.004491 -8.578171) (xy 5.038134 -8.503047) (xy 5.079081 -8.431641)
			(xy 5.126928 -8.364663) (xy 5.1812 -8.302776) (xy 5.241358 -8.246594) (xy 5.306806 -8.196674) (xy 5.376894 -8.153511)
			(xy 5.450928 -8.117534) (xy 5.528174 -8.089098) (xy 5.607865 -8.068487) (xy 5.68921 -8.055904) (xy 5.771404 -8.051475)
			(xy 5.85363 -8.055242) (xy 5.935075 -8.06717) (xy 6.014929 -8.087139) (xy 6.053836 -8.100568) (xy 6.067475 -8.105067)
			(xy 6.095986 -8.108472) (xy 6.124533 -8.105388) (xy 6.151659 -8.095974) (xy 6.175979 -8.08071) (xy 6.186424 -8.07085)
			(xy 6.197796 -8.058689) (xy 6.214418 -8.029854) (xy 6.223022 -7.997702) (xy 6.223022 -7.964419) (xy 6.214419 -7.932268)
			(xy 6.197797 -7.903432) (xy 6.186424 -7.891272) (xy 6.066028 -7.770876) (xy 5.487924 -7.770876) (xy 4.875784 -7.158736)
			(xy 4.863165 -7.146972) (xy 4.83312 -7.130046) (xy 4.799646 -7.121757) (xy 4.765175 -7.122706) (xy 4.74853 -7.12724)
			(xy 4.709984 -7.138643) (xy 4.631235 -7.154794) (xy 4.551289 -7.163218) (xy 4.470903 -7.163837) (xy 4.390837 -7.156645)
			(xy 4.311849 -7.141709) (xy 4.234684 -7.11917) (xy 4.160074 -7.089243) (xy 4.088724 -7.05221) (xy 4.021309 -7.008421)
			(xy 3.958466 -6.958291) (xy 3.900789 -6.902293) (xy 3.848825 -6.840958) (xy 3.803065 -6.774865) (xy 3.763941 -6.704639)
			(xy 3.731824 -6.630945) (xy 3.707017 -6.55448) (xy 3.689756 -6.475967) (xy 3.680202 -6.396148) (xy 3.678447 -6.315779)
			(xy 3.684507 -6.235619) (xy 3.698326 -6.156428) (xy 3.719771 -6.078952) (xy 3.748641 -6.003927) (xy 3.784662 -5.93206)
			(xy 3.827493 -5.864033) (xy 3.87673 -5.800488) (xy 3.931907 -5.742026) (xy 3.961892 -5.715254) (xy 3.978152 -5.700437)
			(xy 4.005808 -5.666233) (xy 4.027161 -5.627776) (xy 4.041571 -5.586217) (xy 4.048608 -5.542797) (xy 4.048063 -5.498814)
			(xy 4.03995 -5.455582) (xy 4.024513 -5.414393) (xy 4.002213 -5.376478) (xy 3.973717 -5.34297) (xy 3.939875 -5.314871)
			(xy 3.9017 -5.29302) (xy 3.860332 -5.27807) (xy 3.817007 -5.270468) (xy 3.795014 -5.269992) (xy 1.510792 -5.269992)
			(xy 1.489645 -5.26946) (xy 1.447739 -5.275188) (xy 1.407583 -5.288472) (xy 1.370528 -5.308865) (xy 1.337819 -5.335681)
			(xy 1.310557 -5.368018) (xy 1.289658 -5.40479) (xy 1.275824 -5.44476) (xy 1.269521 -5.486583) (xy 1.269746 -5.507736)
			(xy 1.27 -5.512054) (xy 1.27 -13.635482) (xy 1.270551 -13.658845) (xy 1.279134 -13.704775) (xy 1.29597 -13.748363)
			(xy 1.320491 -13.788138) (xy 1.351871 -13.822759) (xy 1.389051 -13.85106) (xy 1.430779 -13.872086)
			(xy 1.475648 -13.885128) (xy 1.522145 -13.889748) (xy 1.568703 -13.885788) (xy 1.613752 -13.873383)
			(xy 1.655774 -13.852951) (xy 1.693353 -13.825181) (xy 1.709674 -13.808456) (xy 1.754144 -13.76142)
			(xy 1.848063 -13.672323) (xy 1.947333 -13.58923) (xy 2.051571 -13.512461) (xy 2.160374 -13.442312)
			(xy 2.273323 -13.379054) (xy 2.389981 -13.322931) (xy 2.509899 -13.274159) (xy 2.632614 -13.232928)
			(xy 2.757652 -13.199394) (xy 2.88453 -13.17369) (xy 3.01276 -13.155912) (xy 3.141847 -13.146131)
			(xy 3.271292 -13.144383) (xy 3.400595 -13.150676) (xy 3.529258 -13.164985) (xy 3.656785 -13.187255)
			(xy 3.782683 -13.2174) (xy 3.906466 -13.255304) (xy 4.027657 -13.30082) (xy 4.145788 -13.353773)
			(xy 4.260403 -13.413959) (xy 4.37106 -13.481145) (xy 4.477332 -13.555072) (xy 4.57881 -13.635454)
			(xy 4.6751 -13.721983) (xy 4.765832 -13.814323) (xy 4.850656 -13.912118) (xy 4.929244 -14.014991)
			(xy 5.001293 -14.122545) (xy 5.066525 -14.234365) (xy 5.124689 -14.35002) (xy 5.175559 -14.469063)
			(xy 5.21894 -14.591034) (xy 5.254664 -14.715464) (xy 5.282593 -14.841872) (xy 5.30262 -14.96977)
			(xy 5.314668 -15.098665) (xy 5.318688 -15.228059) (xy 5.314668 -15.357453) (xy 5.302621 -15.486347)
			(xy 5.282594 -15.614245) (xy 5.254665 -15.740653) (xy 5.218941 -15.865083) (xy 5.17556 -15.987055)
			(xy 5.12469 -16.106097) (xy 5.066527 -16.221752) (xy 5.001295 -16.333572) (xy 4.929246 -16.441127)
			(xy 4.850658 -16.544) (xy 4.765834 -16.641795) (xy 4.675102 -16.734135) (xy 4.578812 -16.820664)
			(xy 4.477335 -16.901046) (xy 4.371063 -16.974974) (xy 4.260405 -17.04216) (xy 4.14579 -17.102345)
			(xy 4.027659 -17.155299) (xy 3.906468 -17.200815) (xy 3.782685 -17.238719) (xy 3.656788 -17.268865)
			(xy 3.529261 -17.291135) (xy 3.400598 -17.305444) (xy 3.271294 -17.311737) (xy 3.14185 -17.309989)
			(xy 3.012763 -17.300208) (xy 2.884533 -17.282431) (xy 2.757654 -17.256726) (xy 2.632616 -17.223193)
			(xy 2.509902 -17.181962) (xy 2.389984 -17.13319) (xy 2.273325 -17.077067) (xy 2.160376 -17.013809)
			(xy 2.051573 -16.94366) (xy 1.947336 -16.866891) (xy 1.848066 -16.783798) (xy 1.754146 -16.694702)
			(xy 1.709674 -16.647668) (xy 1.693349 -16.630952) (xy 1.655768 -16.603199) (xy 1.613748 -16.582782)
			(xy 1.568705 -16.570389) (xy 1.522154 -16.566437) (xy 1.475666 -16.57106) (xy 1.430806 -16.584102)
			(xy 1.389084 -16.605123) (xy 1.351908 -16.633415) (xy 1.320529 -16.668026) (xy 1.296004 -16.707788)
			(xy 1.27916 -16.751364) (xy 1.270564 -16.797284) (xy 1.27 -16.820642) (xy 1.27 -44.629324) (xy 1.270551 -44.652686)
			(xy 1.279134 -44.698617) (xy 1.29597 -44.742204) (xy 1.320492 -44.781979) (xy 1.351871 -44.8166)
			(xy 1.389052 -44.8449) (xy 1.430779 -44.865926) (xy 1.475648 -44.878968) (xy 1.522145 -44.883588)
			(xy 1.568703 -44.879628) (xy 1.613752 -44.867224) (xy 1.655774 -44.846792) (xy 1.693352 -44.819022)
			(xy 1.709674 -44.802298) (xy 1.754144 -44.755262) (xy 1.848064 -44.666165) (xy 1.947334 -44.583072)
			(xy 2.051571 -44.506303) (xy 2.160374 -44.436154) (xy 2.273323 -44.372896) (xy 2.389982 -44.316773)
			(xy 2.5099 -44.268002) (xy 2.632615 -44.22677) (xy 2.757653 -44.193237) (xy 2.884532 -44.167532)
			(xy 3.012762 -44.149755) (xy 3.141848 -44.139973) (xy 3.271293 -44.138226) (xy 3.400597 -44.144519)
			(xy 3.52926 -44.158828) (xy 3.656786 -44.181098) (xy 3.782684 -44.211243) (xy 3.906468 -44.249147)
			(xy 4.027658 -44.294663) (xy 4.14579 -44.347617) (xy 4.260405 -44.407802) (xy 4.371062 -44.474989)
			(xy 4.477334 -44.548916) (xy 4.578812 -44.629298) (xy 4.675102 -44.715827) (xy 4.765834 -44.808167)
			(xy 4.850658 -44.905962) (xy 4.929246 -45.008835) (xy 5.001295 -45.11639) (xy 5.066527 -45.22821)
			(xy 5.124691 -45.343865) (xy 5.175561 -45.462908) (xy 5.218942 -45.584879) (xy 5.254666 -45.709309)
			(xy 5.282595 -45.835717) (xy 5.302622 -45.963615) (xy 5.314669 -46.09251) (xy 5.31869 -46.221904)
			(xy 5.314669 -46.351298) (xy 5.302622 -46.480193) (xy 5.282595 -46.608091) (xy 5.254666 -46.734499)
			(xy 5.218942 -46.858929) (xy 5.175561 -46.9809) (xy 5.124691 -47.099943) (xy 5.066527 -47.215598)
			(xy 5.001295 -47.327418) (xy 4.929246 -47.434973) (xy 4.850658 -47.537846) (xy 4.765834 -47.635641)
			(xy 4.675102 -47.727981) (xy 4.578812 -47.81451) (xy 4.477334 -47.894892) (xy 4.371062 -47.968819)
			(xy 4.260405 -48.036006) (xy 4.14579 -48.096191) (xy 4.027658 -48.149145) (xy 3.906468 -48.194661)
			(xy 3.782684 -48.232565) (xy 3.656786 -48.26271) (xy 3.52926 -48.28498) (xy 3.400597 -48.299289)
			(xy 3.271293 -48.305582) (xy 3.141848 -48.303835) (xy 3.012762 -48.294053) (xy 2.884532 -48.276276)
			(xy 2.757653 -48.250571) (xy 2.632615 -48.217038) (xy 2.5099 -48.175806) (xy 2.389982 -48.127035)
			(xy 2.273323 -48.070912) (xy 2.160374 -48.007654) (xy 2.051571 -47.937505) (xy 1.947334 -47.860736)
			(xy 1.848064 -47.777643) (xy 1.754144 -47.688546) (xy 1.709674 -47.64151) (xy 1.693349 -47.624794)
			(xy 1.655769 -47.597041) (xy 1.613749 -47.576624) (xy 1.568705 -47.56423) (xy 1.522155 -47.560278)
			(xy 1.475666 -47.564901) (xy 1.430806 -47.577943) (xy 1.389085 -47.598964) (xy 1.351908 -47.627257)
			(xy 1.320529 -47.661867) (xy 1.296005 -47.70163) (xy 1.279161 -47.745206) (xy 1.270565 -47.791126)
			(xy 1.27 -47.814484) (xy 1.27 -52.612459) (xy 3.67918 -52.612459) (xy 3.67918 -52.531349) (xy 3.68713 -52.45063)
			(xy 3.702953 -52.371079) (xy 3.726498 -52.293463) (xy 3.757537 -52.218527) (xy 3.795772 -52.146995)
			(xy 3.840834 -52.079555) (xy 3.892289 -52.016856) (xy 3.949642 -51.959503) (xy 4.012341 -51.908048)
			(xy 4.079781 -51.862986) (xy 4.151313 -51.824751) (xy 4.226249 -51.793712) (xy 4.303865 -51.770167)
			(xy 4.383416 -51.754344) (xy 4.464135 -51.746394) (xy 4.545245 -51.746394) (xy 4.625964 -51.754344)
			(xy 4.705515 -51.770167) (xy 4.783131 -51.793712) (xy 4.858067 -51.824751) (xy 4.929599 -51.862986)
			(xy 4.997039 -51.908048) (xy 5.059738 -51.959503) (xy 5.117091 -52.016856) (xy 5.168546 -52.079555)
			(xy 5.213608 -52.146995) (xy 5.251843 -52.218527) (xy 5.282882 -52.293463) (xy 5.306427 -52.371079)
			(xy 5.32225 -52.45063) (xy 5.3302 -52.531349) (xy 5.330698 -52.571904) (xy 5.3302 -52.612459) (xy 6.21918 -52.612459)
			(xy 6.21918 -52.531349) (xy 6.22713 -52.45063) (xy 6.242953 -52.371079) (xy 6.266498 -52.293463)
			(xy 6.297537 -52.218527) (xy 6.335772 -52.146995) (xy 6.380834 -52.079555) (xy 6.432289 -52.016856)
			(xy 6.489642 -51.959503) (xy 6.552341 -51.908048) (xy 6.619781 -51.862986) (xy 6.691313 -51.824751)
			(xy 6.766249 -51.793712) (xy 6.843865 -51.770167) (xy 6.923416 -51.754344) (xy 7.004135 -51.746394)
			(xy 7.085245 -51.746394) (xy 7.165964 -51.754344) (xy 7.245515 -51.770167) (xy 7.323131 -51.793712)
			(xy 7.398067 -51.824751) (xy 7.469599 -51.862986) (xy 7.537039 -51.908048) (xy 7.599738 -51.959503)
			(xy 7.657091 -52.016856) (xy 7.708546 -52.079555) (xy 7.753608 -52.146995) (xy 7.791843 -52.218527)
			(xy 7.822882 -52.293463) (xy 7.846427 -52.371079) (xy 7.86225 -52.45063) (xy 7.8702 -52.531349) (xy 7.870698 -52.571904)
			(xy 7.8702 -52.612459) (xy 8.75918 -52.612459) (xy 8.75918 -52.531349) (xy 8.76713 -52.45063) (xy 8.782953 -52.371079)
			(xy 8.806498 -52.293463) (xy 8.837537 -52.218527) (xy 8.875772 -52.146995) (xy 8.920834 -52.079555)
			(xy 8.972289 -52.016856) (xy 9.029642 -51.959503) (xy 9.092341 -51.908048) (xy 9.159781 -51.862986)
			(xy 9.231313 -51.824751) (xy 9.306249 -51.793712) (xy 9.383865 -51.770167) (xy 9.463416 -51.754344)
			(xy 9.544135 -51.746394) (xy 9.625245 -51.746394) (xy 9.705964 -51.754344) (xy 9.785515 -51.770167)
			(xy 9.863131 -51.793712) (xy 9.938067 -51.824751) (xy 10.009599 -51.862986) (xy 10.077039 -51.908048)
			(xy 10.139738 -51.959503) (xy 10.197091 -52.016856) (xy 10.248546 -52.079555) (xy 10.293608 -52.146995)
			(xy 10.331843 -52.218527) (xy 10.362882 -52.293463) (xy 10.386427 -52.371079) (xy 10.40225 -52.45063)
			(xy 10.4102 -52.531349) (xy 10.410698 -52.571904) (xy 10.4102 -52.612459) (xy 11.29918 -52.612459)
			(xy 11.29918 -52.531349) (xy 11.30713 -52.45063) (xy 11.322953 -52.371079) (xy 11.346498 -52.293463)
			(xy 11.377537 -52.218527) (xy 11.415772 -52.146995) (xy 11.460834 -52.079555) (xy 11.512289 -52.016856)
			(xy 11.569642 -51.959503) (xy 11.632341 -51.908048) (xy 11.699781 -51.862986) (xy 11.771313 -51.824751)
			(xy 11.846249 -51.793712) (xy 11.923865 -51.770167) (xy 12.003416 -51.754344) (xy 12.084135 -51.746394)
			(xy 12.165245 -51.746394) (xy 12.245964 -51.754344) (xy 12.325515 -51.770167) (xy 12.403131 -51.793712)
			(xy 12.478067 -51.824751) (xy 12.549599 -51.862986) (xy 12.617039 -51.908048) (xy 12.679738 -51.959503)
			(xy 12.737091 -52.016856) (xy 12.788546 -52.079555) (xy 12.833608 -52.146995) (xy 12.871843 -52.218527)
			(xy 12.902882 -52.293463) (xy 12.926427 -52.371079) (xy 12.94225 -52.45063) (xy 12.9502 -52.531349)
			(xy 12.950698 -52.571904) (xy 12.9502 -52.612459) (xy 12.94225 -52.693178) (xy 12.926427 -52.772729)
			(xy 12.902882 -52.850345) (xy 12.871843 -52.925281) (xy 12.833608 -52.996813) (xy 12.788546 -53.064253)
			(xy 12.737091 -53.126952) (xy 12.679738 -53.184305) (xy 12.617039 -53.23576) (xy 12.549599 -53.280822)
			(xy 12.478067 -53.319057) (xy 12.403131 -53.350096) (xy 12.325515 -53.373641) (xy 12.245964 -53.389464)
			(xy 12.165245 -53.397414) (xy 12.084135 -53.397414) (xy 12.003416 -53.389464) (xy 11.923865 -53.373641)
			(xy 11.846249 -53.350096) (xy 11.771313 -53.319057) (xy 11.699781 -53.280822) (xy 11.632341 -53.23576)
			(xy 11.569642 -53.184305) (xy 11.512289 -53.126952) (xy 11.460834 -53.064253) (xy 11.415772 -52.996813)
			(xy 11.377537 -52.925281) (xy 11.346498 -52.850345) (xy 11.322953 -52.772729) (xy 11.30713 -52.693178)
			(xy 11.29918 -52.612459) (xy 10.4102 -52.612459) (xy 10.40225 -52.693178) (xy 10.386427 -52.772729)
			(xy 10.362882 -52.850345) (xy 10.331843 -52.925281) (xy 10.293608 -52.996813) (xy 10.248546 -53.064253)
			(xy 10.197091 -53.126952) (xy 10.139738 -53.184305) (xy 10.077039 -53.23576) (xy 10.009599 -53.280822)
			(xy 9.938067 -53.319057) (xy 9.863131 -53.350096) (xy 9.785515 -53.373641) (xy 9.705964 -53.389464)
			(xy 9.625245 -53.397414) (xy 9.544135 -53.397414) (xy 9.463416 -53.389464) (xy 9.383865 -53.373641)
			(xy 9.306249 -53.350096) (xy 9.231313 -53.319057) (xy 9.159781 -53.280822) (xy 9.092341 -53.23576)
			(xy 9.029642 -53.184305) (xy 8.972289 -53.126952) (xy 8.920834 -53.064253) (xy 8.875772 -52.996813)
			(xy 8.837537 -52.925281) (xy 8.806498 -52.850345) (xy 8.782953 -52.772729) (xy 8.76713 -52.693178)
			(xy 8.75918 -52.612459) (xy 7.8702 -52.612459) (xy 7.86225 -52.693178) (xy 7.846427 -52.772729) (xy 7.822882 -52.850345)
			(xy 7.791843 -52.925281) (xy 7.753608 -52.996813) (xy 7.708546 -53.064253) (xy 7.657091 -53.126952)
			(xy 7.599738 -53.184305) (xy 7.537039 -53.23576) (xy 7.469599 -53.280822) (xy 7.398067 -53.319057)
			(xy 7.323131 -53.350096) (xy 7.245515 -53.373641) (xy 7.165964 -53.389464) (xy 7.085245 -53.397414)
			(xy 7.004135 -53.397414) (xy 6.923416 -53.389464) (xy 6.843865 -53.373641) (xy 6.766249 -53.350096)
			(xy 6.691313 -53.319057) (xy 6.619781 -53.280822) (xy 6.552341 -53.23576) (xy 6.489642 -53.184305)
			(xy 6.432289 -53.126952) (xy 6.380834 -53.064253) (xy 6.335772 -52.996813) (xy 6.297537 -52.925281)
			(xy 6.266498 -52.850345) (xy 6.242953 -52.772729) (xy 6.22713 -52.693178) (xy 6.21918 -52.612459)
			(xy 5.3302 -52.612459) (xy 5.32225 -52.693178) (xy 5.306427 -52.772729) (xy 5.282882 -52.850345)
			(xy 5.251843 -52.925281) (xy 5.213608 -52.996813) (xy 5.168546 -53.064253) (xy 5.117091 -53.126952)
			(xy 5.059738 -53.184305) (xy 4.997039 -53.23576) (xy 4.929599 -53.280822) (xy 4.858067 -53.319057)
			(xy 4.783131 -53.350096) (xy 4.705515 -53.373641) (xy 4.625964 -53.389464) (xy 4.545245 -53.397414)
			(xy 4.464135 -53.397414) (xy 4.383416 -53.389464) (xy 4.303865 -53.373641) (xy 4.226249 -53.350096)
			(xy 4.151313 -53.319057) (xy 4.079781 -53.280822) (xy 4.012341 -53.23576) (xy 3.949642 -53.184305)
			(xy 3.892289 -53.126952) (xy 3.840834 -53.064253) (xy 3.795772 -52.996813) (xy 3.757537 -52.925281)
			(xy 3.726498 -52.850345) (xy 3.702953 -52.772729) (xy 3.68713 -52.693178) (xy 3.67918 -52.612459)
			(xy 1.27 -52.612459) (xy 1.27 -55.152459) (xy 4.94918 -55.152459) (xy 4.94918 -55.071349) (xy 4.95713 -54.99063)
			(xy 4.972953 -54.911079) (xy 4.996498 -54.833463) (xy 5.027537 -54.758527) (xy 5.065772 -54.686995)
			(xy 5.110834 -54.619555) (xy 5.162289 -54.556856) (xy 5.219642 -54.499503) (xy 5.282341 -54.448048)
			(xy 5.349781 -54.402986) (xy 5.421313 -54.364751) (xy 5.496249 -54.333712) (xy 5.573865 -54.310167)
			(xy 5.653416 -54.294344) (xy 5.734135 -54.286394) (xy 5.815245 -54.286394) (xy 5.895964 -54.294344)
			(xy 5.975515 -54.310167) (xy 6.053131 -54.333712) (xy 6.128067 -54.364751) (xy 6.199599 -54.402986)
			(xy 6.267039 -54.448048) (xy 6.329738 -54.499503) (xy 6.387091 -54.556856) (xy 6.438546 -54.619555)
			(xy 6.483608 -54.686995) (xy 6.521843 -54.758527) (xy 6.552882 -54.833463) (xy 6.576427 -54.911079)
			(xy 6.59225 -54.99063) (xy 6.6002 -55.071349) (xy 6.600698 -55.111904) (xy 6.6002 -55.152459) (xy 7.48918 -55.152459)
			(xy 7.48918 -55.071349) (xy 7.49713 -54.99063) (xy 7.512953 -54.911079) (xy 7.536498 -54.833463)
			(xy 7.567537 -54.758527) (xy 7.605772 -54.686995) (xy 7.650834 -54.619555) (xy 7.702289 -54.556856)
			(xy 7.759642 -54.499503) (xy 7.822341 -54.448048) (xy 7.889781 -54.402986) (xy 7.961313 -54.364751)
			(xy 8.036249 -54.333712) (xy 8.113865 -54.310167) (xy 8.193416 -54.294344) (xy 8.274135 -54.286394)
			(xy 8.355245 -54.286394) (xy 8.435964 -54.294344) (xy 8.515515 -54.310167) (xy 8.593131 -54.333712)
			(xy 8.668067 -54.364751) (xy 8.739599 -54.402986) (xy 8.807039 -54.448048) (xy 8.869738 -54.499503)
			(xy 8.927091 -54.556856) (xy 8.978546 -54.619555) (xy 9.023608 -54.686995) (xy 9.061843 -54.758527)
			(xy 9.092882 -54.833463) (xy 9.116427 -54.911079) (xy 9.13225 -54.99063) (xy 9.1402 -55.071349) (xy 9.140698 -55.111904)
			(xy 9.1402 -55.152459) (xy 10.02918 -55.152459) (xy 10.02918 -55.071349) (xy 10.03713 -54.99063)
			(xy 10.052953 -54.911079) (xy 10.076498 -54.833463) (xy 10.107537 -54.758527) (xy 10.145772 -54.686995)
			(xy 10.190834 -54.619555) (xy 10.242289 -54.556856) (xy 10.299642 -54.499503) (xy 10.362341 -54.448048)
			(xy 10.429781 -54.402986) (xy 10.501313 -54.364751) (xy 10.576249 -54.333712) (xy 10.653865 -54.310167)
			(xy 10.733416 -54.294344) (xy 10.814135 -54.286394) (xy 10.895245 -54.286394) (xy 10.975964 -54.294344)
			(xy 11.055515 -54.310167) (xy 11.133131 -54.333712) (xy 11.208067 -54.364751) (xy 11.279599 -54.402986)
			(xy 11.347039 -54.448048) (xy 11.409738 -54.499503) (xy 11.467091 -54.556856) (xy 11.518546 -54.619555)
			(xy 11.563608 -54.686995) (xy 11.601843 -54.758527) (xy 11.632882 -54.833463) (xy 11.656427 -54.911079)
			(xy 11.67225 -54.99063) (xy 11.6802 -55.071349) (xy 11.680698 -55.111904) (xy 11.6802 -55.152459)
			(xy 12.56918 -55.152459) (xy 12.56918 -55.071349) (xy 12.57713 -54.99063) (xy 12.592953 -54.911079)
			(xy 12.616498 -54.833463) (xy 12.647537 -54.758527) (xy 12.685772 -54.686995) (xy 12.730834 -54.619555)
			(xy 12.782289 -54.556856) (xy 12.839642 -54.499503) (xy 12.902341 -54.448048) (xy 12.969781 -54.402986)
			(xy 13.041313 -54.364751) (xy 13.116249 -54.333712) (xy 13.193865 -54.310167) (xy 13.273416 -54.294344)
			(xy 13.354135 -54.286394) (xy 13.435245 -54.286394) (xy 13.515964 -54.294344) (xy 13.595515 -54.310167)
			(xy 13.673131 -54.333712) (xy 13.748067 -54.364751) (xy 13.819599 -54.402986) (xy 13.887039 -54.448048)
			(xy 13.949738 -54.499503) (xy 14.007091 -54.556856) (xy 14.058546 -54.619555) (xy 14.103608 -54.686995)
			(xy 14.141843 -54.758527) (xy 14.172882 -54.833463) (xy 14.196427 -54.911079) (xy 14.21225 -54.99063)
			(xy 14.2202 -55.071349) (xy 14.220698 -55.111904) (xy 14.2202 -55.152459) (xy 14.21225 -55.233178)
			(xy 14.196427 -55.312729) (xy 14.172882 -55.390345) (xy 14.141843 -55.465281) (xy 14.103608 -55.536813)
			(xy 14.058546 -55.604253) (xy 14.007091 -55.666952) (xy 13.949738 -55.724305) (xy 13.887039 -55.77576)
			(xy 13.819599 -55.820822) (xy 13.748067 -55.859057) (xy 13.673131 -55.890096) (xy 13.595515 -55.913641)
			(xy 13.515964 -55.929464) (xy 13.435245 -55.937414) (xy 13.354135 -55.937414) (xy 13.273416 -55.929464)
			(xy 13.193865 -55.913641) (xy 13.116249 -55.890096) (xy 13.041313 -55.859057) (xy 12.969781 -55.820822)
			(xy 12.902341 -55.77576) (xy 12.839642 -55.724305) (xy 12.782289 -55.666952) (xy 12.730834 -55.604253)
			(xy 12.685772 -55.536813) (xy 12.647537 -55.465281) (xy 12.616498 -55.390345) (xy 12.592953 -55.312729)
			(xy 12.57713 -55.233178) (xy 12.56918 -55.152459) (xy 11.6802 -55.152459) (xy 11.67225 -55.233178)
			(xy 11.656427 -55.312729) (xy 11.632882 -55.390345) (xy 11.601843 -55.465281) (xy 11.563608 -55.536813)
			(xy 11.518546 -55.604253) (xy 11.467091 -55.666952) (xy 11.409738 -55.724305) (xy 11.347039 -55.77576)
			(xy 11.279599 -55.820822) (xy 11.208067 -55.859057) (xy 11.133131 -55.890096) (xy 11.055515 -55.913641)
			(xy 10.975964 -55.929464) (xy 10.895245 -55.937414) (xy 10.814135 -55.937414) (xy 10.733416 -55.929464)
			(xy 10.653865 -55.913641) (xy 10.576249 -55.890096) (xy 10.501313 -55.859057) (xy 10.429781 -55.820822)
			(xy 10.362341 -55.77576) (xy 10.299642 -55.724305) (xy 10.242289 -55.666952) (xy 10.190834 -55.604253)
			(xy 10.145772 -55.536813) (xy 10.107537 -55.465281) (xy 10.076498 -55.390345) (xy 10.052953 -55.312729)
			(xy 10.03713 -55.233178) (xy 10.02918 -55.152459) (xy 9.1402 -55.152459) (xy 9.13225 -55.233178)
			(xy 9.116427 -55.312729) (xy 9.092882 -55.390345) (xy 9.061843 -55.465281) (xy 9.023608 -55.536813)
			(xy 8.978546 -55.604253) (xy 8.927091 -55.666952) (xy 8.869738 -55.724305) (xy 8.807039 -55.77576)
			(xy 8.739599 -55.820822) (xy 8.668067 -55.859057) (xy 8.593131 -55.890096) (xy 8.515515 -55.913641)
			(xy 8.435964 -55.929464) (xy 8.355245 -55.937414) (xy 8.274135 -55.937414) (xy 8.193416 -55.929464)
			(xy 8.113865 -55.913641) (xy 8.036249 -55.890096) (xy 7.961313 -55.859057) (xy 7.889781 -55.820822)
			(xy 7.822341 -55.77576) (xy 7.759642 -55.724305) (xy 7.702289 -55.666952) (xy 7.650834 -55.604253)
			(xy 7.605772 -55.536813) (xy 7.567537 -55.465281) (xy 7.536498 -55.390345) (xy 7.512953 -55.312729)
			(xy 7.49713 -55.233178) (xy 7.48918 -55.152459) (xy 6.6002 -55.152459) (xy 6.59225 -55.233178) (xy 6.576427 -55.312729)
			(xy 6.552882 -55.390345) (xy 6.521843 -55.465281) (xy 6.483608 -55.536813) (xy 6.438546 -55.604253)
			(xy 6.387091 -55.666952) (xy 6.329738 -55.724305) (xy 6.267039 -55.77576) (xy 6.199599 -55.820822)
			(xy 6.128067 -55.859057) (xy 6.053131 -55.890096) (xy 5.975515 -55.913641) (xy 5.895964 -55.929464)
			(xy 5.815245 -55.937414) (xy 5.734135 -55.937414) (xy 5.653416 -55.929464) (xy 5.573865 -55.913641)
			(xy 5.496249 -55.890096) (xy 5.421313 -55.859057) (xy 5.349781 -55.820822) (xy 5.282341 -55.77576)
			(xy 5.219642 -55.724305) (xy 5.162289 -55.666952) (xy 5.110834 -55.604253) (xy 5.065772 -55.536813)
			(xy 5.027537 -55.465281) (xy 4.996498 -55.390345) (xy 4.972953 -55.312729) (xy 4.95713 -55.233178)
			(xy 4.94918 -55.152459) (xy 1.27 -55.152459) (xy 1.27 -59.428549) (xy 3.67918 -59.428549) (xy 3.67918 -59.347439)
			(xy 3.68713 -59.26672) (xy 3.702953 -59.187169) (xy 3.726498 -59.109553) (xy 3.757537 -59.034617)
			(xy 3.795772 -58.963085) (xy 3.840834 -58.895645) (xy 3.892289 -58.832946) (xy 3.949642 -58.775593)
			(xy 4.012341 -58.724138) (xy 4.079781 -58.679076) (xy 4.151313 -58.640841) (xy 4.226249 -58.609802)
			(xy 4.303865 -58.586257) (xy 4.383416 -58.570434) (xy 4.464135 -58.562484) (xy 4.545245 -58.562484)
			(xy 4.625964 -58.570434) (xy 4.705515 -58.586257) (xy 4.783131 -58.609802) (xy 4.858067 -58.640841)
			(xy 4.929599 -58.679076) (xy 4.997039 -58.724138) (xy 5.059738 -58.775593) (xy 5.117091 -58.832946)
			(xy 5.168546 -58.895645) (xy 5.213608 -58.963085) (xy 5.251843 -59.034617) (xy 5.282882 -59.109553)
			(xy 5.306427 -59.187169) (xy 5.32225 -59.26672) (xy 5.3302 -59.347439) (xy 5.330698 -59.387994) (xy 5.3302 -59.428549)
			(xy 6.21918 -59.428549) (xy 6.21918 -59.347439) (xy 6.22713 -59.26672) (xy 6.242953 -59.187169) (xy 6.266498 -59.109553)
			(xy 6.297537 -59.034617) (xy 6.335772 -58.963085) (xy 6.380834 -58.895645) (xy 6.432289 -58.832946)
			(xy 6.489642 -58.775593) (xy 6.552341 -58.724138) (xy 6.619781 -58.679076) (xy 6.691313 -58.640841)
			(xy 6.766249 -58.609802) (xy 6.843865 -58.586257) (xy 6.923416 -58.570434) (xy 7.004135 -58.562484)
			(xy 7.085245 -58.562484) (xy 7.165964 -58.570434) (xy 7.245515 -58.586257) (xy 7.323131 -58.609802)
			(xy 7.398067 -58.640841) (xy 7.469599 -58.679076) (xy 7.537039 -58.724138) (xy 7.599738 -58.775593)
			(xy 7.657091 -58.832946) (xy 7.708546 -58.895645) (xy 7.753608 -58.963085) (xy 7.791843 -59.034617)
			(xy 7.822882 -59.109553) (xy 7.846427 -59.187169) (xy 7.86225 -59.26672) (xy 7.8702 -59.347439) (xy 7.870698 -59.387994)
			(xy 7.8702 -59.428549) (xy 8.75918 -59.428549) (xy 8.75918 -59.347439) (xy 8.76713 -59.26672) (xy 8.782953 -59.187169)
			(xy 8.806498 -59.109553) (xy 8.837537 -59.034617) (xy 8.875772 -58.963085) (xy 8.920834 -58.895645)
			(xy 8.972289 -58.832946) (xy 9.029642 -58.775593) (xy 9.092341 -58.724138) (xy 9.159781 -58.679076)
			(xy 9.231313 -58.640841) (xy 9.306249 -58.609802) (xy 9.383865 -58.586257) (xy 9.463416 -58.570434)
			(xy 9.544135 -58.562484) (xy 9.625245 -58.562484) (xy 9.705964 -58.570434) (xy 9.785515 -58.586257)
			(xy 9.863131 -58.609802) (xy 9.938067 -58.640841) (xy 10.009599 -58.679076) (xy 10.077039 -58.724138)
			(xy 10.139738 -58.775593) (xy 10.197091 -58.832946) (xy 10.248546 -58.895645) (xy 10.293608 -58.963085)
			(xy 10.331843 -59.034617) (xy 10.362882 -59.109553) (xy 10.386427 -59.187169) (xy 10.40225 -59.26672)
			(xy 10.4102 -59.347439) (xy 10.410698 -59.387994) (xy 10.4102 -59.428549) (xy 11.29918 -59.428549)
			(xy 11.29918 -59.347439) (xy 11.30713 -59.26672) (xy 11.322953 -59.187169) (xy 11.346498 -59.109553)
			(xy 11.377537 -59.034617) (xy 11.415772 -58.963085) (xy 11.460834 -58.895645) (xy 11.512289 -58.832946)
			(xy 11.569642 -58.775593) (xy 11.632341 -58.724138) (xy 11.699781 -58.679076) (xy 11.771313 -58.640841)
			(xy 11.846249 -58.609802) (xy 11.923865 -58.586257) (xy 12.003416 -58.570434) (xy 12.084135 -58.562484)
			(xy 12.165245 -58.562484) (xy 12.245964 -58.570434) (xy 12.325515 -58.586257) (xy 12.403131 -58.609802)
			(xy 12.478067 -58.640841) (xy 12.549599 -58.679076) (xy 12.617039 -58.724138) (xy 12.679738 -58.775593)
			(xy 12.737091 -58.832946) (xy 12.788546 -58.895645) (xy 12.833608 -58.963085) (xy 12.871843 -59.034617)
			(xy 12.902882 -59.109553) (xy 12.926427 -59.187169) (xy 12.94225 -59.26672) (xy 12.9502 -59.347439)
			(xy 12.950698 -59.387994) (xy 12.9502 -59.428549) (xy 12.94225 -59.509268) (xy 12.926427 -59.588819)
			(xy 12.902882 -59.666435) (xy 12.871843 -59.741371) (xy 12.833608 -59.812903) (xy 12.788546 -59.880343)
			(xy 12.737091 -59.943042) (xy 12.679738 -60.000395) (xy 12.617039 -60.05185) (xy 12.549599 -60.096912)
			(xy 12.478067 -60.135147) (xy 12.403131 -60.166186) (xy 12.325515 -60.189731) (xy 12.245964 -60.205554)
			(xy 12.165245 -60.213504) (xy 12.084135 -60.213504) (xy 12.003416 -60.205554) (xy 11.923865 -60.189731)
			(xy 11.846249 -60.166186) (xy 11.771313 -60.135147) (xy 11.699781 -60.096912) (xy 11.632341 -60.05185)
			(xy 11.569642 -60.000395) (xy 11.512289 -59.943042) (xy 11.460834 -59.880343) (xy 11.415772 -59.812903)
			(xy 11.377537 -59.741371) (xy 11.346498 -59.666435) (xy 11.322953 -59.588819) (xy 11.30713 -59.509268)
			(xy 11.29918 -59.428549) (xy 10.4102 -59.428549) (xy 10.40225 -59.509268) (xy 10.386427 -59.588819)
			(xy 10.362882 -59.666435) (xy 10.331843 -59.741371) (xy 10.293608 -59.812903) (xy 10.248546 -59.880343)
			(xy 10.197091 -59.943042) (xy 10.139738 -60.000395) (xy 10.077039 -60.05185) (xy 10.009599 -60.096912)
			(xy 9.938067 -60.135147) (xy 9.863131 -60.166186) (xy 9.785515 -60.189731) (xy 9.705964 -60.205554)
			(xy 9.625245 -60.213504) (xy 9.544135 -60.213504) (xy 9.463416 -60.205554) (xy 9.383865 -60.189731)
			(xy 9.306249 -60.166186) (xy 9.231313 -60.135147) (xy 9.159781 -60.096912) (xy 9.092341 -60.05185)
			(xy 9.029642 -60.000395) (xy 8.972289 -59.943042) (xy 8.920834 -59.880343) (xy 8.875772 -59.812903)
			(xy 8.837537 -59.741371) (xy 8.806498 -59.666435) (xy 8.782953 -59.588819) (xy 8.76713 -59.509268)
			(xy 8.75918 -59.428549) (xy 7.8702 -59.428549) (xy 7.86225 -59.509268) (xy 7.846427 -59.588819) (xy 7.822882 -59.666435)
			(xy 7.791843 -59.741371) (xy 7.753608 -59.812903) (xy 7.708546 -59.880343) (xy 7.657091 -59.943042)
			(xy 7.599738 -60.000395) (xy 7.537039 -60.05185) (xy 7.469599 -60.096912) (xy 7.398067 -60.135147)
			(xy 7.323131 -60.166186) (xy 7.245515 -60.189731) (xy 7.165964 -60.205554) (xy 7.085245 -60.213504)
			(xy 7.004135 -60.213504) (xy 6.923416 -60.205554) (xy 6.843865 -60.189731) (xy 6.766249 -60.166186)
			(xy 6.691313 -60.135147) (xy 6.619781 -60.096912) (xy 6.552341 -60.05185) (xy 6.489642 -60.000395)
			(xy 6.432289 -59.943042) (xy 6.380834 -59.880343) (xy 6.335772 -59.812903) (xy 6.297537 -59.741371)
			(xy 6.266498 -59.666435) (xy 6.242953 -59.588819) (xy 6.22713 -59.509268) (xy 6.21918 -59.428549)
			(xy 5.3302 -59.428549) (xy 5.32225 -59.509268) (xy 5.306427 -59.588819) (xy 5.282882 -59.666435)
			(xy 5.251843 -59.741371) (xy 5.213608 -59.812903) (xy 5.168546 -59.880343) (xy 5.117091 -59.943042)
			(xy 5.059738 -60.000395) (xy 4.997039 -60.05185) (xy 4.929599 -60.096912) (xy 4.858067 -60.135147)
			(xy 4.783131 -60.166186) (xy 4.705515 -60.189731) (xy 4.625964 -60.205554) (xy 4.545245 -60.213504)
			(xy 4.464135 -60.213504) (xy 4.383416 -60.205554) (xy 4.303865 -60.189731) (xy 4.226249 -60.166186)
			(xy 4.151313 -60.135147) (xy 4.079781 -60.096912) (xy 4.012341 -60.05185) (xy 3.949642 -60.000395)
			(xy 3.892289 -59.943042) (xy 3.840834 -59.880343) (xy 3.795772 -59.812903) (xy 3.757537 -59.741371)
			(xy 3.726498 -59.666435) (xy 3.702953 -59.588819) (xy 3.68713 -59.509268) (xy 3.67918 -59.428549)
			(xy 1.27 -59.428549) (xy 1.27 -61.968549) (xy 4.94918 -61.968549) (xy 4.94918 -61.887439) (xy 4.95713 -61.80672)
			(xy 4.972953 -61.727169) (xy 4.996498 -61.649553) (xy 5.027537 -61.574617) (xy 5.065772 -61.503085)
			(xy 5.110834 -61.435645) (xy 5.162289 -61.372946) (xy 5.219642 -61.315593) (xy 5.282341 -61.264138)
			(xy 5.349781 -61.219076) (xy 5.421313 -61.180841) (xy 5.496249 -61.149802) (xy 5.573865 -61.126257)
			(xy 5.653416 -61.110434) (xy 5.734135 -61.102484) (xy 5.815245 -61.102484) (xy 5.895964 -61.110434)
			(xy 5.975515 -61.126257) (xy 6.053131 -61.149802) (xy 6.128067 -61.180841) (xy 6.199599 -61.219076)
			(xy 6.267039 -61.264138) (xy 6.329738 -61.315593) (xy 6.387091 -61.372946) (xy 6.438546 -61.435645)
			(xy 6.483608 -61.503085) (xy 6.521843 -61.574617) (xy 6.552882 -61.649553) (xy 6.576427 -61.727169)
			(xy 6.59225 -61.80672) (xy 6.6002 -61.887439) (xy 6.600698 -61.927994) (xy 6.6002 -61.968549) (xy 7.48918 -61.968549)
			(xy 7.48918 -61.887439) (xy 7.49713 -61.80672) (xy 7.512953 -61.727169) (xy 7.536498 -61.649553)
			(xy 7.567537 -61.574617) (xy 7.605772 -61.503085) (xy 7.650834 -61.435645) (xy 7.702289 -61.372946)
			(xy 7.759642 -61.315593) (xy 7.822341 -61.264138) (xy 7.889781 -61.219076) (xy 7.961313 -61.180841)
			(xy 8.036249 -61.149802) (xy 8.113865 -61.126257) (xy 8.193416 -61.110434) (xy 8.274135 -61.102484)
			(xy 8.355245 -61.102484) (xy 8.435964 -61.110434) (xy 8.515515 -61.126257) (xy 8.593131 -61.149802)
			(xy 8.668067 -61.180841) (xy 8.739599 -61.219076) (xy 8.807039 -61.264138) (xy 8.869738 -61.315593)
			(xy 8.927091 -61.372946) (xy 8.978546 -61.435645) (xy 9.023608 -61.503085) (xy 9.061843 -61.574617)
			(xy 9.092882 -61.649553) (xy 9.116427 -61.727169) (xy 9.13225 -61.80672) (xy 9.1402 -61.887439) (xy 9.140698 -61.927994)
			(xy 9.1402 -61.968549) (xy 10.02918 -61.968549) (xy 10.02918 -61.887439) (xy 10.03713 -61.80672)
			(xy 10.052953 -61.727169) (xy 10.076498 -61.649553) (xy 10.107537 -61.574617) (xy 10.145772 -61.503085)
			(xy 10.190834 -61.435645) (xy 10.242289 -61.372946) (xy 10.299642 -61.315593) (xy 10.362341 -61.264138)
			(xy 10.429781 -61.219076) (xy 10.501313 -61.180841) (xy 10.576249 -61.149802) (xy 10.653865 -61.126257)
			(xy 10.733416 -61.110434) (xy 10.814135 -61.102484) (xy 10.895245 -61.102484) (xy 10.975964 -61.110434)
			(xy 11.055515 -61.126257) (xy 11.133131 -61.149802) (xy 11.208067 -61.180841) (xy 11.279599 -61.219076)
			(xy 11.347039 -61.264138) (xy 11.409738 -61.315593) (xy 11.467091 -61.372946) (xy 11.518546 -61.435645)
			(xy 11.563608 -61.503085) (xy 11.601843 -61.574617) (xy 11.632882 -61.649553) (xy 11.656427 -61.727169)
			(xy 11.67225 -61.80672) (xy 11.6802 -61.887439) (xy 11.680698 -61.927994) (xy 11.6802 -61.968549)
			(xy 11.67225 -62.049268) (xy 11.656427 -62.128819) (xy 11.632882 -62.206435) (xy 11.601843 -62.281371)
			(xy 11.563608 -62.352903) (xy 11.518546 -62.420343) (xy 11.467091 -62.483042) (xy 11.409738 -62.540395)
			(xy 11.347039 -62.59185) (xy 11.279599 -62.636912) (xy 11.208067 -62.675147) (xy 11.133131 -62.706186)
			(xy 11.055515 -62.729731) (xy 10.975964 -62.745554) (xy 10.895245 -62.753504) (xy 10.814135 -62.753504)
			(xy 10.733416 -62.745554) (xy 10.653865 -62.729731) (xy 10.576249 -62.706186) (xy 10.501313 -62.675147)
			(xy 10.429781 -62.636912) (xy 10.362341 -62.59185) (xy 10.299642 -62.540395) (xy 10.242289 -62.483042)
			(xy 10.190834 -62.420343) (xy 10.145772 -62.352903) (xy 10.107537 -62.281371) (xy 10.076498 -62.206435)
			(xy 10.052953 -62.128819) (xy 10.03713 -62.049268) (xy 10.02918 -61.968549) (xy 9.1402 -61.968549)
			(xy 9.13225 -62.049268) (xy 9.116427 -62.128819) (xy 9.092882 -62.206435) (xy 9.061843 -62.281371)
			(xy 9.023608 -62.352903) (xy 8.978546 -62.420343) (xy 8.927091 -62.483042) (xy 8.869738 -62.540395)
			(xy 8.807039 -62.59185) (xy 8.739599 -62.636912) (xy 8.668067 -62.675147) (xy 8.593131 -62.706186)
			(xy 8.515515 -62.729731) (xy 8.435964 -62.745554) (xy 8.355245 -62.753504) (xy 8.274135 -62.753504)
			(xy 8.193416 -62.745554) (xy 8.113865 -62.729731) (xy 8.036249 -62.706186) (xy 7.961313 -62.675147)
			(xy 7.889781 -62.636912) (xy 7.822341 -62.59185) (xy 7.759642 -62.540395) (xy 7.702289 -62.483042)
			(xy 7.650834 -62.420343) (xy 7.605772 -62.352903) (xy 7.567537 -62.281371) (xy 7.536498 -62.206435)
			(xy 7.512953 -62.128819) (xy 7.49713 -62.049268) (xy 7.48918 -61.968549) (xy 6.6002 -61.968549) (xy 6.59225 -62.049268)
			(xy 6.576427 -62.128819) (xy 6.552882 -62.206435) (xy 6.521843 -62.281371) (xy 6.483608 -62.352903)
			(xy 6.438546 -62.420343) (xy 6.387091 -62.483042) (xy 6.329738 -62.540395) (xy 6.267039 -62.59185)
			(xy 6.199599 -62.636912) (xy 6.128067 -62.675147) (xy 6.053131 -62.706186) (xy 5.975515 -62.729731)
			(xy 5.895964 -62.745554) (xy 5.815245 -62.753504) (xy 5.734135 -62.753504) (xy 5.653416 -62.745554)
			(xy 5.573865 -62.729731) (xy 5.496249 -62.706186) (xy 5.421313 -62.675147) (xy 5.349781 -62.636912)
			(xy 5.282341 -62.59185) (xy 5.219642 -62.540395) (xy 5.162289 -62.483042) (xy 5.110834 -62.420343)
			(xy 5.065772 -62.352903) (xy 5.027537 -62.281371) (xy 4.996498 -62.206435) (xy 4.972953 -62.128819)
			(xy 4.95713 -62.049268) (xy 4.94918 -61.968549) (xy 1.27 -61.968549) (xy 1.27 -66.685414) (xy 1.270551 -66.708776)
			(xy 1.279134 -66.754707) (xy 1.29597 -66.798294) (xy 1.320492 -66.838069) (xy 1.351871 -66.87269)
			(xy 1.389052 -66.90099) (xy 1.430779 -66.922016) (xy 1.475648 -66.935058) (xy 1.522145 -66.939678)
			(xy 1.568703 -66.935718) (xy 1.613752 -66.923314) (xy 1.655774 -66.902882) (xy 1.693352 -66.875112)
			(xy 1.709674 -66.858388) (xy 1.754144 -66.811352) (xy 1.848064 -66.722255) (xy 1.947334 -66.639162)
			(xy 2.051571 -66.562393) (xy 2.160374 -66.492244) (xy 2.273323 -66.428986) (xy 2.389982 -66.372863)
			(xy 2.5099 -66.324092) (xy 2.632615 -66.28286) (xy 2.757653 -66.249327) (xy 2.884532 -66.223622)
			(xy 3.012762 -66.205845) (xy 3.141848 -66.196063) (xy 3.271293 -66.194316) (xy 3.400597 -66.200609)
			(xy 3.52926 -66.214918) (xy 3.656786 -66.237188) (xy 3.782684 -66.267333) (xy 3.906468 -66.305237)
			(xy 4.027658 -66.350753) (xy 4.14579 -66.403707) (xy 4.260405 -66.463892) (xy 4.371062 -66.531079)
			(xy 4.477334 -66.605006) (xy 4.578812 -66.685388) (xy 4.675102 -66.771917) (xy 4.765834 -66.864257)
			(xy 4.850658 -66.962052) (xy 4.929246 -67.064925) (xy 5.001295 -67.17248) (xy 5.066527 -67.2843)
			(xy 5.124691 -67.399955) (xy 5.175561 -67.518998) (xy 5.218942 -67.640969) (xy 5.254666 -67.765399)
			(xy 5.282595 -67.891807) (xy 5.302622 -68.019705) (xy 5.314669 -68.1486) (xy 5.31869 -68.277994)
			(xy 5.314669 -68.407388) (xy 5.302622 -68.536283) (xy 5.282595 -68.664181) (xy 5.254666 -68.790589)
			(xy 5.218942 -68.915019) (xy 5.175561 -69.03699) (xy 5.124691 -69.156033) (xy 5.066527 -69.271688)
			(xy 5.001295 -69.383508) (xy 4.929246 -69.491063) (xy 4.850658 -69.593936) (xy 4.765834 -69.691731)
			(xy 4.675102 -69.784071) (xy 4.578812 -69.8706) (xy 4.477334 -69.950982) (xy 4.371062 -70.024909)
			(xy 4.260405 -70.092096) (xy 4.14579 -70.152281) (xy 4.027658 -70.205235) (xy 3.906468 -70.250751)
			(xy 3.782684 -70.288655) (xy 3.656786 -70.3188) (xy 3.52926 -70.34107) (xy 3.400597 -70.355379) (xy 3.271293 -70.361672)
			(xy 3.141848 -70.359925) (xy 3.012762 -70.350143) (xy 2.884532 -70.332366) (xy 2.757653 -70.306661)
			(xy 2.632615 -70.273128) (xy 2.5099 -70.231896) (xy 2.389982 -70.183125) (xy 2.273323 -70.127002)
			(xy 2.160374 -70.063744) (xy 2.051571 -69.993595) (xy 1.947334 -69.916826) (xy 1.848064 -69.833733)
			(xy 1.754144 -69.744636) (xy 1.709674 -69.6976) (xy 1.693349 -69.680884) (xy 1.655769 -69.653131)
			(xy 1.613749 -69.632714) (xy 1.568705 -69.62032) (xy 1.522155 -69.616368) (xy 1.475666 -69.620991)
			(xy 1.430806 -69.634033) (xy 1.389085 -69.655054) (xy 1.351908 -69.683347) (xy 1.320529 -69.717957)
			(xy 1.296005 -69.75772) (xy 1.279161 -69.801296) (xy 1.270565 -69.847216) (xy 1.27 -69.870574) (xy 1.27 -97.679256)
			(xy 1.270551 -97.702619) (xy 1.279133 -97.748551) (xy 1.295968 -97.792139) (xy 1.320489 -97.831915)
			(xy 1.351869 -97.866538) (xy 1.38905 -97.894839) (xy 1.430778 -97.915865) (xy 1.475648 -97.928908)
			(xy 1.522146 -97.933528) (xy 1.568705 -97.929568) (xy 1.613755 -97.917163) (xy 1.655777 -97.89673)
			(xy 1.693356 -97.868958) (xy 1.709674 -97.85223) (xy 1.754144 -97.805194) (xy 1.848064 -97.716097)
			(xy 1.947334 -97.633004) (xy 2.051571 -97.556235) (xy 2.160374 -97.486086) (xy 2.273323 -97.422828)
			(xy 2.389982 -97.366705) (xy 2.5099 -97.317934) (xy 2.632615 -97.276702) (xy 2.757653 -97.243169)
			(xy 2.884532 -97.217464) (xy 3.012762 -97.199687) (xy 3.141848 -97.189905) (xy 3.271293 -97.188158)
			(xy 3.400597 -97.194451) (xy 3.52926 -97.20876) (xy 3.656786 -97.23103) (xy 3.782684 -97.261175)
			(xy 3.906468 -97.299079) (xy 4.027658 -97.344595) (xy 4.14579 -97.397549) (xy 4.260405 -97.457734)
			(xy 4.371062 -97.524921) (xy 4.477334 -97.598848) (xy 4.578812 -97.67923) (xy 4.675102 -97.765759)
			(xy 4.765834 -97.858099) (xy 4.850658 -97.955894) (xy 4.929246 -98.058767) (xy 5.001295 -98.166322)
			(xy 5.066527 -98.278142) (xy 5.124691 -98.393797) (xy 5.175561 -98.51284) (xy 5.218942 -98.634811)
			(xy 5.254666 -98.759241) (xy 5.282595 -98.885649) (xy 5.302622 -99.013547) (xy 5.314669 -99.142442)
			(xy 5.31869 -99.271836) (xy 5.314669 -99.40123) (xy 5.302622 -99.530125) (xy 5.282595 -99.658023)
			(xy 5.254666 -99.784431) (xy 5.218942 -99.908861) (xy 5.175561 -100.030832) (xy 5.124691 -100.149875)
			(xy 5.066527 -100.26553) (xy 5.001295 -100.37735) (xy 4.929246 -100.484905) (xy 4.850658 -100.587778)
			(xy 4.765834 -100.685573) (xy 4.675102 -100.777913) (xy 4.578812 -100.864442) (xy 4.477334 -100.944824)
			(xy 4.371062 -101.018751) (xy 4.260405 -101.085938) (xy 4.14579 -101.146123) (xy 4.027658 -101.199077)
			(xy 3.906468 -101.244593) (xy 3.782684 -101.282497) (xy 3.656786 -101.312642) (xy 3.52926 -101.334912)
			(xy 3.400597 -101.349221) (xy 3.271293 -101.355514) (xy 3.141848 -101.353767) (xy 3.012762 -101.343985)
			(xy 2.884532 -101.326208) (xy 2.757653 -101.300503) (xy 2.632615 -101.26697) (xy 2.5099 -101.225738)
			(xy 2.389982 -101.176967) (xy 2.273323 -101.120844) (xy 2.160374 -101.057586) (xy 2.051571 -100.987437)
			(xy 1.947334 -100.910668) (xy 1.848064 -100.827575) (xy 1.754144 -100.738478) (xy 1.709674 -100.691442)
			(xy 1.693349 -100.674726) (xy 1.655769 -100.646973) (xy 1.613749 -100.626555) (xy 1.568705 -100.614162)
			(xy 1.522155 -100.61021) (xy 1.475666 -100.614833) (xy 1.430806 -100.627874) (xy 1.389085 -100.648896)
			(xy 1.351909 -100.677188) (xy 1.32053 -100.711799) (xy 1.296006 -100.751562) (xy 1.279162 -100.795138)
			(xy 1.270566 -100.841058) (xy 1.27 -100.864416) (xy 1.27 -105.662391) (xy 3.67918 -105.662391) (xy 3.67918 -105.581281)
			(xy 3.68713 -105.500562) (xy 3.702953 -105.421011) (xy 3.726498 -105.343395) (xy 3.757537 -105.268459)
			(xy 3.795772 -105.196927) (xy 3.840834 -105.129487) (xy 3.892289 -105.066788) (xy 3.949642 -105.009435)
			(xy 4.012341 -104.95798) (xy 4.079781 -104.912918) (xy 4.151313 -104.874683) (xy 4.226249 -104.843644)
			(xy 4.303865 -104.820099) (xy 4.383416 -104.804276) (xy 4.464135 -104.796326) (xy 4.545245 -104.796326)
			(xy 4.625964 -104.804276) (xy 4.705515 -104.820099) (xy 4.783131 -104.843644) (xy 4.858067 -104.874683)
			(xy 4.929599 -104.912918) (xy 4.997039 -104.95798) (xy 5.059738 -105.009435) (xy 5.117091 -105.066788)
			(xy 5.168546 -105.129487) (xy 5.213608 -105.196927) (xy 5.251843 -105.268459) (xy 5.282882 -105.343395)
			(xy 5.306427 -105.421011) (xy 5.32225 -105.500562) (xy 5.3302 -105.581281) (xy 5.330698 -105.621836)
			(xy 5.3302 -105.662391) (xy 6.21918 -105.662391) (xy 6.21918 -105.581281) (xy 6.22713 -105.500562)
			(xy 6.242953 -105.421011) (xy 6.266498 -105.343395) (xy 6.297537 -105.268459) (xy 6.335772 -105.196927)
			(xy 6.380834 -105.129487) (xy 6.432289 -105.066788) (xy 6.489642 -105.009435) (xy 6.552341 -104.95798)
			(xy 6.619781 -104.912918) (xy 6.691313 -104.874683) (xy 6.766249 -104.843644) (xy 6.843865 -104.820099)
			(xy 6.923416 -104.804276) (xy 7.004135 -104.796326) (xy 7.085245 -104.796326) (xy 7.165964 -104.804276)
			(xy 7.245515 -104.820099) (xy 7.323131 -104.843644) (xy 7.398067 -104.874683) (xy 7.469599 -104.912918)
			(xy 7.537039 -104.95798) (xy 7.599738 -105.009435) (xy 7.657091 -105.066788) (xy 7.708546 -105.129487)
			(xy 7.753608 -105.196927) (xy 7.791843 -105.268459) (xy 7.822882 -105.343395) (xy 7.846427 -105.421011)
			(xy 7.86225 -105.500562) (xy 7.8702 -105.581281) (xy 7.870698 -105.621836) (xy 7.8702 -105.662391)
			(xy 8.75918 -105.662391) (xy 8.75918 -105.581281) (xy 8.76713 -105.500562) (xy 8.782953 -105.421011)
			(xy 8.806498 -105.343395) (xy 8.837537 -105.268459) (xy 8.875772 -105.196927) (xy 8.920834 -105.129487)
			(xy 8.972289 -105.066788) (xy 9.029642 -105.009435) (xy 9.092341 -104.95798) (xy 9.159781 -104.912918)
			(xy 9.231313 -104.874683) (xy 9.306249 -104.843644) (xy 9.383865 -104.820099) (xy 9.463416 -104.804276)
			(xy 9.544135 -104.796326) (xy 9.625245 -104.796326) (xy 9.705964 -104.804276) (xy 9.785515 -104.820099)
			(xy 9.863131 -104.843644) (xy 9.938067 -104.874683) (xy 10.009599 -104.912918) (xy 10.077039 -104.95798)
			(xy 10.139738 -105.009435) (xy 10.197091 -105.066788) (xy 10.248546 -105.129487) (xy 10.293608 -105.196927)
			(xy 10.331843 -105.268459) (xy 10.362882 -105.343395) (xy 10.386427 -105.421011) (xy 10.40225 -105.500562)
			(xy 10.4102 -105.581281) (xy 10.410698 -105.621836) (xy 10.4102 -105.662391) (xy 11.29918 -105.662391)
			(xy 11.29918 -105.581281) (xy 11.30713 -105.500562) (xy 11.322953 -105.421011) (xy 11.346498 -105.343395)
			(xy 11.377537 -105.268459) (xy 11.415772 -105.196927) (xy 11.460834 -105.129487) (xy 11.512289 -105.066788)
			(xy 11.569642 -105.009435) (xy 11.632341 -104.95798) (xy 11.699781 -104.912918) (xy 11.771313 -104.874683)
			(xy 11.846249 -104.843644) (xy 11.923865 -104.820099) (xy 12.003416 -104.804276) (xy 12.084135 -104.796326)
			(xy 12.165245 -104.796326) (xy 12.245964 -104.804276) (xy 12.325515 -104.820099) (xy 12.403131 -104.843644)
			(xy 12.478067 -104.874683) (xy 12.549599 -104.912918) (xy 12.617039 -104.95798) (xy 12.679738 -105.009435)
			(xy 12.737091 -105.066788) (xy 12.788546 -105.129487) (xy 12.833608 -105.196927) (xy 12.871843 -105.268459)
			(xy 12.902882 -105.343395) (xy 12.926427 -105.421011) (xy 12.94225 -105.500562) (xy 12.9502 -105.581281)
			(xy 12.950698 -105.621836) (xy 12.9502 -105.662391) (xy 12.94225 -105.74311) (xy 12.926427 -105.822661)
			(xy 12.902882 -105.900277) (xy 12.871843 -105.975213) (xy 12.833608 -106.046745) (xy 12.788546 -106.114185)
			(xy 12.737091 -106.176884) (xy 12.679738 -106.234237) (xy 12.617039 -106.285692) (xy 12.549599 -106.330754)
			(xy 12.478067 -106.368989) (xy 12.403131 -106.400028) (xy 12.325515 -106.423573) (xy 12.245964 -106.439396)
			(xy 12.165245 -106.447346) (xy 12.084135 -106.447346) (xy 12.003416 -106.439396) (xy 11.923865 -106.423573)
			(xy 11.846249 -106.400028) (xy 11.771313 -106.368989) (xy 11.699781 -106.330754) (xy 11.632341 -106.285692)
			(xy 11.569642 -106.234237) (xy 11.512289 -106.176884) (xy 11.460834 -106.114185) (xy 11.415772 -106.046745)
			(xy 11.377537 -105.975213) (xy 11.346498 -105.900277) (xy 11.322953 -105.822661) (xy 11.30713 -105.74311)
			(xy 11.29918 -105.662391) (xy 10.4102 -105.662391) (xy 10.40225 -105.74311) (xy 10.386427 -105.822661)
			(xy 10.362882 -105.900277) (xy 10.331843 -105.975213) (xy 10.293608 -106.046745) (xy 10.248546 -106.114185)
			(xy 10.197091 -106.176884) (xy 10.139738 -106.234237) (xy 10.077039 -106.285692) (xy 10.009599 -106.330754)
			(xy 9.938067 -106.368989) (xy 9.863131 -106.400028) (xy 9.785515 -106.423573) (xy 9.705964 -106.439396)
			(xy 9.625245 -106.447346) (xy 9.544135 -106.447346) (xy 9.463416 -106.439396) (xy 9.383865 -106.423573)
			(xy 9.306249 -106.400028) (xy 9.231313 -106.368989) (xy 9.159781 -106.330754) (xy 9.092341 -106.285692)
			(xy 9.029642 -106.234237) (xy 8.972289 -106.176884) (xy 8.920834 -106.114185) (xy 8.875772 -106.046745)
			(xy 8.837537 -105.975213) (xy 8.806498 -105.900277) (xy 8.782953 -105.822661) (xy 8.76713 -105.74311)
			(xy 8.75918 -105.662391) (xy 7.8702 -105.662391) (xy 7.86225 -105.74311) (xy 7.846427 -105.822661)
			(xy 7.822882 -105.900277) (xy 7.791843 -105.975213) (xy 7.753608 -106.046745) (xy 7.708546 -106.114185)
			(xy 7.657091 -106.176884) (xy 7.599738 -106.234237) (xy 7.537039 -106.285692) (xy 7.469599 -106.330754)
			(xy 7.398067 -106.368989) (xy 7.323131 -106.400028) (xy 7.245515 -106.423573) (xy 7.165964 -106.439396)
			(xy 7.085245 -106.447346) (xy 7.004135 -106.447346) (xy 6.923416 -106.439396) (xy 6.843865 -106.423573)
			(xy 6.766249 -106.400028) (xy 6.691313 -106.368989) (xy 6.619781 -106.330754) (xy 6.552341 -106.285692)
			(xy 6.489642 -106.234237) (xy 6.432289 -106.176884) (xy 6.380834 -106.114185) (xy 6.335772 -106.046745)
			(xy 6.297537 -105.975213) (xy 6.266498 -105.900277) (xy 6.242953 -105.822661) (xy 6.22713 -105.74311)
			(xy 6.21918 -105.662391) (xy 5.3302 -105.662391) (xy 5.32225 -105.74311) (xy 5.306427 -105.822661)
			(xy 5.282882 -105.900277) (xy 5.251843 -105.975213) (xy 5.213608 -106.046745) (xy 5.168546 -106.114185)
			(xy 5.117091 -106.176884) (xy 5.059738 -106.234237) (xy 4.997039 -106.285692) (xy 4.929599 -106.330754)
			(xy 4.858067 -106.368989) (xy 4.783131 -106.400028) (xy 4.705515 -106.423573) (xy 4.625964 -106.439396)
			(xy 4.545245 -106.447346) (xy 4.464135 -106.447346) (xy 4.383416 -106.439396) (xy 4.303865 -106.423573)
			(xy 4.226249 -106.400028) (xy 4.151313 -106.368989) (xy 4.079781 -106.330754) (xy 4.012341 -106.285692)
			(xy 3.949642 -106.234237) (xy 3.892289 -106.176884) (xy 3.840834 -106.114185) (xy 3.795772 -106.046745)
			(xy 3.757537 -105.975213) (xy 3.726498 -105.900277) (xy 3.702953 -105.822661) (xy 3.68713 -105.74311)
			(xy 3.67918 -105.662391) (xy 1.27 -105.662391) (xy 1.27 -108.202391) (xy 4.94918 -108.202391) (xy 4.94918 -108.121281)
			(xy 4.95713 -108.040562) (xy 4.972953 -107.961011) (xy 4.996498 -107.883395) (xy 5.027537 -107.808459)
			(xy 5.065772 -107.736927) (xy 5.110834 -107.669487) (xy 5.162289 -107.606788) (xy 5.219642 -107.549435)
			(xy 5.282341 -107.49798) (xy 5.349781 -107.452918) (xy 5.421313 -107.414683) (xy 5.496249 -107.383644)
			(xy 5.573865 -107.360099) (xy 5.653416 -107.344276) (xy 5.734135 -107.336326) (xy 5.815245 -107.336326)
			(xy 5.895964 -107.344276) (xy 5.975515 -107.360099) (xy 6.053131 -107.383644) (xy 6.128067 -107.414683)
			(xy 6.199599 -107.452918) (xy 6.267039 -107.49798) (xy 6.329738 -107.549435) (xy 6.387091 -107.606788)
			(xy 6.438546 -107.669487) (xy 6.483608 -107.736927) (xy 6.521843 -107.808459) (xy 6.552882 -107.883395)
			(xy 6.576427 -107.961011) (xy 6.59225 -108.040562) (xy 6.6002 -108.121281) (xy 6.600698 -108.161836)
			(xy 6.6002 -108.202391) (xy 7.48918 -108.202391) (xy 7.48918 -108.121281) (xy 7.49713 -108.040562)
			(xy 7.512953 -107.961011) (xy 7.536498 -107.883395) (xy 7.567537 -107.808459) (xy 7.605772 -107.736927)
			(xy 7.650834 -107.669487) (xy 7.702289 -107.606788) (xy 7.759642 -107.549435) (xy 7.822341 -107.49798)
			(xy 7.889781 -107.452918) (xy 7.961313 -107.414683) (xy 8.036249 -107.383644) (xy 8.113865 -107.360099)
			(xy 8.193416 -107.344276) (xy 8.274135 -107.336326) (xy 8.355245 -107.336326) (xy 8.435964 -107.344276)
			(xy 8.515515 -107.360099) (xy 8.593131 -107.383644) (xy 8.668067 -107.414683) (xy 8.739599 -107.452918)
			(xy 8.807039 -107.49798) (xy 8.869738 -107.549435) (xy 8.927091 -107.606788) (xy 8.978546 -107.669487)
			(xy 9.023608 -107.736927) (xy 9.061843 -107.808459) (xy 9.092882 -107.883395) (xy 9.116427 -107.961011)
			(xy 9.13225 -108.040562) (xy 9.1402 -108.121281) (xy 9.140698 -108.161836) (xy 9.1402 -108.202391)
			(xy 10.02918 -108.202391) (xy 10.02918 -108.121281) (xy 10.03713 -108.040562) (xy 10.052953 -107.961011)
			(xy 10.076498 -107.883395) (xy 10.107537 -107.808459) (xy 10.145772 -107.736927) (xy 10.190834 -107.669487)
			(xy 10.242289 -107.606788) (xy 10.299642 -107.549435) (xy 10.362341 -107.49798) (xy 10.429781 -107.452918)
			(xy 10.501313 -107.414683) (xy 10.576249 -107.383644) (xy 10.653865 -107.360099) (xy 10.733416 -107.344276)
			(xy 10.814135 -107.336326) (xy 10.895245 -107.336326) (xy 10.975964 -107.344276) (xy 11.055515 -107.360099)
			(xy 11.133131 -107.383644) (xy 11.208067 -107.414683) (xy 11.279599 -107.452918) (xy 11.347039 -107.49798)
			(xy 11.409738 -107.549435) (xy 11.467091 -107.606788) (xy 11.518546 -107.669487) (xy 11.563608 -107.736927)
			(xy 11.601843 -107.808459) (xy 11.632882 -107.883395) (xy 11.656427 -107.961011) (xy 11.67225 -108.040562)
			(xy 11.6802 -108.121281) (xy 11.680698 -108.161836) (xy 11.6802 -108.202391) (xy 11.67225 -108.28311)
			(xy 11.656427 -108.362661) (xy 11.632882 -108.440277) (xy 11.601843 -108.515213) (xy 11.563608 -108.586745)
			(xy 11.518546 -108.654185) (xy 11.467091 -108.716884) (xy 11.409738 -108.774237) (xy 11.347039 -108.825692)
			(xy 11.279599 -108.870754) (xy 11.208067 -108.908989) (xy 11.133131 -108.940028) (xy 11.055515 -108.963573)
			(xy 10.975964 -108.979396) (xy 10.895245 -108.987346) (xy 10.814135 -108.987346) (xy 10.733416 -108.979396)
			(xy 10.653865 -108.963573) (xy 10.576249 -108.940028) (xy 10.501313 -108.908989) (xy 10.429781 -108.870754)
			(xy 10.362341 -108.825692) (xy 10.299642 -108.774237) (xy 10.242289 -108.716884) (xy 10.190834 -108.654185)
			(xy 10.145772 -108.586745) (xy 10.107537 -108.515213) (xy 10.076498 -108.440277) (xy 10.052953 -108.362661)
			(xy 10.03713 -108.28311) (xy 10.02918 -108.202391) (xy 9.1402 -108.202391) (xy 9.13225 -108.28311)
			(xy 9.116427 -108.362661) (xy 9.092882 -108.440277) (xy 9.061843 -108.515213) (xy 9.023608 -108.586745)
			(xy 8.978546 -108.654185) (xy 8.927091 -108.716884) (xy 8.869738 -108.774237) (xy 8.807039 -108.825692)
			(xy 8.739599 -108.870754) (xy 8.668067 -108.908989) (xy 8.593131 -108.940028) (xy 8.515515 -108.963573)
			(xy 8.435964 -108.979396) (xy 8.355245 -108.987346) (xy 8.274135 -108.987346) (xy 8.193416 -108.979396)
			(xy 8.113865 -108.963573) (xy 8.036249 -108.940028) (xy 7.961313 -108.908989) (xy 7.889781 -108.870754)
			(xy 7.822341 -108.825692) (xy 7.759642 -108.774237) (xy 7.702289 -108.716884) (xy 7.650834 -108.654185)
			(xy 7.605772 -108.586745) (xy 7.567537 -108.515213) (xy 7.536498 -108.440277) (xy 7.512953 -108.362661)
			(xy 7.49713 -108.28311) (xy 7.48918 -108.202391) (xy 6.6002 -108.202391) (xy 6.59225 -108.28311)
			(xy 6.576427 -108.362661) (xy 6.552882 -108.440277) (xy 6.521843 -108.515213) (xy 6.483608 -108.586745)
			(xy 6.438546 -108.654185) (xy 6.387091 -108.716884) (xy 6.329738 -108.774237) (xy 6.267039 -108.825692)
			(xy 6.199599 -108.870754) (xy 6.128067 -108.908989) (xy 6.053131 -108.940028) (xy 5.975515 -108.963573)
			(xy 5.895964 -108.979396) (xy 5.815245 -108.987346) (xy 5.734135 -108.987346) (xy 5.653416 -108.979396)
			(xy 5.573865 -108.963573) (xy 5.496249 -108.940028) (xy 5.421313 -108.908989) (xy 5.349781 -108.870754)
			(xy 5.282341 -108.825692) (xy 5.219642 -108.774237) (xy 5.162289 -108.716884) (xy 5.110834 -108.654185)
			(xy 5.065772 -108.586745) (xy 5.027537 -108.515213) (xy 4.996498 -108.440277) (xy 4.972953 -108.362661)
			(xy 4.95713 -108.28311) (xy 4.94918 -108.202391) (xy 1.27 -108.202391) (xy 1.27 -129.249987) (xy 4.037327 -129.249987)
			(xy 4.037327 -129.170121) (xy 4.045407 -129.090666) (xy 4.061484 -129.012436) (xy 4.085393 -128.936234)
			(xy 4.116888 -128.862841) (xy 4.155647 -128.793011) (xy 4.201271 -128.727461) (xy 4.253293 -128.666862)
			(xy 4.311178 -128.611838) (xy 4.374334 -128.562952) (xy 4.442111 -128.520706) (xy 4.513814 -128.485534)
			(xy 4.588708 -128.457797) (xy 4.666023 -128.437778) (xy 4.744967 -128.425685) (xy 4.82473 -128.42164)
			(xy 4.904493 -128.425685) (xy 4.983437 -128.437778) (xy 5.060752 -128.457797) (xy 5.135646 -128.485534)
			(xy 5.207349 -128.520706) (xy 5.275126 -128.562952) (xy 5.338282 -128.611838) (xy 5.396167 -128.666862)
			(xy 5.448189 -128.727461) (xy 5.493813 -128.793011) (xy 5.532572 -128.862841) (xy 5.564067 -128.936234)
			(xy 5.587976 -129.012436) (xy 5.604053 -129.090666) (xy 5.612133 -129.170121) (xy 5.612638 -129.210054)
			(xy 5.612133 -129.249987) (xy 6.577327 -129.249987) (xy 6.577327 -129.170121) (xy 6.585407 -129.090666)
			(xy 6.601484 -129.012436) (xy 6.625393 -128.936234) (xy 6.656888 -128.862841) (xy 6.695647 -128.793011)
			(xy 6.741271 -128.727461) (xy 6.793293 -128.666862) (xy 6.851178 -128.611838) (xy 6.914334 -128.562952)
			(xy 6.982111 -128.520706) (xy 7.053814 -128.485534) (xy 7.128708 -128.457797) (xy 7.206023 -128.437778)
			(xy 7.284967 -128.425685) (xy 7.36473 -128.42164) (xy 7.444493 -128.425685) (xy 7.523437 -128.437778)
			(xy 7.600752 -128.457797) (xy 7.675646 -128.485534) (xy 7.747349 -128.520706) (xy 7.815126 -128.562952)
			(xy 7.878282 -128.611838) (xy 7.936167 -128.666862) (xy 7.988189 -128.727461) (xy 8.033813 -128.793011)
			(xy 8.072572 -128.862841) (xy 8.104067 -128.936234) (xy 8.127976 -129.012436) (xy 8.144053 -129.090666)
			(xy 8.152133 -129.170121) (xy 8.152638 -129.210054) (xy 8.152133 -129.249987) (xy 9.117327 -129.249987)
			(xy 9.117327 -129.170121) (xy 9.125407 -129.090666) (xy 9.141484 -129.012436) (xy 9.165393 -128.936234)
			(xy 9.196888 -128.862841) (xy 9.235647 -128.793011) (xy 9.281271 -128.727461) (xy 9.333293 -128.666862)
			(xy 9.391178 -128.611838) (xy 9.454334 -128.562952) (xy 9.522111 -128.520706) (xy 9.593814 -128.485534)
			(xy 9.668708 -128.457797) (xy 9.746023 -128.437778) (xy 9.824967 -128.425685) (xy 9.90473 -128.42164)
			(xy 9.984493 -128.425685) (xy 10.063437 -128.437778) (xy 10.140752 -128.457797) (xy 10.215646 -128.485534)
			(xy 10.287349 -128.520706) (xy 10.355126 -128.562952) (xy 10.418282 -128.611838) (xy 10.476167 -128.666862)
			(xy 10.528189 -128.727461) (xy 10.573813 -128.793011) (xy 10.612572 -128.862841) (xy 10.644067 -128.936234)
			(xy 10.667976 -129.012436) (xy 10.684053 -129.090666) (xy 10.692133 -129.170121) (xy 10.692638 -129.210054)
			(xy 10.692133 -129.249987) (xy 11.657327 -129.249987) (xy 11.657327 -129.170121) (xy 11.665407 -129.090666)
			(xy 11.681484 -129.012436) (xy 11.705393 -128.936234) (xy 11.736888 -128.862841) (xy 11.775647 -128.793011)
			(xy 11.821271 -128.727461) (xy 11.873293 -128.666862) (xy 11.931178 -128.611838) (xy 11.994334 -128.562952)
			(xy 12.062111 -128.520706) (xy 12.133814 -128.485534) (xy 12.208708 -128.457797) (xy 12.286023 -128.437778)
			(xy 12.364967 -128.425685) (xy 12.44473 -128.42164) (xy 12.524493 -128.425685) (xy 12.603437 -128.437778)
			(xy 12.680752 -128.457797) (xy 12.755646 -128.485534) (xy 12.827349 -128.520706) (xy 12.895126 -128.562952)
			(xy 12.958282 -128.611838) (xy 13.016167 -128.666862) (xy 13.068189 -128.727461) (xy 13.113813 -128.793011)
			(xy 13.152572 -128.862841) (xy 13.184067 -128.936234) (xy 13.207976 -129.012436) (xy 13.224053 -129.090666)
			(xy 13.232133 -129.170121) (xy 13.232638 -129.210054) (xy 13.232133 -129.249987) (xy 13.224053 -129.329442)
			(xy 13.207976 -129.407672) (xy 13.184067 -129.483874) (xy 13.152572 -129.557267) (xy 13.113813 -129.627097)
			(xy 13.068189 -129.692647) (xy 13.016167 -129.753246) (xy 12.958282 -129.80827) (xy 12.895126 -129.857156)
			(xy 12.827349 -129.899402) (xy 12.755646 -129.934574) (xy 12.680752 -129.962311) (xy 12.603437 -129.98233)
			(xy 12.524493 -129.994423) (xy 12.44473 -129.998469) (xy 12.364967 -129.994423) (xy 12.286023 -129.98233)
			(xy 12.208708 -129.962311) (xy 12.133814 -129.934574) (xy 12.062111 -129.899402) (xy 11.994334 -129.857156)
			(xy 11.931178 -129.80827) (xy 11.873293 -129.753246) (xy 11.821271 -129.692647) (xy 11.775647 -129.627097)
			(xy 11.736888 -129.557267) (xy 11.705393 -129.483874) (xy 11.681484 -129.407672) (xy 11.665407 -129.329442)
			(xy 11.657327 -129.249987) (xy 10.692133 -129.249987) (xy 10.684053 -129.329442) (xy 10.667976 -129.407672)
			(xy 10.644067 -129.483874) (xy 10.612572 -129.557267) (xy 10.573813 -129.627097) (xy 10.528189 -129.692647)
			(xy 10.476167 -129.753246) (xy 10.418282 -129.80827) (xy 10.355126 -129.857156) (xy 10.287349 -129.899402)
			(xy 10.215646 -129.934574) (xy 10.140752 -129.962311) (xy 10.063437 -129.98233) (xy 9.984493 -129.994423)
			(xy 9.90473 -129.998469) (xy 9.824967 -129.994423) (xy 9.746023 -129.98233) (xy 9.668708 -129.962311)
			(xy 9.593814 -129.934574) (xy 9.522111 -129.899402) (xy 9.454334 -129.857156) (xy 9.391178 -129.80827)
			(xy 9.333293 -129.753246) (xy 9.281271 -129.692647) (xy 9.235647 -129.627097) (xy 9.196888 -129.557267)
			(xy 9.165393 -129.483874) (xy 9.141484 -129.407672) (xy 9.125407 -129.329442) (xy 9.117327 -129.249987)
			(xy 8.152133 -129.249987) (xy 8.144053 -129.329442) (xy 8.127976 -129.407672) (xy 8.104067 -129.483874)
			(xy 8.072572 -129.557267) (xy 8.033813 -129.627097) (xy 7.988189 -129.692647) (xy 7.936167 -129.753246)
			(xy 7.878282 -129.80827) (xy 7.815126 -129.857156) (xy 7.747349 -129.899402) (xy 7.675646 -129.934574)
			(xy 7.600752 -129.962311) (xy 7.523437 -129.98233) (xy 7.444493 -129.994423) (xy 7.36473 -129.998469)
			(xy 7.284967 -129.994423) (xy 7.206023 -129.98233) (xy 7.128708 -129.962311) (xy 7.053814 -129.934574)
			(xy 6.982111 -129.899402) (xy 6.914334 -129.857156) (xy 6.851178 -129.80827) (xy 6.793293 -129.753246)
			(xy 6.741271 -129.692647) (xy 6.695647 -129.627097) (xy 6.656888 -129.557267) (xy 6.625393 -129.483874)
			(xy 6.601484 -129.407672) (xy 6.585407 -129.329442) (xy 6.577327 -129.249987) (xy 5.612133 -129.249987)
			(xy 5.604053 -129.329442) (xy 5.587976 -129.407672) (xy 5.564067 -129.483874) (xy 5.532572 -129.557267)
			(xy 5.493813 -129.627097) (xy 5.448189 -129.692647) (xy 5.396167 -129.753246) (xy 5.338282 -129.80827)
			(xy 5.275126 -129.857156) (xy 5.207349 -129.899402) (xy 5.135646 -129.934574) (xy 5.060752 -129.962311)
			(xy 4.983437 -129.98233) (xy 4.904493 -129.994423) (xy 4.82473 -129.998469) (xy 4.744967 -129.994423)
			(xy 4.666023 -129.98233) (xy 4.588708 -129.962311) (xy 4.513814 -129.934574) (xy 4.442111 -129.899402)
			(xy 4.374334 -129.857156) (xy 4.311178 -129.80827) (xy 4.253293 -129.753246) (xy 4.201271 -129.692647)
			(xy 4.155647 -129.627097) (xy 4.116888 -129.557267) (xy 4.085393 -129.483874) (xy 4.061484 -129.407672)
			(xy 4.045407 -129.329442) (xy 4.037327 -129.249987) (xy 1.27 -129.249987) (xy 1.27 -131.789987) (xy 5.307327 -131.789987)
			(xy 5.307327 -131.710121) (xy 5.315407 -131.630666) (xy 5.331484 -131.552436) (xy 5.355393 -131.476234)
			(xy 5.386888 -131.402841) (xy 5.425647 -131.333011) (xy 5.471271 -131.267461) (xy 5.523293 -131.206862)
			(xy 5.581178 -131.151838) (xy 5.644334 -131.102952) (xy 5.712111 -131.060706) (xy 5.783814 -131.025534)
			(xy 5.858708 -130.997797) (xy 5.936023 -130.977778) (xy 6.014967 -130.965685) (xy 6.09473 -130.96164)
			(xy 6.174493 -130.965685) (xy 6.253437 -130.977778) (xy 6.330752 -130.997797) (xy 6.405646 -131.025534)
			(xy 6.477349 -131.060706) (xy 6.545126 -131.102952) (xy 6.608282 -131.151838) (xy 6.666167 -131.206862)
			(xy 6.718189 -131.267461) (xy 6.763813 -131.333011) (xy 6.802572 -131.402841) (xy 6.834067 -131.476234)
			(xy 6.857976 -131.552436) (xy 6.874053 -131.630666) (xy 6.882133 -131.710121) (xy 6.882638 -131.750054)
			(xy 6.882133 -131.789987) (xy 7.847327 -131.789987) (xy 7.847327 -131.710121) (xy 7.855407 -131.630666)
			(xy 7.871484 -131.552436) (xy 7.895393 -131.476234) (xy 7.926888 -131.402841) (xy 7.965647 -131.333011)
			(xy 8.011271 -131.267461) (xy 8.063293 -131.206862) (xy 8.121178 -131.151838) (xy 8.184334 -131.102952)
			(xy 8.252111 -131.060706) (xy 8.323814 -131.025534) (xy 8.398708 -130.997797) (xy 8.476023 -130.977778)
			(xy 8.554967 -130.965685) (xy 8.63473 -130.96164) (xy 8.714493 -130.965685) (xy 8.793437 -130.977778)
			(xy 8.870752 -130.997797) (xy 8.945646 -131.025534) (xy 9.017349 -131.060706) (xy 9.085126 -131.102952)
			(xy 9.148282 -131.151838) (xy 9.206167 -131.206862) (xy 9.258189 -131.267461) (xy 9.303813 -131.333011)
			(xy 9.342572 -131.402841) (xy 9.374067 -131.476234) (xy 9.397976 -131.552436) (xy 9.414053 -131.630666)
			(xy 9.422133 -131.710121) (xy 9.422638 -131.750054) (xy 9.422133 -131.789987) (xy 10.387327 -131.789987)
			(xy 10.387327 -131.710121) (xy 10.395407 -131.630666) (xy 10.411484 -131.552436) (xy 10.435393 -131.476234)
			(xy 10.466888 -131.402841) (xy 10.505647 -131.333011) (xy 10.551271 -131.267461) (xy 10.603293 -131.206862)
			(xy 10.661178 -131.151838) (xy 10.724334 -131.102952) (xy 10.792111 -131.060706) (xy 10.863814 -131.025534)
			(xy 10.938708 -130.997797) (xy 11.016023 -130.977778) (xy 11.094967 -130.965685) (xy 11.17473 -130.96164)
			(xy 11.254493 -130.965685) (xy 11.333437 -130.977778) (xy 11.410752 -130.997797) (xy 11.485646 -131.025534)
			(xy 11.557349 -131.060706) (xy 11.625126 -131.102952) (xy 11.688282 -131.151838) (xy 11.746167 -131.206862)
			(xy 11.798189 -131.267461) (xy 11.843813 -131.333011) (xy 11.882572 -131.402841) (xy 11.914067 -131.476234)
			(xy 11.937976 -131.552436) (xy 11.954053 -131.630666) (xy 11.962133 -131.710121) (xy 11.962638 -131.750054)
			(xy 11.962133 -131.789987) (xy 12.927327 -131.789987) (xy 12.927327 -131.710121) (xy 12.935407 -131.630666)
			(xy 12.951484 -131.552436) (xy 12.975393 -131.476234) (xy 13.006888 -131.402841) (xy 13.045647 -131.333011)
			(xy 13.091271 -131.267461) (xy 13.143293 -131.206862) (xy 13.201178 -131.151838) (xy 13.264334 -131.102952)
			(xy 13.332111 -131.060706) (xy 13.403814 -131.025534) (xy 13.478708 -130.997797) (xy 13.556023 -130.977778)
			(xy 13.634967 -130.965685) (xy 13.71473 -130.96164) (xy 13.794493 -130.965685) (xy 13.873437 -130.977778)
			(xy 13.950752 -130.997797) (xy 14.025646 -131.025534) (xy 14.097349 -131.060706) (xy 14.165126 -131.102952)
			(xy 14.228282 -131.151838) (xy 14.286167 -131.206862) (xy 14.338189 -131.267461) (xy 14.383813 -131.333011)
			(xy 14.422572 -131.402841) (xy 14.454067 -131.476234) (xy 14.477976 -131.552436) (xy 14.494053 -131.630666)
			(xy 14.502133 -131.710121) (xy 14.502638 -131.750054) (xy 14.502133 -131.789987) (xy 14.494053 -131.869442)
			(xy 14.477976 -131.947672) (xy 14.454067 -132.023874) (xy 14.422572 -132.097267) (xy 14.383813 -132.167097)
			(xy 14.338189 -132.232647) (xy 14.286167 -132.293246) (xy 14.228282 -132.34827) (xy 14.165126 -132.397156)
			(xy 14.097349 -132.439402) (xy 14.025646 -132.474574) (xy 13.950752 -132.502311) (xy 13.873437 -132.52233)
			(xy 13.794493 -132.534423) (xy 13.71473 -132.538469) (xy 13.634967 -132.534423) (xy 13.556023 -132.52233)
			(xy 13.478708 -132.502311) (xy 13.403814 -132.474574) (xy 13.332111 -132.439402) (xy 13.264334 -132.397156)
			(xy 13.201178 -132.34827) (xy 13.143293 -132.293246) (xy 13.091271 -132.232647) (xy 13.045647 -132.167097)
			(xy 13.006888 -132.097267) (xy 12.975393 -132.023874) (xy 12.951484 -131.947672) (xy 12.935407 -131.869442)
			(xy 12.927327 -131.789987) (xy 11.962133 -131.789987) (xy 11.954053 -131.869442) (xy 11.937976 -131.947672)
			(xy 11.914067 -132.023874) (xy 11.882572 -132.097267) (xy 11.843813 -132.167097) (xy 11.798189 -132.232647)
			(xy 11.746167 -132.293246) (xy 11.688282 -132.34827) (xy 11.625126 -132.397156) (xy 11.557349 -132.439402)
			(xy 11.485646 -132.474574) (xy 11.410752 -132.502311) (xy 11.333437 -132.52233) (xy 11.254493 -132.534423)
			(xy 11.17473 -132.538469) (xy 11.094967 -132.534423) (xy 11.016023 -132.52233) (xy 10.938708 -132.502311)
			(xy 10.863814 -132.474574) (xy 10.792111 -132.439402) (xy 10.724334 -132.397156) (xy 10.661178 -132.34827)
			(xy 10.603293 -132.293246) (xy 10.551271 -132.232647) (xy 10.505647 -132.167097) (xy 10.466888 -132.097267)
			(xy 10.435393 -132.023874) (xy 10.411484 -131.947672) (xy 10.395407 -131.869442) (xy 10.387327 -131.789987)
			(xy 9.422133 -131.789987) (xy 9.414053 -131.869442) (xy 9.397976 -131.947672) (xy 9.374067 -132.023874)
			(xy 9.342572 -132.097267) (xy 9.303813 -132.167097) (xy 9.258189 -132.232647) (xy 9.206167 -132.293246)
			(xy 9.148282 -132.34827) (xy 9.085126 -132.397156) (xy 9.017349 -132.439402) (xy 8.945646 -132.474574)
			(xy 8.870752 -132.502311) (xy 8.793437 -132.52233) (xy 8.714493 -132.534423) (xy 8.63473 -132.538469)
			(xy 8.554967 -132.534423) (xy 8.476023 -132.52233) (xy 8.398708 -132.502311) (xy 8.323814 -132.474574)
			(xy 8.252111 -132.439402) (xy 8.184334 -132.397156) (xy 8.121178 -132.34827) (xy 8.063293 -132.293246)
			(xy 8.011271 -132.232647) (xy 7.965647 -132.167097) (xy 7.926888 -132.097267) (xy 7.895393 -132.023874)
			(xy 7.871484 -131.947672) (xy 7.855407 -131.869442) (xy 7.847327 -131.789987) (xy 6.882133 -131.789987)
			(xy 6.874053 -131.869442) (xy 6.857976 -131.947672) (xy 6.834067 -132.023874) (xy 6.802572 -132.097267)
			(xy 6.763813 -132.167097) (xy 6.718189 -132.232647) (xy 6.666167 -132.293246) (xy 6.608282 -132.34827)
			(xy 6.545126 -132.397156) (xy 6.477349 -132.439402) (xy 6.405646 -132.474574) (xy 6.330752 -132.502311)
			(xy 6.253437 -132.52233) (xy 6.174493 -132.534423) (xy 6.09473 -132.538469) (xy 6.014967 -132.534423)
			(xy 5.936023 -132.52233) (xy 5.858708 -132.502311) (xy 5.783814 -132.474574) (xy 5.712111 -132.439402)
			(xy 5.644334 -132.397156) (xy 5.581178 -132.34827) (xy 5.523293 -132.293246) (xy 5.471271 -132.232647)
			(xy 5.425647 -132.167097) (xy 5.386888 -132.097267) (xy 5.355393 -132.023874) (xy 5.331484 -131.947672)
			(xy 5.315407 -131.869442) (xy 5.307327 -131.789987) (xy 1.27 -131.789987) (xy 1.27 -132.814568) (xy 1.27054 -132.831195)
			(xy 1.279136 -132.86332) (xy 1.295744 -132.892131) (xy 1.319235 -132.915669) (xy 1.348012 -132.932335)
			(xy 1.38012 -132.940996) (xy 1.396746 -132.941568) (xy 1.44809 -132.94215) (xy 1.550451 -132.950358)
			(xy 1.651854 -132.966564) (xy 1.751674 -132.990668) (xy 1.849299 -133.022522) (xy 1.944126 -133.06193)
			(xy 2.035572 -133.10865) (xy 2.123075 -133.162393) (xy 2.206097 -133.22283) (xy 2.284125 -133.289588)
			(xy 2.356681 -133.362257) (xy 2.423318 -133.44039) (xy 2.483626 -133.523505) (xy 2.537234 -133.611091)
			(xy 2.583811 -133.70261) (xy 2.623072 -133.797498) (xy 2.654775 -133.895172) (xy 2.678724 -133.99503)
			(xy 2.694772 -134.096457) (xy 2.702821 -134.198831) (xy 2.702821 -134.301521) (xy 2.702817 -134.301572)
			(xy 15.836642 -134.301572) (xy 15.836642 -134.19878) (xy 15.844707 -134.096306) (xy 15.860787 -133.994781)
			(xy 15.884783 -133.89483) (xy 15.916548 -133.79707) (xy 15.955884 -133.702103) (xy 16.00255 -133.610516)
			(xy 16.056258 -133.522872) (xy 16.116677 -133.439712) (xy 16.183435 -133.361549) (xy 16.256119 -133.288865)
			(xy 16.334282 -133.222107) (xy 16.417442 -133.161688) (xy 16.505086 -133.10798) (xy 16.596673 -133.061314)
			(xy 16.69164 -133.021978) (xy 16.7894 -132.990213) (xy 16.889351 -132.966217) (xy 16.990876 -132.950137)
			(xy 17.09335 -132.942072) (xy 17.196142 -132.942072) (xy 17.298616 -132.950137) (xy 17.400141 -132.966217)
			(xy 17.500092 -132.990213) (xy 17.597852 -133.021978) (xy 17.692819 -133.061314) (xy 17.784406 -133.10798)
			(xy 17.87205 -133.161688) (xy 17.95521 -133.222107) (xy 18.033373 -133.288865) (xy 18.106057 -133.361549)
			(xy 18.172815 -133.439712) (xy 18.233234 -133.522872) (xy 18.286942 -133.610516) (xy 18.333608 -133.702103)
			(xy 18.372944 -133.79707) (xy 18.404709 -133.89483) (xy 18.428705 -133.994781) (xy 18.444785 -134.096306)
			(xy 18.45285 -134.19878) (xy 18.453354 -134.250176) (xy 18.45285 -134.301572) (xy 18.444785 -134.404046)
			(xy 18.428705 -134.505571) (xy 18.404709 -134.605522) (xy 18.372944 -134.703282) (xy 18.333608 -134.798249)
			(xy 18.286942 -134.889836) (xy 18.233234 -134.97748) (xy 18.172815 -135.06064) (xy 18.106057 -135.138803)
			(xy 18.033373 -135.211487) (xy 17.95521 -135.278245) (xy 17.87205 -135.338664) (xy 17.784406 -135.392372)
			(xy 17.692819 -135.439038) (xy 17.597852 -135.478374) (xy 17.500092 -135.510139) (xy 17.400141 -135.534135)
			(xy 17.298616 -135.550215) (xy 17.196142 -135.55828) (xy 17.09335 -135.55828) (xy 16.990876 -135.550215)
			(xy 16.889351 -135.534135) (xy 16.7894 -135.510139) (xy 16.69164 -135.478374) (xy 16.596673 -135.439038)
			(xy 16.505086 -135.392372) (xy 16.417442 -135.338664) (xy 16.334282 -135.278245) (xy 16.256119 -135.211487)
			(xy 16.183435 -135.138803) (xy 16.116677 -135.06064) (xy 16.056258 -134.97748) (xy 16.00255 -134.889836)
			(xy 15.955884 -134.798249) (xy 15.916548 -134.703282) (xy 15.884783 -134.605522) (xy 15.860787 -134.505571)
			(xy 15.844707 -134.404046) (xy 15.836642 -134.301572) (xy 2.702817 -134.301572) (xy 2.694772 -134.403895)
			(xy 2.678724 -134.505322) (xy 2.654775 -134.60518) (xy 2.623072 -134.702854) (xy 2.583811 -134.797742)
			(xy 2.537234 -134.889261) (xy 2.483626 -134.976847) (xy 2.423318 -135.059962) (xy 2.356681 -135.138095)
			(xy 2.284125 -135.210764) (xy 2.206097 -135.277522) (xy 2.123075 -135.337959) (xy 2.035572 -135.391702)
			(xy 1.944126 -135.438422) (xy 1.849299 -135.47783) (xy 1.751674 -135.509684) (xy 1.651854 -135.533788)
			(xy 1.550451 -135.549994) (xy 1.44809 -135.558202) (xy 1.396746 -135.558784) (xy 1.380119 -135.559358)
			(xy 1.34801 -135.568018) (xy 1.319231 -135.584683) (xy 1.295738 -135.608221) (xy 1.279126 -135.637031)
			(xy 1.270526 -135.669156) (xy 1.27 -135.685784) (xy 1.27 -138.163122) (xy 1.547863 -138.163122) (xy 1.547863 -138.036986)
			(xy 1.555783 -137.911098) (xy 1.571593 -137.785956) (xy 1.595228 -137.662053) (xy 1.626597 -137.53988)
			(xy 1.665575 -137.419917) (xy 1.712009 -137.302638) (xy 1.765716 -137.188506) (xy 1.826483 -137.077971)
			(xy 1.89407 -136.971471) (xy 1.968211 -136.869424) (xy 2.048614 -136.772234) (xy 2.13496 -136.680284)
			(xy 2.22691 -136.593938) (xy 2.3241 -136.513535) (xy 2.426147 -136.439394) (xy 2.532647 -136.371807)
			(xy 2.643182 -136.31104) (xy 2.757314 -136.257333) (xy 2.874593 -136.210899) (xy 2.994556 -136.171921)
			(xy 3.116729 -136.140552) (xy 3.240632 -136.116917) (xy 3.365774 -136.101107) (xy 3.491662 -136.093187)
			(xy 3.617798 -136.093187) (xy 3.743686 -136.101107) (xy 3.868828 -136.116917) (xy 3.992731 -136.140552)
			(xy 4.114904 -136.171921) (xy 4.234867 -136.210899) (xy 4.352146 -136.257333) (xy 4.466278 -136.31104)
			(xy 4.576813 -136.371807) (xy 4.683313 -136.439394) (xy 4.78536 -136.513535) (xy 4.88255 -136.593938)
			(xy 4.9745 -136.680284) (xy 5.060846 -136.772234) (xy 5.141249 -136.869424) (xy 5.21539 -136.971471)
			(xy 5.282977 -137.077971) (xy 5.343744 -137.188506) (xy 5.397451 -137.302638) (xy 5.443885 -137.419917)
			(xy 5.482863 -137.53988) (xy 5.514232 -137.662053) (xy 5.537867 -137.785956) (xy 5.553677 -137.911098)
			(xy 5.561597 -138.036986) (xy 5.562092 -138.100054) (xy 5.561597 -138.163122) (xy 12.977863 -138.163122)
			(xy 12.977863 -138.036986) (xy 12.985783 -137.911098) (xy 13.001593 -137.785956) (xy 13.025228 -137.662053)
			(xy 13.056597 -137.53988) (xy 13.095575 -137.419917) (xy 13.142009 -137.302638) (xy 13.195716 -137.188506)
			(xy 13.256483 -137.077971) (xy 13.32407 -136.971471) (xy 13.398211 -136.869424) (xy 13.478614 -136.772234)
			(xy 13.56496 -136.680284) (xy 13.65691 -136.593938) (xy 13.7541 -136.513535) (xy 13.856147 -136.439394)
			(xy 13.962647 -136.371807) (xy 14.073182 -136.31104) (xy 14.187314 -136.257333) (xy 14.304593 -136.210899)
			(xy 14.424556 -136.171921) (xy 14.546729 -136.140552) (xy 14.670632 -136.116917) (xy 14.795774 -136.101107)
			(xy 14.921662 -136.093187) (xy 15.047798 -136.093187) (xy 15.173686 -136.101107) (xy 15.298828 -136.116917)
			(xy 15.422731 -136.140552) (xy 15.544904 -136.171921) (xy 15.664867 -136.210899) (xy 15.782146 -136.257333)
			(xy 15.896278 -136.31104) (xy 16.006813 -136.371807) (xy 16.113313 -136.439394) (xy 16.21536 -136.513535)
			(xy 16.31255 -136.593938) (xy 16.4045 -136.680284) (xy 16.490846 -136.772234) (xy 16.571249 -136.869424)
			(xy 16.64539 -136.971471) (xy 16.712977 -137.077971) (xy 16.773744 -137.188506) (xy 16.827451 -137.302638)
			(xy 16.873885 -137.419917) (xy 16.912863 -137.53988) (xy 16.944232 -137.662053) (xy 16.967867 -137.785956)
			(xy 16.983677 -137.911098) (xy 16.991597 -138.036986) (xy 16.992092 -138.100054) (xy 16.991597 -138.163122)
			(xy 16.983677 -138.28901) (xy 16.967867 -138.414152) (xy 16.944232 -138.538055) (xy 16.912863 -138.660228)
			(xy 16.873885 -138.780191) (xy 16.827451 -138.89747) (xy 16.773744 -139.011602) (xy 16.712977 -139.122137)
			(xy 16.64539 -139.228637) (xy 16.571249 -139.330684) (xy 16.490846 -139.427874) (xy 16.4045 -139.519824)
			(xy 16.31255 -139.60617) (xy 16.21536 -139.686573) (xy 16.113313 -139.760714) (xy 16.006813 -139.828301)
			(xy 15.896278 -139.889068) (xy 15.782146 -139.942775) (xy 15.664867 -139.989209) (xy 15.544904 -140.028187)
			(xy 15.422731 -140.059556) (xy 15.298828 -140.083191) (xy 15.173686 -140.099001) (xy 15.047798 -140.106921)
			(xy 14.921662 -140.106921) (xy 14.795774 -140.099001) (xy 14.670632 -140.083191) (xy 14.546729 -140.059556)
			(xy 14.424556 -140.028187) (xy 14.304593 -139.989209) (xy 14.187314 -139.942775) (xy 14.073182 -139.889068)
			(xy 13.962647 -139.828301) (xy 13.856147 -139.760714) (xy 13.7541 -139.686573) (xy 13.65691 -139.60617)
			(xy 13.56496 -139.519824) (xy 13.478614 -139.427874) (xy 13.398211 -139.330684) (xy 13.32407 -139.228637)
			(xy 13.256483 -139.122137) (xy 13.195716 -139.011602) (xy 13.142009 -138.89747) (xy 13.095575 -138.780191)
			(xy 13.056597 -138.660228) (xy 13.025228 -138.538055) (xy 13.001593 -138.414152) (xy 12.985783 -138.28901)
			(xy 12.977863 -138.163122) (xy 5.561597 -138.163122) (xy 5.553677 -138.28901) (xy 5.537867 -138.414152)
			(xy 5.514232 -138.538055) (xy 5.482863 -138.660228) (xy 5.443885 -138.780191) (xy 5.397451 -138.89747)
			(xy 5.343744 -139.011602) (xy 5.282977 -139.122137) (xy 5.21539 -139.228637) (xy 5.141249 -139.330684)
			(xy 5.060846 -139.427874) (xy 4.9745 -139.519824) (xy 4.88255 -139.60617) (xy 4.78536 -139.686573)
			(xy 4.683313 -139.760714) (xy 4.576813 -139.828301) (xy 4.466278 -139.889068) (xy 4.352146 -139.942775)
			(xy 4.234867 -139.989209) (xy 4.114904 -140.028187) (xy 3.992731 -140.059556) (xy 3.868828 -140.083191)
			(xy 3.743686 -140.099001) (xy 3.617798 -140.106921) (xy 3.491662 -140.106921) (xy 3.365774 -140.099001)
			(xy 3.240632 -140.083191) (xy 3.116729 -140.059556) (xy 2.994556 -140.028187) (xy 2.874593 -139.989209)
			(xy 2.757314 -139.942775) (xy 2.643182 -139.889068) (xy 2.532647 -139.828301) (xy 2.426147 -139.760714)
			(xy 2.3241 -139.686573) (xy 2.22691 -139.60617) (xy 2.13496 -139.519824) (xy 2.048614 -139.427874)
			(xy 1.968211 -139.330684) (xy 1.89407 -139.228637) (xy 1.826483 -139.122137) (xy 1.765716 -139.011602)
			(xy 1.712009 -138.89747) (xy 1.665575 -138.780191) (xy 1.626597 -138.660228) (xy 1.595228 -138.538055)
			(xy 1.571593 -138.414152) (xy 1.555783 -138.28901) (xy 1.547863 -138.163122) (xy 1.27 -138.163122)
			(xy 1.27 -142.249961) (xy 2.182365 -142.249961) (xy 2.182365 -142.170095) (xy 2.190445 -142.09064)
			(xy 2.206522 -142.01241) (xy 2.230431 -141.936208) (xy 2.261926 -141.862815) (xy 2.300685 -141.792985)
			(xy 2.346309 -141.727435) (xy 2.398331 -141.666836) (xy 2.456216 -141.611812) (xy 2.519372 -141.562926)
			(xy 2.587149 -141.52068) (xy 2.658852 -141.485508) (xy 2.733746 -141.457771) (xy 2.811061 -141.437752)
			(xy 2.890005 -141.425659) (xy 2.969768 -141.421614) (xy 3.049531 -141.425659) (xy 3.128475 -141.437752)
			(xy 3.20579 -141.457771) (xy 3.280684 -141.485508) (xy 3.352387 -141.52068) (xy 3.420164 -141.562926)
			(xy 3.48332 -141.611812) (xy 3.541205 -141.666836) (xy 3.593227 -141.727435) (xy 3.638851 -141.792985)
			(xy 3.67761 -141.862815) (xy 3.709105 -141.936208) (xy 3.733014 -142.01241) (xy 3.749091 -142.09064)
			(xy 3.757171 -142.170095) (xy 3.757676 -142.210028) (xy 3.757171 -142.249961) (xy 4.672327 -142.249961)
			(xy 4.672327 -142.170095) (xy 4.680407 -142.09064) (xy 4.696484 -142.01241) (xy 4.720393 -141.936208)
			(xy 4.751888 -141.862815) (xy 4.790647 -141.792985) (xy 4.836271 -141.727435) (xy 4.888293 -141.666836)
			(xy 4.946178 -141.611812) (xy 5.009334 -141.562926) (xy 5.077111 -141.52068) (xy 5.148814 -141.485508)
			(xy 5.223708 -141.457771) (xy 5.301023 -141.437752) (xy 5.379967 -141.425659) (xy 5.45973 -141.421614)
			(xy 5.539493 -141.425659) (xy 5.618437 -141.437752) (xy 5.695752 -141.457771) (xy 5.770646 -141.485508)
			(xy 5.842349 -141.52068) (xy 5.910126 -141.562926) (xy 5.973282 -141.611812) (xy 6.031167 -141.666836)
			(xy 6.083189 -141.727435) (xy 6.128813 -141.792985) (xy 6.167572 -141.862815) (xy 6.199067 -141.936208)
			(xy 6.222976 -142.01241) (xy 6.239053 -142.09064) (xy 6.247133 -142.170095) (xy 6.247638 -142.210028)
			(xy 6.247133 -142.249961) (xy 12.292327 -142.249961) (xy 12.292327 -142.170095) (xy 12.300407 -142.09064)
			(xy 12.316484 -142.01241) (xy 12.340393 -141.936208) (xy 12.371888 -141.862815) (xy 12.410647 -141.792985)
			(xy 12.456271 -141.727435) (xy 12.508293 -141.666836) (xy 12.566178 -141.611812) (xy 12.629334 -141.562926)
			(xy 12.697111 -141.52068) (xy 12.768814 -141.485508) (xy 12.843708 -141.457771) (xy 12.921023 -141.437752)
			(xy 12.999967 -141.425659) (xy 13.07973 -141.421614) (xy 13.159493 -141.425659) (xy 13.238437 -141.437752)
			(xy 13.315752 -141.457771) (xy 13.390646 -141.485508) (xy 13.462349 -141.52068) (xy 13.530126 -141.562926)
			(xy 13.593282 -141.611812) (xy 13.651167 -141.666836) (xy 13.703189 -141.727435) (xy 13.748813 -141.792985)
			(xy 13.787572 -141.862815) (xy 13.819067 -141.936208) (xy 13.842976 -142.01241) (xy 13.859053 -142.09064)
			(xy 13.867133 -142.170095) (xy 13.867638 -142.210028) (xy 13.867133 -142.249961) (xy 14.782289 -142.249961)
			(xy 14.782289 -142.170095) (xy 14.790369 -142.09064) (xy 14.806446 -142.01241) (xy 14.830355 -141.936208)
			(xy 14.86185 -141.862815) (xy 14.900609 -141.792985) (xy 14.946233 -141.727435) (xy 14.998255 -141.666836)
			(xy 15.05614 -141.611812) (xy 15.119296 -141.562926) (xy 15.187073 -141.52068) (xy 15.258776 -141.485508)
			(xy 15.33367 -141.457771) (xy 15.410985 -141.437752) (xy 15.489929 -141.425659) (xy 15.569692 -141.421614)
			(xy 15.649455 -141.425659) (xy 15.728399 -141.437752) (xy 15.805714 -141.457771) (xy 15.880608 -141.485508)
			(xy 15.952311 -141.52068) (xy 16.020088 -141.562926) (xy 16.083244 -141.611812) (xy 16.141129 -141.666836)
			(xy 16.193151 -141.727435) (xy 16.238775 -141.792985) (xy 16.277534 -141.862815) (xy 16.309029 -141.936208)
			(xy 16.332938 -142.01241) (xy 16.349015 -142.09064) (xy 16.357095 -142.170095) (xy 16.3576 -142.210028)
			(xy 16.357095 -142.249961) (xy 16.349015 -142.329416) (xy 16.332938 -142.407646) (xy 16.309029 -142.483848)
			(xy 16.277534 -142.557241) (xy 16.238775 -142.627071) (xy 16.193151 -142.692621) (xy 16.141129 -142.75322)
			(xy 16.083244 -142.808244) (xy 16.020088 -142.85713) (xy 15.952311 -142.899376) (xy 15.880608 -142.934548)
			(xy 15.805714 -142.962285) (xy 15.728399 -142.982304) (xy 15.649455 -142.994397) (xy 15.569692 -142.998443)
			(xy 15.489929 -142.994397) (xy 15.410985 -142.982304) (xy 15.33367 -142.962285) (xy 15.258776 -142.934548)
			(xy 15.187073 -142.899376) (xy 15.119296 -142.85713) (xy 15.05614 -142.808244) (xy 14.998255 -142.75322)
			(xy 14.946233 -142.692621) (xy 14.900609 -142.627071) (xy 14.86185 -142.557241) (xy 14.830355 -142.483848)
			(xy 14.806446 -142.407646) (xy 14.790369 -142.329416) (xy 14.782289 -142.249961) (xy 13.867133 -142.249961)
			(xy 13.859053 -142.329416) (xy 13.842976 -142.407646) (xy 13.819067 -142.483848) (xy 13.787572 -142.557241)
			(xy 13.748813 -142.627071) (xy 13.703189 -142.692621) (xy 13.651167 -142.75322) (xy 13.593282 -142.808244)
			(xy 13.530126 -142.85713) (xy 13.462349 -142.899376) (xy 13.390646 -142.934548) (xy 13.315752 -142.962285)
			(xy 13.238437 -142.982304) (xy 13.159493 -142.994397) (xy 13.07973 -142.998443) (xy 12.999967 -142.994397)
			(xy 12.921023 -142.982304) (xy 12.843708 -142.962285) (xy 12.768814 -142.934548) (xy 12.697111 -142.899376)
			(xy 12.629334 -142.85713) (xy 12.566178 -142.808244) (xy 12.508293 -142.75322) (xy 12.456271 -142.692621)
			(xy 12.410647 -142.627071) (xy 12.371888 -142.557241) (xy 12.340393 -142.483848) (xy 12.316484 -142.407646)
			(xy 12.300407 -142.329416) (xy 12.292327 -142.249961) (xy 6.247133 -142.249961) (xy 6.239053 -142.329416)
			(xy 6.222976 -142.407646) (xy 6.199067 -142.483848) (xy 6.167572 -142.557241) (xy 6.128813 -142.627071)
			(xy 6.083189 -142.692621) (xy 6.031167 -142.75322) (xy 5.973282 -142.808244) (xy 5.910126 -142.85713)
			(xy 5.842349 -142.899376) (xy 5.770646 -142.934548) (xy 5.695752 -142.962285) (xy 5.618437 -142.982304)
			(xy 5.539493 -142.994397) (xy 5.45973 -142.998443) (xy 5.379967 -142.994397) (xy 5.301023 -142.982304)
			(xy 5.223708 -142.962285) (xy 5.148814 -142.934548) (xy 5.077111 -142.899376) (xy 5.009334 -142.85713)
			(xy 4.946178 -142.808244) (xy 4.888293 -142.75322) (xy 4.836271 -142.692621) (xy 4.790647 -142.627071)
			(xy 4.751888 -142.557241) (xy 4.720393 -142.483848) (xy 4.696484 -142.407646) (xy 4.680407 -142.329416)
			(xy 4.672327 -142.249961) (xy 3.757171 -142.249961) (xy 3.749091 -142.329416) (xy 3.733014 -142.407646)
			(xy 3.709105 -142.483848) (xy 3.67761 -142.557241) (xy 3.638851 -142.627071) (xy 3.593227 -142.692621)
			(xy 3.541205 -142.75322) (xy 3.48332 -142.808244) (xy 3.420164 -142.85713) (xy 3.352387 -142.899376)
			(xy 3.280684 -142.934548) (xy 3.20579 -142.962285) (xy 3.128475 -142.982304) (xy 3.049531 -142.994397)
			(xy 2.969768 -142.998443) (xy 2.890005 -142.994397) (xy 2.811061 -142.982304) (xy 2.733746 -142.962285)
			(xy 2.658852 -142.934548) (xy 2.587149 -142.899376) (xy 2.519372 -142.85713) (xy 2.456216 -142.808244)
			(xy 2.398331 -142.75322) (xy 2.346309 -142.692621) (xy 2.300685 -142.627071) (xy 2.261926 -142.557241)
			(xy 2.230431 -142.483848) (xy 2.206522 -142.407646) (xy 2.190445 -142.329416) (xy 2.182365 -142.249961)
			(xy 1.27 -142.249961) (xy 1.27 -147.006564) (xy 2.58394 -147.006564) (xy 2.588011 -146.950942) (xy 2.600137 -146.896505)
			(xy 2.62006 -146.844414) (xy 2.647356 -146.795779) (xy 2.681442 -146.751636) (xy 2.721591 -146.712927)
			(xy 2.766949 -146.680476) (xy 2.816549 -146.654975) (xy 2.869333 -146.636968) (xy 2.924176 -146.626838)
			(xy 2.97991 -146.624801) (xy 3.035347 -146.630901) (xy 3.089304 -146.645007) (xy 3.140633 -146.666819)
			(xy 3.188239 -146.695873) (xy 3.231107 -146.731548) (xy 3.268324 -146.773085) (xy 3.299097 -146.819598)
			(xy 3.322769 -146.870095) (xy 3.338837 -146.923502) (xy 3.346957 -146.978678) (xy 3.347466 -147.006564)
			(xy 3.346957 -147.03445) (xy 3.338837 -147.089626) (xy 3.322769 -147.143033) (xy 3.299097 -147.19353)
			(xy 3.273737 -147.231862) (xy 14.540482 -147.231862) (xy 14.544553 -147.17624) (xy 14.556679 -147.121803)
			(xy 14.576602 -147.069712) (xy 14.603898 -147.021077) (xy 14.637984 -146.976934) (xy 14.678133 -146.938225)
			(xy 14.723491 -146.905774) (xy 14.773091 -146.880273) (xy 14.825875 -146.862266) (xy 14.880718 -146.852136)
			(xy 14.936452 -146.850099) (xy 14.991889 -146.856199) (xy 15.045846 -146.870305) (xy 15.097175 -146.892117)
			(xy 15.144781 -146.921171) (xy 15.187649 -146.956846) (xy 15.224866 -146.998383) (xy 15.255639 -147.044896)
			(xy 15.279311 -147.095393) (xy 15.295379 -147.1488) (xy 15.303499 -147.203976) (xy 15.304008 -147.231862)
			(xy 15.304003 -147.232116) (xy 15.828262 -147.232116) (xy 15.832333 -147.176494) (xy 15.844459 -147.122057)
			(xy 15.864382 -147.069966) (xy 15.891678 -147.021331) (xy 15.925764 -146.977188) (xy 15.965913 -146.938479)
			(xy 16.011271 -146.906028) (xy 16.060871 -146.880527) (xy 16.113655 -146.86252) (xy 16.168498 -146.85239)
			(xy 16.224232 -146.850353) (xy 16.279669 -146.856453) (xy 16.333626 -146.870559) (xy 16.384955 -146.892371)
			(xy 16.432561 -146.921425) (xy 16.475429 -146.9571) (xy 16.512646 -146.998637) (xy 16.543419 -147.04515)
			(xy 16.567091 -147.095647) (xy 16.583159 -147.149054) (xy 16.591279 -147.20423) (xy 16.591788 -147.232116)
			(xy 16.591279 -147.260002) (xy 16.583159 -147.315178) (xy 16.567091 -147.368585) (xy 16.543419 -147.419082)
			(xy 16.512646 -147.465595) (xy 16.475429 -147.507132) (xy 16.432561 -147.542807) (xy 16.384955 -147.571861)
			(xy 16.333626 -147.593673) (xy 16.279669 -147.607779) (xy 16.224232 -147.613879) (xy 16.168498 -147.611842)
			(xy 16.113655 -147.601712) (xy 16.060871 -147.583705) (xy 16.011271 -147.558204) (xy 15.965913 -147.525753)
			(xy 15.925764 -147.487044) (xy 15.891678 -147.442901) (xy 15.864382 -147.394266) (xy 15.844459 -147.342175)
			(xy 15.832333 -147.287738) (xy 15.828262 -147.232116) (xy 15.304003 -147.232116) (xy 15.303499 -147.259748)
			(xy 15.295379 -147.314924) (xy 15.279311 -147.368331) (xy 15.255639 -147.418828) (xy 15.224866 -147.465341)
			(xy 15.187649 -147.506878) (xy 15.144781 -147.542553) (xy 15.097175 -147.571607) (xy 15.045846 -147.593419)
			(xy 14.991889 -147.607525) (xy 14.936452 -147.613625) (xy 14.880718 -147.611588) (xy 14.825875 -147.601458)
			(xy 14.773091 -147.583451) (xy 14.723491 -147.55795) (xy 14.678133 -147.525499) (xy 14.637984 -147.48679)
			(xy 14.603898 -147.442647) (xy 14.576602 -147.394012) (xy 14.556679 -147.341921) (xy 14.544553 -147.287484)
			(xy 14.540482 -147.231862) (xy 3.273737 -147.231862) (xy 3.268324 -147.240043) (xy 3.231107 -147.28158)
			(xy 3.188239 -147.317255) (xy 3.140633 -147.346309) (xy 3.089304 -147.368121) (xy 3.035347 -147.382227)
			(xy 2.97991 -147.388327) (xy 2.924176 -147.38629) (xy 2.869333 -147.37616) (xy 2.816549 -147.358153)
			(xy 2.766949 -147.332652) (xy 2.721591 -147.300201) (xy 2.681442 -147.261492) (xy 2.647356 -147.217349)
			(xy 2.62006 -147.168714) (xy 2.600137 -147.116623) (xy 2.588011 -147.062186) (xy 2.58394 -147.006564)
			(xy 1.27 -147.006564) (xy 1.27 -152.374854) (xy 1.295616 -152.374854) (xy 1.299617 -152.279253) (xy 1.31159 -152.184321)
			(xy 1.331453 -152.09072) (xy 1.359066 -151.999107) (xy 1.394236 -151.91012) (xy 1.436718 -151.824383)
			(xy 1.486214 -151.742495) (xy 1.542379 -151.665028) (xy 1.604819 -151.592524) (xy 1.673098 -151.525491)
			(xy 1.746738 -151.464396) (xy 1.825226 -151.409667) (xy 1.908011 -151.361686) (xy 1.994515 -151.32079)
			(xy 2.084134 -151.287263) (xy 2.176241 -151.261341) (xy 2.270191 -151.243204) (xy 2.365327 -151.23298)
			(xy 2.460986 -151.23074) (xy 2.556497 -151.236499) (xy 2.651193 -151.250218) (xy 2.744412 -151.2718)
			(xy 2.835502 -151.301095) (xy 2.923826 -151.337897) (xy 3.008766 -151.38195) (xy 3.08973 -151.432945)
			(xy 3.16615 -151.490525) (xy 3.237492 -151.554289) (xy 3.303257 -151.623791) (xy 3.362987 -151.698543)
			(xy 3.416262 -151.778025) (xy 3.439922 -151.81961) (xy 3.463579 -151.778023) (xy 3.516854 -151.698541)
			(xy 3.576583 -151.623788) (xy 3.642348 -151.554286) (xy 3.71369 -151.490522) (xy 3.79011 -151.432941)
			(xy 3.871074 -151.381946) (xy 3.956014 -151.337893) (xy 4.044338 -151.30109) (xy 4.135428 -151.271795)
			(xy 4.228647 -151.250213) (xy 4.323343 -151.236494) (xy 4.418855 -151.230734) (xy 4.514513 -151.232974)
			(xy 4.60965 -151.243198) (xy 4.7036 -151.261334) (xy 4.795707 -151.287256) (xy 4.885326 -151.320782)
			(xy 4.971831 -151.361679) (xy 5.054616 -151.409659) (xy 5.133104 -151.464388) (xy 5.206745 -151.525483)
			(xy 5.275024 -151.592517) (xy 5.337465 -151.66502) (xy 5.39363 -151.742487) (xy 5.443126 -151.824375)
			(xy 5.485608 -151.910112) (xy 5.520779 -151.999099) (xy 5.548392 -152.090712) (xy 5.568255 -152.184313)
			(xy 5.580229 -152.279245) (xy 5.58423 -152.374847) (xy 5.58023 -152.470448) (xy 5.568256 -152.56538)
			(xy 5.548394 -152.658981) (xy 5.520781 -152.750595) (xy 5.485611 -152.839581) (xy 5.443129 -152.925319)
			(xy 5.393633 -153.007207) (xy 5.337469 -153.084674) (xy 5.275029 -153.157178) (xy 5.20675 -153.224212)
			(xy 5.13311 -153.285308) (xy 5.054622 -153.340037) (xy 4.971837 -153.388018) (xy 4.885332 -153.428915)
			(xy 4.795714 -153.462442) (xy 4.703607 -153.488364) (xy 4.609657 -153.506501) (xy 4.51452 -153.516726)
			(xy 4.418862 -153.518966) (xy 4.32335 -153.513207) (xy 4.228654 -153.499488) (xy 4.135435 -153.477907)
			(xy 4.044345 -153.448612) (xy 3.956021 -153.41181) (xy 3.87108 -153.367758) (xy 3.790116 -153.316763)
			(xy 3.713696 -153.259182) (xy 3.642353 -153.195418) (xy 3.576587 -153.125917) (xy 3.516858 -153.051165)
			(xy 3.463582 -152.971683) (xy 3.439922 -152.930098) (xy 3.416262 -152.971683) (xy 3.362987 -153.051165)
			(xy 3.303257 -153.125917) (xy 3.237492 -153.195419) (xy 3.16615 -153.259183) (xy 3.08973 -153.316763)
			(xy 3.008766 -153.367758) (xy 2.923826 -153.411811) (xy 2.835502 -153.448613) (xy 2.744412 -153.477908)
			(xy 2.651193 -153.49949) (xy 2.556497 -153.513209) (xy 2.460986 -153.518968) (xy 2.365327 -153.516728)
			(xy 2.270191 -153.506504) (xy 2.176241 -153.488367) (xy 2.084134 -153.462445) (xy 1.994515 -153.428918)
			(xy 1.908011 -153.388022) (xy 1.825226 -153.340041) (xy 1.746738 -153.285312) (xy 1.673098 -153.224217)
			(xy 1.604819 -153.157184) (xy 1.542379 -153.08468) (xy 1.486214 -153.007213) (xy 1.436718 -152.925325)
			(xy 1.394236 -152.839588) (xy 1.359066 -152.750601) (xy 1.331453 -152.658988) (xy 1.31159 -152.565387)
			(xy 1.299617 -152.470455) (xy 1.295616 -152.374854) (xy 1.27 -152.374854) (xy 1.27 -159.325056) (xy 1.295616 -159.325056)
			(xy 1.299617 -159.229455) (xy 1.31159 -159.134523) (xy 1.331453 -159.040922) (xy 1.359066 -158.949309)
			(xy 1.394236 -158.860322) (xy 1.436718 -158.774585) (xy 1.486214 -158.692697) (xy 1.542379 -158.61523)
			(xy 1.604819 -158.542726) (xy 1.673098 -158.475693) (xy 1.746738 -158.414598) (xy 1.825226 -158.359869)
			(xy 1.908011 -158.311888) (xy 1.994515 -158.270992) (xy 2.084134 -158.237465) (xy 2.176241 -158.211543)
			(xy 2.270191 -158.193406) (xy 2.365327 -158.183182) (xy 2.460986 -158.180942) (xy 2.556497 -158.186701)
			(xy 2.651193 -158.20042) (xy 2.744412 -158.222002) (xy 2.835502 -158.251297) (xy 2.923826 -158.288099)
			(xy 3.008766 -158.332152) (xy 3.08973 -158.383147) (xy 3.16615 -158.440727) (xy 3.237492 -158.504491)
			(xy 3.303257 -158.573993) (xy 3.362987 -158.648745) (xy 3.416262 -158.728227) (xy 3.439922 -158.769812)
			(xy 3.463586 -158.728229) (xy 3.516861 -158.648748) (xy 3.57659 -158.573995) (xy 3.642356 -158.504494)
			(xy 3.713698 -158.440731) (xy 3.790118 -158.38315) (xy 3.871082 -158.332156) (xy 3.956022 -158.288103)
			(xy 4.044346 -158.251301) (xy 4.135436 -158.222007) (xy 4.228655 -158.200425) (xy 4.323351 -158.186707)
			(xy 4.418862 -158.180948) (xy 4.51452 -158.183188) (xy 4.609657 -158.193413) (xy 4.703606 -158.21155)
			(xy 4.795713 -158.237472) (xy 4.885331 -158.270999) (xy 4.971835 -158.311895) (xy 5.05462 -158.359876)
			(xy 5.133107 -158.414605) (xy 5.206748 -158.475701) (xy 5.275026 -158.542734) (xy 5.337466 -158.615238)
			(xy 5.39363 -158.692705) (xy 5.443126 -158.774593) (xy 5.485607 -158.86033) (xy 5.520777 -158.949317)
			(xy 5.54839 -159.04093) (xy 5.568253 -159.13453) (xy 5.580226 -159.229463) (xy 5.584226 -159.325063)
			(xy 5.580225 -159.420664) (xy 5.568251 -159.515597) (xy 5.548389 -159.609197) (xy 5.520775 -159.70081)
			(xy 5.485605 -159.789796) (xy 5.443123 -159.875533) (xy 5.393626 -159.957421) (xy 5.337462 -160.034887)
			(xy 5.275022 -160.107391) (xy 5.206742 -160.174424) (xy 5.133102 -160.235519) (xy 5.054614 -160.290248)
			(xy 4.971829 -160.338228) (xy 4.885325 -160.379124) (xy 4.795706 -160.41265) (xy 4.7036 -160.438572)
			(xy 4.60965 -160.456708) (xy 4.514513 -160.466932) (xy 4.418855 -160.469172) (xy 4.323344 -160.463412)
			(xy 4.228648 -160.449693) (xy 4.135429 -160.428111) (xy 4.04434 -160.398816) (xy 3.956016 -160.362014)
			(xy 3.871076 -160.317961) (xy 3.790113 -160.266966) (xy 3.713693 -160.209385) (xy 3.642351 -160.145621)
			(xy 3.576586 -160.076119) (xy 3.516857 -160.001367) (xy 3.463582 -159.921885) (xy 3.439922 -159.8803)
			(xy 3.416262 -159.921885) (xy 3.362987 -160.001367) (xy 3.303257 -160.076119) (xy 3.237492 -160.145621)
			(xy 3.16615 -160.209385) (xy 3.08973 -160.266965) (xy 3.008766 -160.31796) (xy 2.923826 -160.362013)
			(xy 2.835502 -160.398815) (xy 2.744412 -160.42811) (xy 2.651193 -160.449692) (xy 2.556497 -160.463411)
			(xy 2.460986 -160.46917) (xy 2.365327 -160.46693) (xy 2.270191 -160.456706) (xy 2.176241 -160.438569)
			(xy 2.084134 -160.412647) (xy 1.994515 -160.37912) (xy 1.908011 -160.338224) (xy 1.825226 -160.290243)
			(xy 1.746738 -160.235514) (xy 1.673098 -160.174419) (xy 1.604819 -160.107386) (xy 1.542379 -160.034882)
			(xy 1.486214 -159.957415) (xy 1.436718 -159.875527) (xy 1.394236 -159.78979) (xy 1.359066 -159.700803)
			(xy 1.331453 -159.60919) (xy 1.31159 -159.515589) (xy 1.299617 -159.420657) (xy 1.295616 -159.325056)
			(xy 1.27 -159.325056) (xy 1.27 -169.167048) (xy 15.337534 -169.167048) (xy 15.341605 -169.111426)
			(xy 15.353731 -169.056989) (xy 15.373654 -169.004898) (xy 15.40095 -168.956263) (xy 15.435036 -168.91212)
			(xy 15.475185 -168.873411) (xy 15.520543 -168.84096) (xy 15.570143 -168.815459) (xy 15.622927 -168.797452)
			(xy 15.67777 -168.787322) (xy 15.733504 -168.785285) (xy 15.788941 -168.791385) (xy 15.842898 -168.805491)
			(xy 15.894227 -168.827303) (xy 15.941833 -168.856357) (xy 15.984701 -168.892032) (xy 16.021918 -168.933569)
			(xy 16.052691 -168.980082) (xy 16.076363 -169.030579) (xy 16.092431 -169.083986) (xy 16.100551 -169.139162)
			(xy 16.10106 -169.167048) (xy 16.100551 -169.194934) (xy 16.092431 -169.25011) (xy 16.076363 -169.303517)
			(xy 16.052691 -169.354014) (xy 16.021918 -169.400527) (xy 15.984701 -169.442064) (xy 15.941833 -169.477739)
			(xy 15.894227 -169.506793) (xy 15.842898 -169.528605) (xy 15.788941 -169.542711) (xy 15.733504 -169.548811)
			(xy 15.67777 -169.546774) (xy 15.622927 -169.536644) (xy 15.570143 -169.518637) (xy 15.520543 -169.493136)
			(xy 15.475185 -169.460685) (xy 15.435036 -169.421976) (xy 15.40095 -169.377833) (xy 15.373654 -169.329198)
			(xy 15.353731 -169.277107) (xy 15.341605 -169.22267) (xy 15.337534 -169.167048) (xy 1.27 -169.167048)
			(xy 1.27 -170.372532) (xy 14.663926 -170.372532) (xy 14.667997 -170.31691) (xy 14.680123 -170.262473)
			(xy 14.700046 -170.210382) (xy 14.727342 -170.161747) (xy 14.761428 -170.117604) (xy 14.801577 -170.078895)
			(xy 14.846935 -170.046444) (xy 14.896535 -170.020943) (xy 14.949319 -170.002936) (xy 15.004162 -169.992806)
			(xy 15.059896 -169.990769) (xy 15.115333 -169.996869) (xy 15.16929 -170.010975) (xy 15.220619 -170.032787)
			(xy 15.268225 -170.061841) (xy 15.311093 -170.097516) (xy 15.34831 -170.139053) (xy 15.379083 -170.185566)
			(xy 15.402755 -170.236063) (xy 15.418823 -170.28947) (xy 15.426943 -170.344646) (xy 15.427452 -170.372532)
			(xy 15.426943 -170.400418) (xy 15.418823 -170.455594) (xy 15.402755 -170.509001) (xy 15.379083 -170.559498)
			(xy 15.34831 -170.606011) (xy 15.311093 -170.647548) (xy 15.268225 -170.683223) (xy 15.220619 -170.712277)
			(xy 15.16929 -170.734089) (xy 15.115333 -170.748195) (xy 15.059896 -170.754295) (xy 15.004162 -170.752258)
			(xy 14.949319 -170.742128) (xy 14.896535 -170.724121) (xy 14.846935 -170.69862) (xy 14.801577 -170.666169)
			(xy 14.761428 -170.62746) (xy 14.727342 -170.583317) (xy 14.700046 -170.534682) (xy 14.680123 -170.482591)
			(xy 14.667997 -170.428154) (xy 14.663926 -170.372532) (xy 1.27 -170.372532) (xy 1.27 -171.533058)
			(xy 14.127478 -171.533058) (xy 14.131549 -171.477436) (xy 14.143675 -171.422999) (xy 14.163598 -171.370908)
			(xy 14.190894 -171.322273) (xy 14.22498 -171.27813) (xy 14.265129 -171.239421) (xy 14.310487 -171.20697)
			(xy 14.360087 -171.181469) (xy 14.412871 -171.163462) (xy 14.467714 -171.153332) (xy 14.523448 -171.151295)
			(xy 14.578885 -171.157395) (xy 14.632842 -171.171501) (xy 14.684171 -171.193313) (xy 14.731777 -171.222367)
			(xy 14.774645 -171.258042) (xy 14.811862 -171.299579) (xy 14.842635 -171.346092) (xy 14.866307 -171.396589)
			(xy 14.882375 -171.449996) (xy 14.890495 -171.505172) (xy 14.891004 -171.533058) (xy 14.890495 -171.560944)
			(xy 14.882375 -171.61612) (xy 14.866307 -171.669527) (xy 14.842635 -171.720024) (xy 14.811862 -171.766537)
			(xy 14.774645 -171.808074) (xy 14.731777 -171.843749) (xy 14.684171 -171.872803) (xy 14.632842 -171.894615)
			(xy 14.578885 -171.908721) (xy 14.523448 -171.914821) (xy 14.467714 -171.912784) (xy 14.412871 -171.902654)
			(xy 14.360087 -171.884647) (xy 14.310487 -171.859146) (xy 14.265129 -171.826695) (xy 14.22498 -171.787986)
			(xy 14.190894 -171.743843) (xy 14.163598 -171.695208) (xy 14.143675 -171.643117) (xy 14.131549 -171.58868)
			(xy 14.127478 -171.533058) (xy 1.27 -171.533058) (xy 1.27 -172.67174) (xy 13.456664 -172.67174) (xy 13.460735 -172.616118)
			(xy 13.472861 -172.561681) (xy 13.492784 -172.50959) (xy 13.52008 -172.460955) (xy 13.554166 -172.416812)
			(xy 13.594315 -172.378103) (xy 13.639673 -172.345652) (xy 13.689273 -172.320151) (xy 13.742057 -172.302144)
			(xy 13.7969 -172.292014) (xy 13.852634 -172.289977) (xy 13.908071 -172.296077) (xy 13.962028 -172.310183)
			(xy 14.013357 -172.331995) (xy 14.060963 -172.361049) (xy 14.103831 -172.396724) (xy 14.141048 -172.438261)
			(xy 14.171821 -172.484774) (xy 14.195493 -172.535271) (xy 14.211561 -172.588678) (xy 14.219681 -172.643854)
			(xy 14.22019 -172.67174) (xy 14.219681 -172.699626) (xy 14.211561 -172.754802) (xy 14.195493 -172.808209)
			(xy 14.171821 -172.858706) (xy 14.141048 -172.905219) (xy 14.103831 -172.946756) (xy 14.060963 -172.982431)
			(xy 14.013357 -173.011485) (xy 13.962028 -173.033297) (xy 13.908071 -173.047403) (xy 13.852634 -173.053503)
			(xy 13.7969 -173.051466) (xy 13.742057 -173.041336) (xy 13.689273 -173.023329) (xy 13.639673 -172.997828)
			(xy 13.594315 -172.965377) (xy 13.554166 -172.926668) (xy 13.52008 -172.882525) (xy 13.492784 -172.83389)
			(xy 13.472861 -172.781799) (xy 13.460735 -172.727362) (xy 13.456664 -172.67174) (xy 1.27 -172.67174)
			(xy 1.27 -176.870614) (xy 3.864362 -176.870614) (xy 3.868375 -176.7672) (xy 3.88039 -176.664407)
			(xy 3.900334 -176.562855) (xy 3.928088 -176.463153) (xy 3.963484 -176.365903) (xy 4.00631 -176.271687)
			(xy 4.056309 -176.181074) (xy 4.113179 -176.094607) (xy 4.176578 -176.012808) (xy 4.246126 -175.936167)
			(xy 4.321403 -175.865146) (xy 4.401958 -175.800173) (xy 4.487305 -175.741637) (xy 4.576932 -175.689891)
			(xy 4.6703 -175.645245) (xy 4.766846 -175.60797) (xy 4.86599 -175.578288) (xy 4.967137 -175.556378)
			(xy 5.069677 -175.542372) (xy 5.172994 -175.536355) (xy 5.276467 -175.538362) (xy 5.379473 -175.548381)
			(xy 5.481393 -175.566352) (xy 5.581614 -175.592167) (xy 5.679533 -175.625671) (xy 5.774561 -175.666663)
			(xy 5.866127 -175.714894) (xy 5.95368 -175.770077) (xy 6.036694 -175.831878) (xy 6.114668 -175.899927)
			(xy 6.187135 -175.973813) (xy 6.253659 -176.053092) (xy 6.313839 -176.137289) (xy 6.367313 -176.225895)
			(xy 6.41376 -176.318379) (xy 6.452901 -176.414185) (xy 6.4845 -176.512735) (xy 6.508367 -176.613438)
			(xy 6.524359 -176.715687) (xy 6.532378 -176.818868) (xy 6.53288 -176.870614) (xy 6.532378 -176.92236)
			(xy 6.524359 -177.025541) (xy 6.508367 -177.12779) (xy 6.4845 -177.228493) (xy 6.452901 -177.327043)
			(xy 6.41376 -177.422849) (xy 6.367313 -177.515333) (xy 6.313839 -177.603939) (xy 6.253659 -177.688136)
			(xy 6.187135 -177.767415) (xy 6.114668 -177.841301) (xy 6.036694 -177.90935) (xy 5.95368 -177.971151)
			(xy 5.866127 -178.026334) (xy 5.774561 -178.074565) (xy 5.679533 -178.115557) (xy 5.581614 -178.149061)
			(xy 5.481393 -178.174876) (xy 5.379473 -178.192847) (xy 5.276467 -178.202866) (xy 5.172994 -178.204873)
			(xy 5.069677 -178.198856) (xy 4.967137 -178.18485) (xy 4.86599 -178.16294) (xy 4.766846 -178.133258)
			(xy 4.6703 -178.095983) (xy 4.576932 -178.051337) (xy 4.487305 -177.999591) (xy 4.401958 -177.941055)
			(xy 4.321403 -177.876082) (xy 4.246126 -177.805061) (xy 4.176578 -177.72842) (xy 4.113179 -177.646621)
			(xy 4.056309 -177.560154) (xy 4.00631 -177.469541) (xy 3.963484 -177.375325) (xy 3.928088 -177.278075)
			(xy 3.900334 -177.178373) (xy 3.88039 -177.076821) (xy 3.868375 -176.974028) (xy 3.864362 -176.870614)
			(xy 1.27 -176.870614) (xy 1.27 -179.706117) (xy 3.31393 -179.706117) (xy 3.31393 -179.634795) (xy 3.321916 -179.563921)
			(xy 3.337786 -179.494386) (xy 3.361343 -179.427066) (xy 3.392288 -179.362807) (xy 3.430234 -179.302416)
			(xy 3.474703 -179.246654) (xy 3.525136 -179.196221) (xy 3.580898 -179.151752) (xy 3.641289 -179.113806)
			(xy 3.705548 -179.082861) (xy 3.772868 -179.059304) (xy 3.842403 -179.043434) (xy 3.913277 -179.035448)
			(xy 3.984599 -179.035448) (xy 4.055473 -179.043434) (xy 4.125008 -179.059304) (xy 4.192328 -179.082861)
			(xy 4.256587 -179.113806) (xy 4.316978 -179.151752) (xy 4.37274 -179.196221) (xy 4.423173 -179.246654)
			(xy 4.467642 -179.302416) (xy 4.505588 -179.362807) (xy 4.536533 -179.427066) (xy 4.56009 -179.494386)
			(xy 4.57596 -179.563921) (xy 4.583946 -179.634795) (xy 4.584446 -179.670456) (xy 4.583946 -179.706117)
			(xy 4.57596 -179.776991) (xy 4.56009 -179.846526) (xy 4.536533 -179.913846) (xy 4.505588 -179.978105)
			(xy 4.467642 -180.038496) (xy 4.423173 -180.094258) (xy 4.37274 -180.144691) (xy 4.316978 -180.18916)
			(xy 4.256587 -180.227106) (xy 4.192328 -180.258051) (xy 4.125008 -180.281608) (xy 4.055473 -180.297478)
			(xy 3.984599 -180.305464) (xy 3.913277 -180.305464) (xy 3.842403 -180.297478) (xy 3.772868 -180.281608)
			(xy 3.705548 -180.258051) (xy 3.641289 -180.227106) (xy 3.580898 -180.18916) (xy 3.525136 -180.144691)
			(xy 3.474703 -180.094258) (xy 3.430234 -180.038496) (xy 3.392288 -179.978105) (xy 3.361343 -179.913846)
			(xy 3.337786 -179.846526) (xy 3.321916 -179.776991) (xy 3.31393 -179.706117) (xy 1.27 -179.706117)
			(xy 1.27 -181.889146) (xy 1.270451 -181.911049) (xy 1.27795 -181.954207) (xy 1.292745 -181.995438)
			(xy 1.314397 -182.033517) (xy 1.342264 -182.067316) (xy 1.375518 -182.095829) (xy 1.413173 -182.118213)
			(xy 1.45411 -182.133801) (xy 1.497116 -182.142132) (xy 1.540913 -182.142957) (xy 1.584202 -182.136254)
			(xy 1.625698 -182.12222) (xy 1.645158 -182.112158) (xy 1.676623 -182.095599) (xy 1.742485 -182.068797)
			(xy 1.810926 -182.049514) (xy 1.881092 -182.037989) (xy 1.952105 -182.034368) (xy 2.023079 -182.038696)
			(xy 2.093127 -182.050918) (xy 2.161373 -182.070882) (xy 2.226964 -182.098338) (xy 2.289081 -182.132943)
			(xy 2.346948 -182.174265) (xy 2.399841 -182.221787) (xy 2.447099 -182.274916) (xy 2.488133 -182.332988)
			(xy 2.522429 -182.395276) (xy 2.549558 -182.461003) (xy 2.569182 -182.529348) (xy 2.581055 -182.599455)
			(xy 2.58503 -182.67045) (xy 2.581055 -182.741445) (xy 2.569182 -182.811552) (xy 2.549558 -182.879897)
			(xy 2.522429 -182.945624) (xy 2.488133 -183.007912) (xy 2.447099 -183.065984) (xy 2.399841 -183.119113)
			(xy 2.346948 -183.166635) (xy 2.289081 -183.207957) (xy 2.226964 -183.242562) (xy 2.161373 -183.270018)
			(xy 2.093127 -183.289982) (xy 2.023079 -183.302204) (xy 1.952105 -183.306532) (xy 1.881092 -183.302911)
			(xy 1.810926 -183.291386) (xy 1.742485 -183.272103) (xy 1.676623 -183.245301) (xy 1.645158 -183.228742)
			(xy 1.625698 -183.218703) (xy 1.584205 -183.204724) (xy 1.540931 -183.198064) (xy 1.497155 -183.19892)
			(xy 1.454174 -183.207267) (xy 1.413259 -183.222857) (xy 1.375623 -183.245229) (xy 1.342377 -183.273721)
			(xy 1.314508 -183.30749) (xy 1.292839 -183.345536) (xy 1.278012 -183.386734) (xy 1.270465 -183.429862)
			(xy 1.27 -183.451754) (xy 1.27 -183.706109) (xy 3.31393 -183.706109) (xy 3.31393 -183.634787) (xy 3.321916 -183.563913)
			(xy 3.337786 -183.494378) (xy 3.361343 -183.427058) (xy 3.392288 -183.362799) (xy 3.430234 -183.302408)
			(xy 3.474703 -183.246646) (xy 3.525136 -183.196213) (xy 3.580898 -183.151744) (xy 3.641289 -183.113798)
			(xy 3.705548 -183.082853) (xy 3.772868 -183.059296) (xy 3.842403 -183.043426) (xy 3.913277 -183.03544)
			(xy 3.984599 -183.03544) (xy 4.055473 -183.043426) (xy 4.125008 -183.059296) (xy 4.192328 -183.082853)
			(xy 4.256587 -183.113798) (xy 4.316978 -183.151744) (xy 4.37274 -183.196213) (xy 4.423173 -183.246646)
			(xy 4.467642 -183.302408) (xy 4.505588 -183.362799) (xy 4.536533 -183.427058) (xy 4.56009 -183.494378)
			(xy 4.57596 -183.563913) (xy 4.583946 -183.634787) (xy 4.584446 -183.670448) (xy 4.583946 -183.706109)
			(xy 5.813798 -183.706109) (xy 5.813798 -183.634787) (xy 5.821784 -183.563913) (xy 5.837654 -183.494378)
			(xy 5.861211 -183.427058) (xy 5.892156 -183.362799) (xy 5.930102 -183.302408) (xy 5.974571 -183.246646)
			(xy 6.025004 -183.196213) (xy 6.080766 -183.151744) (xy 6.141157 -183.113798) (xy 6.205416 -183.082853)
			(xy 6.272736 -183.059296) (xy 6.342271 -183.043426) (xy 6.413145 -183.03544) (xy 6.484467 -183.03544)
			(xy 6.555341 -183.043426) (xy 6.624876 -183.059296) (xy 6.692196 -183.082853) (xy 6.756455 -183.113798)
			(xy 6.816846 -183.151744) (xy 6.872608 -183.196213) (xy 6.923041 -183.246646) (xy 6.96751 -183.302408)
			(xy 7.005456 -183.362799) (xy 7.036401 -183.427058) (xy 7.059958 -183.494378) (xy 7.075828 -183.563913)
			(xy 7.083814 -183.634787) (xy 7.084314 -183.670448) (xy 7.083814 -183.706109) (xy 7.075828 -183.776983)
			(xy 7.059958 -183.846518) (xy 7.036401 -183.913838) (xy 7.005456 -183.978097) (xy 6.96751 -184.038488)
			(xy 6.923041 -184.09425) (xy 6.872608 -184.144683) (xy 6.816846 -184.189152) (xy 6.756455 -184.227098)
			(xy 6.692196 -184.258043) (xy 6.624876 -184.2816) (xy 6.555341 -184.29747) (xy 6.484467 -184.305456)
			(xy 6.413145 -184.305456) (xy 6.342271 -184.29747) (xy 6.272736 -184.2816) (xy 6.205416 -184.258043)
			(xy 6.141157 -184.227098) (xy 6.080766 -184.189152) (xy 6.025004 -184.144683) (xy 5.974571 -184.09425)
			(xy 5.930102 -184.038488) (xy 5.892156 -183.978097) (xy 5.861211 -183.913838) (xy 5.837654 -183.846518)
			(xy 5.821784 -183.776983) (xy 5.813798 -183.706109) (xy 4.583946 -183.706109) (xy 4.57596 -183.776983)
			(xy 4.56009 -183.846518) (xy 4.536533 -183.913838) (xy 4.505588 -183.978097) (xy 4.467642 -184.038488)
			(xy 4.423173 -184.09425) (xy 4.37274 -184.144683) (xy 4.316978 -184.189152) (xy 4.256587 -184.227098)
			(xy 4.192328 -184.258043) (xy 4.125008 -184.2816) (xy 4.055473 -184.29747) (xy 3.984599 -184.305456)
			(xy 3.913277 -184.305456) (xy 3.842403 -184.29747) (xy 3.772868 -184.2816) (xy 3.705548 -184.258043)
			(xy 3.641289 -184.227098) (xy 3.580898 -184.189152) (xy 3.525136 -184.144683) (xy 3.474703 -184.09425)
			(xy 3.430234 -184.038488) (xy 3.392288 -183.978097) (xy 3.361343 -183.913838) (xy 3.337786 -183.846518)
			(xy 3.321916 -183.776983) (xy 3.31393 -183.706109) (xy 1.27 -183.706109) (xy 1.27 -183.889142) (xy 1.27045 -183.911045)
			(xy 1.277949 -183.954204) (xy 1.292744 -183.995435) (xy 1.314396 -184.033515) (xy 1.342263 -184.067314)
			(xy 1.375517 -184.095829) (xy 1.413172 -184.118212) (xy 1.45411 -184.133801) (xy 1.497116 -184.142132)
			(xy 1.540913 -184.142957) (xy 1.584203 -184.136254) (xy 1.625699 -184.122219) (xy 1.645158 -184.112154)
			(xy 1.676623 -184.095595) (xy 1.742485 -184.068793) (xy 1.810926 -184.049509) (xy 1.881092 -184.037985)
			(xy 1.952106 -184.034363) (xy 2.02308 -184.038691) (xy 2.093128 -184.050913) (xy 2.161374 -184.070876)
			(xy 2.226966 -184.098332) (xy 2.289083 -184.132938) (xy 2.34695 -184.17426) (xy 2.399843 -184.221782)
			(xy 2.447102 -184.274911) (xy 2.488136 -184.332983) (xy 2.522431 -184.395271) (xy 2.549561 -184.460999)
			(xy 2.569185 -184.529343) (xy 2.581058 -184.599451) (xy 2.585033 -184.670446) (xy 2.583036 -184.706107)
			(xy 7.813794 -184.706107) (xy 7.813794 -184.634785) (xy 7.82178 -184.563911) (xy 7.83765 -184.494376)
			(xy 7.861207 -184.427056) (xy 7.892152 -184.362797) (xy 7.930098 -184.302406) (xy 7.974567 -184.246644)
			(xy 8.025 -184.196211) (xy 8.080762 -184.151742) (xy 8.141153 -184.113796) (xy 8.205412 -184.082851)
			(xy 8.272732 -184.059294) (xy 8.342267 -184.043424) (xy 8.413141 -184.035438) (xy 8.484463 -184.035438)
			(xy 8.555337 -184.043424) (xy 8.624872 -184.059294) (xy 8.692192 -184.082851) (xy 8.756451 -184.113796)
			(xy 8.816842 -184.151742) (xy 8.872604 -184.196211) (xy 8.923037 -184.246644) (xy 8.967506 -184.302406)
			(xy 9.005452 -184.362797) (xy 9.036397 -184.427056) (xy 9.059954 -184.494376) (xy 9.075824 -184.563911)
			(xy 9.08381 -184.634785) (xy 9.08431 -184.670446) (xy 9.08381 -184.706107) (xy 9.075824 -184.776981)
			(xy 9.059954 -184.846516) (xy 9.036397 -184.913836) (xy 9.005452 -184.978095) (xy 8.967506 -185.038486)
			(xy 8.923037 -185.094248) (xy 8.872604 -185.144681) (xy 8.816842 -185.18915) (xy 8.756451 -185.227096)
			(xy 8.692192 -185.258041) (xy 8.624872 -185.281598) (xy 8.555337 -185.297468) (xy 8.484463 -185.305454)
			(xy 8.413141 -185.305454) (xy 8.342267 -185.297468) (xy 8.272732 -185.281598) (xy 8.205412 -185.258041)
			(xy 8.141153 -185.227096) (xy 8.080762 -185.18915) (xy 8.025 -185.144681) (xy 7.974567 -185.094248)
			(xy 7.930098 -185.038486) (xy 7.892152 -184.978095) (xy 7.861207 -184.913836) (xy 7.83765 -184.846516)
			(xy 7.82178 -184.776981) (xy 7.813794 -184.706107) (xy 2.583036 -184.706107) (xy 2.581058 -184.741441)
			(xy 2.569185 -184.811549) (xy 2.549561 -184.879893) (xy 2.522431 -184.945621) (xy 2.488136 -185.007909)
			(xy 2.447102 -185.065981) (xy 2.399843 -185.11911) (xy 2.34695 -185.166632) (xy 2.289083 -185.207954)
			(xy 2.226966 -185.24256) (xy 2.161374 -185.270016) (xy 2.093128 -185.289979) (xy 2.02308 -185.302201)
			(xy 1.952106 -185.306529) (xy 1.881092 -185.302907) (xy 1.810926 -185.291383) (xy 1.742485 -185.272099)
			(xy 1.676623 -185.245297) (xy 1.645158 -185.228738) (xy 1.625698 -185.218699) (xy 1.584205 -185.20472)
			(xy 1.54093 -185.198061) (xy 1.497154 -185.198917) (xy 1.454173 -185.207263) (xy 1.413259 -185.222853)
			(xy 1.375622 -185.245226) (xy 1.342376 -185.273718) (xy 1.314506 -185.307486) (xy 1.292837 -185.345532)
			(xy 1.278009 -185.386729) (xy 1.270462 -185.429858) (xy 1.27 -185.45175) (xy 1.27 -185.706105) (xy 3.31393 -185.706105)
			(xy 3.31393 -185.634783) (xy 3.321916 -185.563909) (xy 3.337786 -185.494374) (xy 3.361343 -185.427054)
			(xy 3.392288 -185.362795) (xy 3.430234 -185.302404) (xy 3.474703 -185.246642) (xy 3.525136 -185.196209)
			(xy 3.580898 -185.15174) (xy 3.641289 -185.113794) (xy 3.705548 -185.082849) (xy 3.772868 -185.059292)
			(xy 3.842403 -185.043422) (xy 3.913277 -185.035436) (xy 3.984599 -185.035436) (xy 4.055473 -185.043422)
			(xy 4.125008 -185.059292) (xy 4.192328 -185.082849) (xy 4.256587 -185.113794) (xy 4.316978 -185.15174)
			(xy 4.37274 -185.196209) (xy 4.423173 -185.246642) (xy 4.467642 -185.302404) (xy 4.505588 -185.362795)
			(xy 4.536533 -185.427054) (xy 4.56009 -185.494374) (xy 4.57596 -185.563909) (xy 4.583946 -185.634783)
			(xy 4.584446 -185.670444) (xy 4.583946 -185.706105) (xy 5.813798 -185.706105) (xy 5.813798 -185.634783)
			(xy 5.821784 -185.563909) (xy 5.837654 -185.494374) (xy 5.861211 -185.427054) (xy 5.892156 -185.362795)
			(xy 5.930102 -185.302404) (xy 5.974571 -185.246642) (xy 6.025004 -185.196209) (xy 6.080766 -185.15174)
			(xy 6.141157 -185.113794) (xy 6.205416 -185.082849) (xy 6.272736 -185.059292) (xy 6.342271 -185.043422)
			(xy 6.413145 -185.035436) (xy 6.484467 -185.035436) (xy 6.555341 -185.043422) (xy 6.624876 -185.059292)
			(xy 6.692196 -185.082849) (xy 6.756455 -185.113794) (xy 6.816846 -185.15174) (xy 6.872608 -185.196209)
			(xy 6.923041 -185.246642) (xy 6.96751 -185.302404) (xy 7.005456 -185.362795) (xy 7.036401 -185.427054)
			(xy 7.059958 -185.494374) (xy 7.075828 -185.563909) (xy 7.083814 -185.634783) (xy 7.084314 -185.670444)
			(xy 7.083814 -185.706105) (xy 7.075828 -185.776979) (xy 7.059958 -185.846514) (xy 7.036401 -185.913834)
			(xy 7.005456 -185.978093) (xy 6.96751 -186.038484) (xy 6.923041 -186.094246) (xy 6.872608 -186.144679)
			(xy 6.816846 -186.189148) (xy 6.756455 -186.227094) (xy 6.692196 -186.258039) (xy 6.624876 -186.281596)
			(xy 6.555341 -186.297466) (xy 6.484467 -186.305452) (xy 6.413145 -186.305452) (xy 6.342271 -186.297466)
			(xy 6.272736 -186.281596) (xy 6.205416 -186.258039) (xy 6.141157 -186.227094) (xy 6.080766 -186.189148)
			(xy 6.025004 -186.144679) (xy 5.974571 -186.094246) (xy 5.930102 -186.038484) (xy 5.892156 -185.978093)
			(xy 5.861211 -185.913834) (xy 5.837654 -185.846514) (xy 5.821784 -185.776979) (xy 5.813798 -185.706105)
			(xy 4.583946 -185.706105) (xy 4.57596 -185.776979) (xy 4.56009 -185.846514) (xy 4.536533 -185.913834)
			(xy 4.505588 -185.978093) (xy 4.467642 -186.038484) (xy 4.423173 -186.094246) (xy 4.37274 -186.144679)
			(xy 4.316978 -186.189148) (xy 4.256587 -186.227094) (xy 4.192328 -186.258039) (xy 4.125008 -186.281596)
			(xy 4.055473 -186.297466) (xy 3.984599 -186.305452) (xy 3.913277 -186.305452) (xy 3.842403 -186.297466)
			(xy 3.772868 -186.281596) (xy 3.705548 -186.258039) (xy 3.641289 -186.227094) (xy 3.580898 -186.189148)
			(xy 3.525136 -186.144679) (xy 3.474703 -186.094246) (xy 3.430234 -186.038484) (xy 3.392288 -185.978093)
			(xy 3.361343 -185.913834) (xy 3.337786 -185.846514) (xy 3.321916 -185.776979) (xy 3.31393 -185.706105)
			(xy 1.27 -185.706105) (xy 1.27 -185.889138) (xy 1.270451 -185.911041) (xy 1.27795 -185.954199) (xy 1.292746 -185.995429)
			(xy 1.314398 -186.033508) (xy 1.342265 -186.067306) (xy 1.375519 -186.09582) (xy 1.413173 -186.118203)
			(xy 1.45411 -186.133791) (xy 1.497116 -186.142122) (xy 1.540912 -186.142947) (xy 1.584201 -186.136244)
			(xy 1.625697 -186.12221) (xy 1.645158 -186.11215) (xy 1.676623 -186.095591) (xy 1.742484 -186.068789)
			(xy 1.810925 -186.049506) (xy 1.881091 -186.037981) (xy 1.952104 -186.03436) (xy 2.023078 -186.038687)
			(xy 2.093126 -186.050909) (xy 2.161371 -186.070873) (xy 2.226963 -186.098329) (xy 2.289079 -186.132934)
			(xy 2.346946 -186.174256) (xy 2.399839 -186.221778) (xy 2.447098 -186.274906) (xy 2.488131 -186.332978)
			(xy 2.522427 -186.395266) (xy 2.549556 -186.460993) (xy 2.56918 -186.529337) (xy 2.581053 -186.599444)
			(xy 2.585028 -186.670439) (xy 2.583032 -186.706103) (xy 7.813794 -186.706103) (xy 7.813794 -186.634781)
			(xy 7.82178 -186.563907) (xy 7.83765 -186.494372) (xy 7.861207 -186.427052) (xy 7.892152 -186.362793)
			(xy 7.930098 -186.302402) (xy 7.974567 -186.24664) (xy 8.025 -186.196207) (xy 8.080762 -186.151738)
			(xy 8.141153 -186.113792) (xy 8.205412 -186.082847) (xy 8.272732 -186.05929) (xy 8.342267 -186.04342)
			(xy 8.413141 -186.035434) (xy 8.484463 -186.035434) (xy 8.555337 -186.04342) (xy 8.624872 -186.05929)
			(xy 8.692192 -186.082847) (xy 8.756451 -186.113792) (xy 8.816842 -186.151738) (xy 8.872604 -186.196207)
			(xy 8.923037 -186.24664) (xy 8.967506 -186.302402) (xy 9.005452 -186.362793) (xy 9.036397 -186.427052)
			(xy 9.059954 -186.494372) (xy 9.075824 -186.563907) (xy 9.08381 -186.634781) (xy 9.08431 -186.670442)
			(xy 9.08381 -186.706103) (xy 9.075824 -186.776977) (xy 9.059954 -186.846512) (xy 9.036397 -186.913832)
			(xy 9.005452 -186.978091) (xy 8.967506 -187.038482) (xy 8.923037 -187.094244) (xy 8.872604 -187.144677)
			(xy 8.816842 -187.189146) (xy 8.756451 -187.227092) (xy 8.692192 -187.258037) (xy 8.624872 -187.281594)
			(xy 8.555337 -187.297464) (xy 8.484463 -187.30545) (xy 8.413141 -187.30545) (xy 8.342267 -187.297464)
			(xy 8.272732 -187.281594) (xy 8.205412 -187.258037) (xy 8.141153 -187.227092) (xy 8.080762 -187.189146)
			(xy 8.025 -187.144677) (xy 7.974567 -187.094244) (xy 7.930098 -187.038482) (xy 7.892152 -186.978091)
			(xy 7.861207 -186.913832) (xy 7.83765 -186.846512) (xy 7.82178 -186.776977) (xy 7.813794 -186.706103)
			(xy 2.583032 -186.706103) (xy 2.581054 -186.741434) (xy 2.56918 -186.811541) (xy 2.549557 -186.879885)
			(xy 2.522428 -186.945612) (xy 2.488132 -187.007901) (xy 2.447099 -187.065972) (xy 2.39984 -187.119101)
			(xy 2.346947 -187.166623) (xy 2.289081 -187.207945) (xy 2.226964 -187.24255) (xy 2.161373 -187.270006)
			(xy 2.093127 -187.28997) (xy 2.02308 -187.302192) (xy 1.952106 -187.30652) (xy 1.881093 -187.302899)
			(xy 1.810927 -187.291375) (xy 1.742486 -187.272091) (xy 1.676625 -187.24529) (xy 1.645158 -187.228734)
			(xy 1.625698 -187.218695) (xy 1.584205 -187.204717) (xy 1.54093 -187.198057) (xy 1.497154 -187.198913)
			(xy 1.454172 -187.20726) (xy 1.413258 -187.22285) (xy 1.375621 -187.245222) (xy 1.342375 -187.273714)
			(xy 1.314505 -187.307483) (xy 1.292835 -187.345528) (xy 1.278006 -187.386725) (xy 1.270459 -187.429854)
			(xy 1.27 -187.451746) (xy 1.27 -187.706101) (xy 3.31393 -187.706101) (xy 3.31393 -187.634779) (xy 3.321916 -187.563905)
			(xy 3.337786 -187.49437) (xy 3.361343 -187.42705) (xy 3.392288 -187.362791) (xy 3.430234 -187.3024)
			(xy 3.474703 -187.246638) (xy 3.525136 -187.196205) (xy 3.580898 -187.151736) (xy 3.641289 -187.11379)
			(xy 3.705548 -187.082845) (xy 3.772868 -187.059288) (xy 3.842403 -187.043418) (xy 3.913277 -187.035432)
			(xy 3.984599 -187.035432) (xy 4.055473 -187.043418) (xy 4.125008 -187.059288) (xy 4.192328 -187.082845)
			(xy 4.256587 -187.11379) (xy 4.316978 -187.151736) (xy 4.37274 -187.196205) (xy 4.423173 -187.246638)
			(xy 4.467642 -187.3024) (xy 4.505588 -187.362791) (xy 4.536533 -187.42705) (xy 4.56009 -187.49437)
			(xy 4.57596 -187.563905) (xy 4.583946 -187.634779) (xy 4.584446 -187.67044) (xy 4.583946 -187.706101)
			(xy 5.813798 -187.706101) (xy 5.813798 -187.634779) (xy 5.821784 -187.563905) (xy 5.837654 -187.49437)
			(xy 5.861211 -187.42705) (xy 5.892156 -187.362791) (xy 5.930102 -187.3024) (xy 5.974571 -187.246638)
			(xy 6.025004 -187.196205) (xy 6.080766 -187.151736) (xy 6.141157 -187.11379) (xy 6.205416 -187.082845)
			(xy 6.272736 -187.059288) (xy 6.342271 -187.043418) (xy 6.413145 -187.035432) (xy 6.484467 -187.035432)
			(xy 6.555341 -187.043418) (xy 6.624876 -187.059288) (xy 6.692196 -187.082845) (xy 6.756455 -187.11379)
			(xy 6.816846 -187.151736) (xy 6.872608 -187.196205) (xy 6.923041 -187.246638) (xy 6.96751 -187.3024)
			(xy 7.005456 -187.362791) (xy 7.036401 -187.42705) (xy 7.059958 -187.49437) (xy 7.075828 -187.563905)
			(xy 7.083814 -187.634779) (xy 7.084314 -187.67044) (xy 7.083814 -187.706101) (xy 7.075828 -187.776975)
			(xy 7.059958 -187.84651) (xy 7.036401 -187.91383) (xy 7.005456 -187.978089) (xy 6.96751 -188.03848)
			(xy 6.923041 -188.094242) (xy 6.872608 -188.144675) (xy 6.816846 -188.189144) (xy 6.756455 -188.22709)
			(xy 6.692196 -188.258035) (xy 6.624876 -188.281592) (xy 6.555341 -188.297462) (xy 6.484467 -188.305448)
			(xy 6.413145 -188.305448) (xy 6.342271 -188.297462) (xy 6.272736 -188.281592) (xy 6.205416 -188.258035)
			(xy 6.141157 -188.22709) (xy 6.080766 -188.189144) (xy 6.025004 -188.144675) (xy 5.974571 -188.094242)
			(xy 5.930102 -188.03848) (xy 5.892156 -187.978089) (xy 5.861211 -187.91383) (xy 5.837654 -187.84651)
			(xy 5.821784 -187.776975) (xy 5.813798 -187.706101) (xy 4.583946 -187.706101) (xy 4.57596 -187.776975)
			(xy 4.56009 -187.84651) (xy 4.536533 -187.91383) (xy 4.505588 -187.978089) (xy 4.467642 -188.03848)
			(xy 4.423173 -188.094242) (xy 4.37274 -188.144675) (xy 4.316978 -188.189144) (xy 4.256587 -188.22709)
			(xy 4.192328 -188.258035) (xy 4.125008 -188.281592) (xy 4.055473 -188.297462) (xy 3.984599 -188.305448)
			(xy 3.913277 -188.305448) (xy 3.842403 -188.297462) (xy 3.772868 -188.281592) (xy 3.705548 -188.258035)
			(xy 3.641289 -188.22709) (xy 3.580898 -188.189144) (xy 3.525136 -188.144675) (xy 3.474703 -188.094242)
			(xy 3.430234 -188.03848) (xy 3.392288 -187.978089) (xy 3.361343 -187.91383) (xy 3.337786 -187.84651)
			(xy 3.321916 -187.776975) (xy 3.31393 -187.706101) (xy 1.27 -187.706101) (xy 1.27 -187.889134) (xy 1.270451 -187.911037)
			(xy 1.277949 -187.954195) (xy 1.292744 -187.995427) (xy 1.314397 -188.033506) (xy 1.342263 -188.067305)
			(xy 1.375517 -188.095819) (xy 1.413172 -188.118202) (xy 1.45411 -188.133791) (xy 1.497116 -188.142122)
			(xy 1.540913 -188.142947) (xy 1.584202 -188.136244) (xy 1.625699 -188.12221) (xy 1.645158 -188.112146)
			(xy 1.676623 -188.095587) (xy 1.742485 -188.068785) (xy 1.810926 -188.049502) (xy 1.881092 -188.037977)
			(xy 1.952106 -188.034357) (xy 2.02308 -188.038684) (xy 2.093128 -188.050906) (xy 2.161374 -188.07087)
			(xy 2.226966 -188.098327) (xy 2.289083 -188.132932) (xy 2.34695 -188.174254) (xy 2.399843 -188.221777)
			(xy 2.447101 -188.274906) (xy 2.488135 -188.332978) (xy 2.522431 -188.395266) (xy 2.54956 -188.460994)
			(xy 2.569184 -188.529338) (xy 2.581057 -188.599446) (xy 2.585031 -188.670441) (xy 2.581057 -188.741436)
			(xy 2.569183 -188.811544) (xy 2.549559 -188.879888) (xy 2.52243 -188.945615) (xy 2.488134 -189.007904)
			(xy 2.4471 -189.065976) (xy 2.399841 -189.119105) (xy 2.346948 -189.166627) (xy 2.289081 -189.207949)
			(xy 2.226964 -189.242554) (xy 2.161373 -189.27001) (xy 2.093126 -189.289974) (xy 2.023079 -189.302196)
			(xy 1.952104 -189.306523) (xy 1.88109 -189.302902) (xy 1.810924 -189.291378) (xy 1.742483 -189.272094)
			(xy 1.676622 -189.245292) (xy 1.645158 -189.22873) (xy 1.625698 -189.218691) (xy 1.584204 -189.204713)
			(xy 1.540929 -189.198054) (xy 1.497153 -189.19891) (xy 1.454172 -189.207256) (xy 1.413257 -189.222846)
			(xy 1.37562 -189.245218) (xy 1.342374 -189.27371) (xy 1.314503 -189.307479) (xy 1.292833 -189.345524)
			(xy 1.278004 -189.386721) (xy 1.270456 -189.42985) (xy 1.27 -189.451742) (xy 1.27 -189.706097) (xy 3.31393 -189.706097)
			(xy 3.31393 -189.634775) (xy 3.321916 -189.563901) (xy 3.337786 -189.494366) (xy 3.361343 -189.427046)
			(xy 3.392288 -189.362787) (xy 3.430234 -189.302396) (xy 3.474703 -189.246634) (xy 3.525136 -189.196201)
			(xy 3.580898 -189.151732) (xy 3.641289 -189.113786) (xy 3.705548 -189.082841) (xy 3.772868 -189.059284)
			(xy 3.842403 -189.043414) (xy 3.913277 -189.035428) (xy 3.984599 -189.035428) (xy 4.055473 -189.043414)
			(xy 4.125008 -189.059284) (xy 4.192328 -189.082841) (xy 4.256587 -189.113786) (xy 4.316978 -189.151732)
			(xy 4.37274 -189.196201) (xy 4.423173 -189.246634) (xy 4.467642 -189.302396) (xy 4.505588 -189.362787)
			(xy 4.536533 -189.427046) (xy 4.56009 -189.494366) (xy 4.57596 -189.563901) (xy 4.583946 -189.634775)
			(xy 4.584446 -189.670436) (xy 4.583946 -189.706097) (xy 4.57596 -189.776971) (xy 4.56009 -189.846506)
			(xy 4.536533 -189.913826) (xy 4.505588 -189.978085) (xy 4.467642 -190.038476) (xy 4.423173 -190.094238)
			(xy 4.37274 -190.144671) (xy 4.316978 -190.18914) (xy 4.256587 -190.227086) (xy 4.192328 -190.258031)
			(xy 4.125008 -190.281588) (xy 4.055473 -190.297458) (xy 3.984599 -190.305444) (xy 3.913277 -190.305444)
			(xy 3.842403 -190.297458) (xy 3.772868 -190.281588) (xy 3.705548 -190.258031) (xy 3.641289 -190.227086)
			(xy 3.580898 -190.18914) (xy 3.525136 -190.144671) (xy 3.474703 -190.094238) (xy 3.430234 -190.038476)
			(xy 3.392288 -189.978085) (xy 3.361343 -189.913826) (xy 3.337786 -189.846506) (xy 3.321916 -189.776971)
			(xy 3.31393 -189.706097) (xy 1.27 -189.706097) (xy 1.27 -189.88913) (xy 1.27045 -189.911033) (xy 1.277949 -189.954192)
			(xy 1.292743 -189.995424) (xy 1.314395 -190.033505) (xy 1.342262 -190.067304) (xy 1.375516 -190.095818)
			(xy 1.413171 -190.118202) (xy 1.45411 -190.133791) (xy 1.497116 -190.142122) (xy 1.540914 -190.142947)
			(xy 1.584204 -190.136243) (xy 1.6257 -190.122209) (xy 1.645158 -190.112142) (xy 1.676623 -190.095583)
			(xy 1.742485 -190.068781) (xy 1.810926 -190.049497) (xy 1.881092 -190.037973) (xy 1.952106 -190.034351)
			(xy 2.02308 -190.038679) (xy 2.093128 -190.050901) (xy 2.161374 -190.070864) (xy 2.226966 -190.09832)
			(xy 2.289083 -190.132926) (xy 2.34695 -190.174248) (xy 2.399843 -190.22177) (xy 2.447102 -190.274899)
			(xy 2.488136 -190.332971) (xy 2.522431 -190.395259) (xy 2.549561 -190.460987) (xy 2.569185 -190.529331)
			(xy 2.581058 -190.599439) (xy 2.585033 -190.670434) (xy 2.581058 -190.741429) (xy 2.569185 -190.811537)
			(xy 2.549561 -190.879881) (xy 2.522431 -190.945609) (xy 2.488136 -191.007897) (xy 2.447102 -191.065969)
			(xy 2.399843 -191.119098) (xy 2.34695 -191.16662) (xy 2.289083 -191.207942) (xy 2.226966 -191.242548)
			(xy 2.161374 -191.270004) (xy 2.093128 -191.289967) (xy 2.02308 -191.302189) (xy 1.952106 -191.306517)
			(xy 1.881092 -191.302895) (xy 1.810926 -191.291371) (xy 1.742485 -191.272087) (xy 1.676623 -191.245285)
			(xy 1.645158 -191.228726) (xy 1.625698 -191.218687) (xy 1.584204 -191.204709) (xy 1.540929 -191.19805)
			(xy 1.497153 -191.198906) (xy 1.454171 -191.207253) (xy 1.413256 -191.222843) (xy 1.375619 -191.245215)
			(xy 1.342372 -191.273707) (xy 1.314501 -191.307475) (xy 1.292831 -191.34552) (xy 1.278001 -191.386717)
			(xy 1.270452 -191.429846) (xy 1.27 -191.451738) (xy 1.27 -191.889126) (xy 1.270451 -191.911029) (xy 1.27795 -191.954187)
			(xy 1.292745 -191.995418) (xy 1.314397 -192.033497) (xy 1.342264 -192.067296) (xy 1.375518 -192.095809)
			(xy 1.413173 -192.118193) (xy 1.45411 -192.133781) (xy 1.497116 -192.142112) (xy 1.540913 -192.142937)
			(xy 1.584202 -192.136234) (xy 1.625698 -192.1222) (xy 1.645158 -192.112138) (xy 1.676051 -192.095868)
			(xy 1.740672 -192.069417) (xy 1.807804 -192.050208) (xy 1.876636 -192.038475) (xy 1.94634 -192.034358)
			(xy 2.016074 -192.037907) (xy 2.085 -192.049079) (xy 2.152286 -192.06774) (xy 2.21712 -192.093664)
			(xy 2.278722 -192.12654) (xy 2.336348 -192.16597) (xy 2.389305 -192.211479) (xy 2.436954 -192.26252)
			(xy 2.47872 -192.318477) (xy 2.5141 -192.378674)
		)
		(stroke
			(width 0)
			(type solid)
		)
		(fill yes)
		(layer "In2.Cu")
		(net "P12V")
	)
	(gr_poly
		(pts
			(xy 101.000052 -528.729956) (xy 101.038285 -528.729475) (xy 101.114333 -528.721487) (xy 101.189128 -528.705592)
			(xy 101.261853 -528.681966) (xy 101.331709 -528.650867) (xy 101.397931 -528.612636) (xy 101.459795 -528.567691)
			(xy 101.51662 -528.516526) (xy 101.567786 -528.459701) (xy 101.612731 -528.397838) (xy 101.650963 -528.331616)
			(xy 101.682063 -528.26176) (xy 101.70569 -528.189036) (xy 101.721586 -528.11424) (xy 101.729575 -528.038193)
			(xy 101.730048 -527.99996) (xy 101.730048 -1.999996) (xy 101.729565 -1.961765) (xy 101.721571 -1.885722)
			(xy 101.705673 -1.810931) (xy 101.682044 -1.738211) (xy 101.650942 -1.66836) (xy 101.612709 -1.602143)
			(xy 101.567764 -1.540285) (xy 101.516599 -1.483464) (xy 101.459775 -1.432303) (xy 101.397914 -1.387362)
			(xy 101.331694 -1.349134) (xy 101.26184 -1.318038) (xy 101.189119 -1.294413) (xy 101.114327 -1.27852)
			(xy 101.038283 -1.270533) (xy 101.000052 -1.27) (xy 26.510742 -1.27) (xy 26.487457 -1.269477) (xy 26.441447 -1.27665)
			(xy 26.397815 -1.292918) (xy 26.35834 -1.317619) (xy 26.34107 -1.333246) (xy 26.327262 -1.346933)
			(xy 26.303992 -1.378075) (xy 26.28629 -1.412686) (xy 26.27466 -1.449781) (xy 26.269434 -1.488304)
			(xy 26.269696 -1.507744) (xy 26.269696 -2.500122) (xy 26.2692 -2.573782) (xy 26.261353 -2.720892)
			(xy 26.245696 -2.867378) (xy 26.222275 -3.012823) (xy 26.191154 -3.156818) (xy 26.152423 -3.298956)
			(xy 26.106191 -3.438833) (xy 26.052588 -3.576054) (xy 25.991766 -3.710232) (xy 25.923897 -3.840987)
			(xy 25.849173 -3.96795) (xy 25.767805 -4.09076) (xy 25.680024 -4.209071) (xy 25.586077 -4.322548)
			(xy 25.486231 -4.430871) (xy 25.380767 -4.533732) (xy 25.269984 -4.630842) (xy 25.266625 -4.633484)
			(xy 29.519874 -4.633484) (xy 29.519874 -4.546584) (xy 29.527892 -4.460055) (xy 29.54386 -4.374635)
			(xy 29.567641 -4.291053) (xy 29.599033 -4.210021) (xy 29.637767 -4.132232) (xy 29.683514 -4.058348)
			(xy 29.735883 -3.989001) (xy 29.794427 -3.924781) (xy 29.858647 -3.866237) (xy 29.927994 -3.813868)
			(xy 30.001878 -3.768121) (xy 30.079667 -3.729387) (xy 30.160699 -3.697995) (xy 30.244281 -3.674214)
			(xy 30.329701 -3.658246) (xy 30.41623 -3.650228) (xy 30.50313 -3.650228) (xy 30.589659 -3.658246)
			(xy 30.675079 -3.674214) (xy 30.758661 -3.697995) (xy 30.839693 -3.729387) (xy 30.917482 -3.768121)
			(xy 30.991366 -3.813868) (xy 31.060713 -3.866237) (xy 31.124933 -3.924781) (xy 31.183477 -3.989001)
			(xy 31.235846 -4.058348) (xy 31.281593 -4.132232) (xy 31.320327 -4.210021) (xy 31.351719 -4.291053)
			(xy 31.3755 -4.374635) (xy 31.391468 -4.460055) (xy 31.399486 -4.546584) (xy 31.399988 -4.590034)
			(xy 31.399486 -4.633484) (xy 34.599874 -4.633484) (xy 34.599874 -4.546584) (xy 34.607892 -4.460055)
			(xy 34.62386 -4.374635) (xy 34.647641 -4.291053) (xy 34.679033 -4.210021) (xy 34.717767 -4.132232)
			(xy 34.763514 -4.058348) (xy 34.815883 -3.989001) (xy 34.874427 -3.924781) (xy 34.938647 -3.866237)
			(xy 35.007994 -3.813868) (xy 35.081878 -3.768121) (xy 35.159667 -3.729387) (xy 35.240699 -3.697995)
			(xy 35.324281 -3.674214) (xy 35.409701 -3.658246) (xy 35.49623 -3.650228) (xy 35.58313 -3.650228)
			(xy 35.669659 -3.658246) (xy 35.755079 -3.674214) (xy 35.838661 -3.697995) (xy 35.919693 -3.729387)
			(xy 35.997482 -3.768121) (xy 36.071366 -3.813868) (xy 36.140713 -3.866237) (xy 36.204933 -3.924781)
			(xy 36.263477 -3.989001) (xy 36.315846 -4.058348) (xy 36.361593 -4.132232) (xy 36.400327 -4.210021)
			(xy 36.431719 -4.291053) (xy 36.4555 -4.374635) (xy 36.471468 -4.460055) (xy 36.479486 -4.546584)
			(xy 36.479988 -4.590034) (xy 36.479486 -4.633484) (xy 36.471468 -4.720013) (xy 36.4555 -4.805433)
			(xy 36.431719 -4.889015) (xy 36.400327 -4.970047) (xy 36.361593 -5.047836) (xy 36.315846 -5.12172)
			(xy 36.263477 -5.191067) (xy 36.204933 -5.255287) (xy 36.140713 -5.313831) (xy 36.071366 -5.3662)
			(xy 35.997482 -5.411947) (xy 35.919693 -5.450681) (xy 35.838661 -5.482073) (xy 35.755079 -5.505854)
			(xy 35.669659 -5.521822) (xy 35.58313 -5.52984) (xy 35.49623 -5.52984) (xy 35.409701 -5.521822) (xy 35.324281 -5.505854)
			(xy 35.240699 -5.482073) (xy 35.159667 -5.450681) (xy 35.081878 -5.411947) (xy 35.007994 -5.3662)
			(xy 34.938647 -5.313831) (xy 34.874427 -5.255287) (xy 34.815883 -5.191067) (xy 34.763514 -5.12172)
			(xy 34.717767 -5.047836) (xy 34.679033 -4.970047) (xy 34.647641 -4.889015) (xy 34.62386 -4.805433)
			(xy 34.607892 -4.720013) (xy 34.599874 -4.633484) (xy 31.399486 -4.633484) (xy 31.391468 -4.720013)
			(xy 31.3755 -4.805433) (xy 31.351719 -4.889015) (xy 31.320327 -4.970047) (xy 31.281593 -5.047836)
			(xy 31.235846 -5.12172) (xy 31.183477 -5.191067) (xy 31.124933 -5.255287) (xy 31.060713 -5.313831)
			(xy 30.991366 -5.3662) (xy 30.917482 -5.411947) (xy 30.839693 -5.450681) (xy 30.758661 -5.482073)
			(xy 30.675079 -5.505854) (xy 30.589659 -5.521822) (xy 30.50313 -5.52984) (xy 30.41623 -5.52984) (xy 30.329701 -5.521822)
			(xy 30.244281 -5.505854) (xy 30.160699 -5.482073) (xy 30.079667 -5.450681) (xy 30.001878 -5.411947)
			(xy 29.927994 -5.3662) (xy 29.858647 -5.313831) (xy 29.794427 -5.255287) (xy 29.735883 -5.191067)
			(xy 29.683514 -5.12172) (xy 29.637767 -5.047836) (xy 29.599033 -4.970047) (xy 29.567641 -4.889015)
			(xy 29.54386 -4.805433) (xy 29.527892 -4.720013) (xy 29.519874 -4.633484) (xy 25.266625 -4.633484)
			(xy 25.154196 -4.721925) (xy 25.033729 -4.806724) (xy 24.908925 -4.884999) (xy 24.780136 -4.956528)
			(xy 24.647727 -5.02111) (xy 24.580088 -5.050282) (xy 24.508304 -5.080096) (xy 24.36198 -5.132588)
			(xy 24.212942 -5.176791) (xy 24.06166 -5.212568) (xy 23.908611 -5.239805) (xy 23.754274 -5.258417)
			(xy 23.599137 -5.268345) (xy 23.521416 -5.269484) (xy 23.521416 -5.269992) (xy 12.834366 -5.269992)
			(xy 12.812362 -5.270455) (xy 12.769012 -5.278028) (xy 12.727615 -5.292958) (xy 12.689411 -5.3148)
			(xy 12.655542 -5.342899) (xy 12.627023 -5.376414) (xy 12.604707 -5.414343) (xy 12.589261 -5.45555)
			(xy 12.581148 -5.498803) (xy 12.580611 -5.542807) (xy 12.587665 -5.586245) (xy 12.6021 -5.627817)
			(xy 12.623483 -5.66628) (xy 12.651175 -5.700482) (xy 12.667488 -5.715254) (xy 12.697377 -5.741926)
			(xy 12.713738 -5.759241) (xy 26.627809 -5.759241) (xy 26.628405 -5.703251) (xy 26.637179 -5.647949)
			(xy 26.653941 -5.594524) (xy 26.678333 -5.544123) (xy 26.70983 -5.497828) (xy 26.747755 -5.456634)
			(xy 26.791295 -5.421427) (xy 26.839513 -5.392961) (xy 26.891373 -5.37185) (xy 26.945763 -5.358545)
			(xy 27.001514 -5.353334) (xy 27.057427 -5.356327) (xy 27.112302 -5.367462) (xy 27.16496 -5.386497)
			(xy 27.21427 -5.413026) (xy 27.259174 -5.446477) (xy 27.298705 -5.486132) (xy 27.332015 -5.531139)
			(xy 27.358389 -5.580532) (xy 27.37726 -5.63325) (xy 27.388222 -5.68816) (xy 27.391041 -5.744082)
			(xy 27.385655 -5.799816) (xy 27.37218 -5.854164) (xy 27.350906 -5.905958) (xy 27.32229 -5.954087)
			(xy 27.305 -5.976112) (xy 27.29176 -5.993153) (xy 27.270581 -6.030748) (xy 27.256064 -6.071382) (xy 27.248627 -6.113885)
			(xy 27.248484 -6.157035) (xy 27.255639 -6.199587) (xy 27.269886 -6.240316) (xy 27.290815 -6.27805)
			(xy 27.317824 -6.311702) (xy 27.350134 -6.340302) (xy 27.368246 -6.352032) (xy 27.391817 -6.367153)
			(xy 27.43461 -6.403277) (xy 27.471662 -6.445268) (xy 27.502178 -6.492225) (xy 27.525504 -6.543137)
			(xy 27.541136 -6.596913) (xy 27.548741 -6.652395) (xy 27.548154 -6.708394) (xy 27.539388 -6.763705)
			(xy 27.522631 -6.81714) (xy 27.498244 -6.867553) (xy 27.46675 -6.913859) (xy 27.428825 -6.955065)
			(xy 27.385285 -6.990284) (xy 27.337065 -7.018761) (xy 27.2852 -7.039884) (xy 27.230804 -7.053198)
			(xy 27.175047 -7.058419) (xy 27.119125 -7.055434) (xy 27.06424 -7.044306) (xy 27.011571 -7.025276)
			(xy 26.96225 -6.998752) (xy 26.917335 -6.965303) (xy 26.877792 -6.925648) (xy 26.84447 -6.880639)
			(xy 26.818085 -6.831243) (xy 26.799204 -6.77852) (xy 26.788231 -6.723604) (xy 26.785404 -6.667674)
			(xy 26.790782 -6.611932) (xy 26.804251 -6.557574) (xy 26.82552 -6.505769) (xy 26.854133 -6.457629)
			(xy 26.871422 -6.435598) (xy 26.884645 -6.418545) (xy 26.905823 -6.380952) (xy 26.920339 -6.34032)
			(xy 26.927776 -6.297819) (xy 26.92792 -6.254672) (xy 26.920767 -6.212122) (xy 26.906522 -6.171395)
			(xy 26.885596 -6.133662) (xy 26.858592 -6.10001) (xy 26.826286 -6.071409) (xy 26.808176 -6.059678)
			(xy 26.784665 -6.044468) (xy 26.741885 -6.008342) (xy 26.704844 -5.96635) (xy 26.67434 -5.919396)
			(xy 26.651026 -5.868487) (xy 26.635404 -5.814717) (xy 26.627809 -5.759241) (xy 12.713738 -5.759241)
			(xy 12.752398 -5.800157) (xy 12.801522 -5.863441) (xy 12.844288 -5.931183) (xy 12.880296 -6.002748)
			(xy 12.909205 -6.077463) (xy 12.930744 -6.154626) (xy 12.944712 -6.233512) (xy 12.950977 -6.31338)
			(xy 12.949479 -6.393479) (xy 12.940234 -6.473056) (xy 12.923328 -6.551365) (xy 12.898919 -6.627669)
			(xy 12.867238 -6.701251) (xy 12.828582 -6.771421) (xy 12.783313 -6.837518) (xy 12.731858 -6.898922)
			(xy 12.674699 -6.955055) (xy 12.612375 -7.005391) (xy 12.54547 -7.049457) (xy 12.510262 -7.068566)
			(xy 12.495273 -7.077129) (xy 12.470181 -7.100817) (xy 12.452337 -7.130351) (xy 12.443041 -7.163582)
			(xy 12.442698 -7.173484) (xy 29.519874 -7.173484) (xy 29.519874 -7.086584) (xy 29.527892 -7.000055)
			(xy 29.54386 -6.914635) (xy 29.567641 -6.831053) (xy 29.599033 -6.750021) (xy 29.637767 -6.672232)
			(xy 29.683514 -6.598348) (xy 29.735883 -6.529001) (xy 29.794427 -6.464781) (xy 29.858647 -6.406237)
			(xy 29.927994 -6.353868) (xy 30.001878 -6.308121) (xy 30.079667 -6.269387) (xy 30.160699 -6.237995)
			(xy 30.244281 -6.214214) (xy 30.329701 -6.198246) (xy 30.41623 -6.190228) (xy 30.50313 -6.190228)
			(xy 30.589659 -6.198246) (xy 30.675079 -6.214214) (xy 30.758661 -6.237995) (xy 30.839693 -6.269387)
			(xy 30.917482 -6.308121) (xy 30.991366 -6.353868) (xy 31.060713 -6.406237) (xy 31.124933 -6.464781)
			(xy 31.183477 -6.529001) (xy 31.235846 -6.598348) (xy 31.281593 -6.672232) (xy 31.320327 -6.750021)
			(xy 31.351719 -6.831053) (xy 31.3755 -6.914635) (xy 31.391468 -7.000055) (xy 31.399486 -7.086584)
			(xy 31.399988 -7.130034) (xy 31.399486 -7.173484) (xy 34.599874 -7.173484) (xy 34.599874 -7.086584)
			(xy 34.607892 -7.000055) (xy 34.62386 -6.914635) (xy 34.647641 -6.831053) (xy 34.679033 -6.750021)
			(xy 34.717767 -6.672232) (xy 34.763514 -6.598348) (xy 34.815883 -6.529001) (xy 34.874427 -6.464781)
			(xy 34.938647 -6.406237) (xy 35.007994 -6.353868) (xy 35.081878 -6.308121) (xy 35.159667 -6.269387)
			(xy 35.240699 -6.237995) (xy 35.324281 -6.214214) (xy 35.409701 -6.198246) (xy 35.49623 -6.190228)
			(xy 35.58313 -6.190228) (xy 35.669659 -6.198246) (xy 35.755079 -6.214214) (xy 35.838661 -6.237995)
			(xy 35.919693 -6.269387) (xy 35.997482 -6.308121) (xy 36.071366 -6.353868) (xy 36.140713 -6.406237)
			(xy 36.204933 -6.464781) (xy 36.263477 -6.529001) (xy 36.315846 -6.598348) (xy 36.361593 -6.672232)
			(xy 36.400327 -6.750021) (xy 36.431719 -6.831053) (xy 36.454201 -6.91007) (xy 39.818063 -6.91007)
			(xy 39.82207 -6.794046) (xy 39.834072 -6.678574) (xy 39.854012 -6.564206) (xy 39.881795 -6.451486)
			(xy 39.917289 -6.340952) (xy 39.960324 -6.233129) (xy 40.010695 -6.128532) (xy 40.068162 -6.02766)
			(xy 40.132452 -5.930993) (xy 40.203257 -5.838992) (xy 40.280241 -5.752095) (xy 40.363037 -5.670716)
			(xy 40.45125 -5.595243) (xy 40.54446 -5.526036) (xy 40.642223 -5.463424) (xy 40.744072 -5.407707)
			(xy 40.849522 -5.359149) (xy 40.958071 -5.317981) (xy 41.069202 -5.284401) (xy 41.182385 -5.258568)
			(xy 41.29708 -5.240605) (xy 41.412742 -5.230597) (xy 41.528818 -5.228594) (xy 41.644756 -5.234603)
			(xy 41.760003 -5.248596) (xy 41.874009 -5.270507) (xy 41.986233 -5.300232) (xy 42.096139 -5.337628)
			(xy 42.203202 -5.382517) (xy 42.306914 -5.434686) (xy 42.406779 -5.493886) (xy 42.502322 -5.559835)
			(xy 42.502604 -5.56006) (xy 43.327577 -5.56006) (xy 43.331612 -5.484356) (xy 43.343671 -5.409511)
			(xy 43.363617 -5.33637) (xy 43.391224 -5.265765) (xy 43.42618 -5.198494) (xy 43.468088 -5.135319)
			(xy 43.516474 -5.076957) (xy 43.57079 -5.024069) (xy 43.630419 -4.977254) (xy 43.694687 -4.937042)
			(xy 43.762864 -4.90389) (xy 43.83418 -4.878172) (xy 43.907825 -4.86018) (xy 43.982965 -4.850118)
			(xy 44.058749 -4.848099) (xy 44.134319 -4.854148) (xy 44.208817 -4.868195) (xy 44.2814 -4.890081)
			(xy 44.351246 -4.919558) (xy 44.417563 -4.956293) (xy 44.479599 -4.999868) (xy 44.536652 -5.04979)
			(xy 44.588076 -5.105494) (xy 44.633287 -5.166349) (xy 44.671774 -5.231664) (xy 44.7031 -5.3007) (xy 44.72691 -5.372675)
			(xy 44.742935 -5.446773) (xy 44.750994 -5.522154) (xy 44.751498 -5.56006) (xy 45.867577 -5.56006)
			(xy 45.871612 -5.484356) (xy 45.883671 -5.409511) (xy 45.903617 -5.33637) (xy 45.931224 -5.265765)
			(xy 45.96618 -5.198494) (xy 46.008088 -5.135319) (xy 46.056474 -5.076957) (xy 46.11079 -5.024069)
			(xy 46.170419 -4.977254) (xy 46.234687 -4.937042) (xy 46.302864 -4.90389) (xy 46.37418 -4.878172)
			(xy 46.447825 -4.86018) (xy 46.522965 -4.850118) (xy 46.598749 -4.848099) (xy 46.674319 -4.854148)
			(xy 46.748817 -4.868195) (xy 46.8214 -4.890081) (xy 46.891246 -4.919558) (xy 46.957563 -4.956293)
			(xy 47.019599 -4.999868) (xy 47.076652 -5.04979) (xy 47.128076 -5.105494) (xy 47.173287 -5.166349)
			(xy 47.211774 -5.231664) (xy 47.2431 -5.3007) (xy 47.26691 -5.372675) (xy 47.282935 -5.446773) (xy 47.290994 -5.522154)
			(xy 47.291498 -5.56006) (xy 48.407577 -5.56006) (xy 48.411612 -5.484356) (xy 48.423671 -5.409511)
			(xy 48.443617 -5.33637) (xy 48.471224 -5.265765) (xy 48.50618 -5.198494) (xy 48.548088 -5.135319)
			(xy 48.596474 -5.076957) (xy 48.65079 -5.024069) (xy 48.710419 -4.977254) (xy 48.774687 -4.937042)
			(xy 48.842864 -4.90389) (xy 48.91418 -4.878172) (xy 48.987825 -4.86018) (xy 49.062965 -4.850118)
			(xy 49.138749 -4.848099) (xy 49.214319 -4.854148) (xy 49.288817 -4.868195) (xy 49.3614 -4.890081)
			(xy 49.431246 -4.919558) (xy 49.497563 -4.956293) (xy 49.559599 -4.999868) (xy 49.616652 -5.04979)
			(xy 49.668076 -5.105494) (xy 49.713287 -5.166349) (xy 49.751774 -5.231664) (xy 49.7831 -5.3007) (xy 49.80691 -5.372675)
			(xy 49.822935 -5.446773) (xy 49.830994 -5.522154) (xy 49.831498 -5.56006) (xy 50.947577 -5.56006)
			(xy 50.951612 -5.484356) (xy 50.963671 -5.409511) (xy 50.983617 -5.33637) (xy 51.011224 -5.265765)
			(xy 51.04618 -5.198494) (xy 51.088088 -5.135319) (xy 51.136474 -5.076957) (xy 51.19079 -5.024069)
			(xy 51.250419 -4.977254) (xy 51.314687 -4.937042) (xy 51.382864 -4.90389) (xy 51.45418 -4.878172)
			(xy 51.527825 -4.86018) (xy 51.602965 -4.850118) (xy 51.678749 -4.848099) (xy 51.754319 -4.854148)
			(xy 51.828817 -4.868195) (xy 51.9014 -4.890081) (xy 51.971246 -4.919558) (xy 52.037563 -4.956293)
			(xy 52.099599 -4.999868) (xy 52.156652 -5.04979) (xy 52.208076 -5.105494) (xy 52.253287 -5.166349)
			(xy 52.291774 -5.231664) (xy 52.3231 -5.3007) (xy 52.34691 -5.372675) (xy 52.362935 -5.446773) (xy 52.370994 -5.522154)
			(xy 52.371498 -5.56006) (xy 53.487577 -5.56006) (xy 53.491612 -5.484356) (xy 53.503671 -5.409511)
			(xy 53.523617 -5.33637) (xy 53.551224 -5.265765) (xy 53.58618 -5.198494) (xy 53.628088 -5.135319)
			(xy 53.676474 -5.076957) (xy 53.73079 -5.024069) (xy 53.790419 -4.977254) (xy 53.854687 -4.937042)
			(xy 53.922864 -4.90389) (xy 53.99418 -4.878172) (xy 54.067825 -4.86018) (xy 54.142965 -4.850118)
			(xy 54.218749 -4.848099) (xy 54.294319 -4.854148) (xy 54.368817 -4.868195) (xy 54.4414 -4.890081)
			(xy 54.511246 -4.919558) (xy 54.577563 -4.956293) (xy 54.639599 -4.999868) (xy 54.696652 -5.04979)
			(xy 54.748076 -5.105494) (xy 54.793287 -5.166349) (xy 54.831774 -5.231664) (xy 54.8631 -5.3007) (xy 54.88691 -5.372675)
			(xy 54.902935 -5.446773) (xy 54.910994 -5.522154) (xy 54.911498 -5.56006) (xy 56.027577 -5.56006)
			(xy 56.031612 -5.484356) (xy 56.043671 -5.409511) (xy 56.063617 -5.33637) (xy 56.091224 -5.265765)
			(xy 56.12618 -5.198494) (xy 56.168088 -5.135319) (xy 56.216474 -5.076957) (xy 56.27079 -5.024069)
			(xy 56.330419 -4.977254) (xy 56.394687 -4.937042) (xy 56.462864 -4.90389) (xy 56.53418 -4.878172)
			(xy 56.607825 -4.86018) (xy 56.682965 -4.850118) (xy 56.758749 -4.848099) (xy 56.834319 -4.854148)
			(xy 56.908817 -4.868195) (xy 56.9814 -4.890081) (xy 57.051246 -4.919558) (xy 57.117563 -4.956293)
			(xy 57.179599 -4.999868) (xy 57.236652 -5.04979) (xy 57.288076 -5.105494) (xy 57.333287 -5.166349)
			(xy 57.371774 -5.231664) (xy 57.4031 -5.3007) (xy 57.42691 -5.372675) (xy 57.442935 -5.446773) (xy 57.450994 -5.522154)
			(xy 57.451498 -5.56006) (xy 58.567577 -5.56006) (xy 58.571612 -5.484356) (xy 58.583671 -5.409511)
			(xy 58.603617 -5.33637) (xy 58.631224 -5.265765) (xy 58.66618 -5.198494) (xy 58.708088 -5.135319)
			(xy 58.756474 -5.076957) (xy 58.81079 -5.024069) (xy 58.870419 -4.977254) (xy 58.934687 -4.937042)
			(xy 59.002864 -4.90389) (xy 59.07418 -4.878172) (xy 59.147825 -4.86018) (xy 59.222965 -4.850118)
			(xy 59.298749 -4.848099) (xy 59.374319 -4.854148) (xy 59.448817 -4.868195) (xy 59.5214 -4.890081)
			(xy 59.591246 -4.919558) (xy 59.657563 -4.956293) (xy 59.719599 -4.999868) (xy 59.776652 -5.04979)
			(xy 59.828076 -5.105494) (xy 59.873287 -5.166349) (xy 59.911774 -5.231664) (xy 59.9431 -5.3007) (xy 59.96691 -5.372675)
			(xy 59.982935 -5.446773) (xy 59.990994 -5.522154) (xy 59.991498 -5.56006) (xy 61.107577 -5.56006)
			(xy 61.111612 -5.484356) (xy 61.123671 -5.409511) (xy 61.143617 -5.33637) (xy 61.171224 -5.265765)
			(xy 61.20618 -5.198494) (xy 61.248088 -5.135319) (xy 61.296474 -5.076957) (xy 61.35079 -5.024069)
			(xy 61.410419 -4.977254) (xy 61.474687 -4.937042) (xy 61.542864 -4.90389) (xy 61.61418 -4.878172)
			(xy 61.687825 -4.86018) (xy 61.762965 -4.850118) (xy 61.838749 -4.848099) (xy 61.914319 -4.854148)
			(xy 61.988817 -4.868195) (xy 62.0614 -4.890081) (xy 62.131246 -4.919558) (xy 62.197563 -4.956293)
			(xy 62.259599 -4.999868) (xy 62.316652 -5.04979) (xy 62.368076 -5.105494) (xy 62.413287 -5.166349)
			(xy 62.451774 -5.231664) (xy 62.4831 -5.3007) (xy 62.50691 -5.372675) (xy 62.522935 -5.446773) (xy 62.530994 -5.522154)
			(xy 62.531498 -5.56006) (xy 62.530994 -5.597966) (xy 62.522935 -5.673347) (xy 62.50691 -5.747445)
			(xy 62.4831 -5.81942) (xy 62.451774 -5.888456) (xy 62.413287 -5.953771) (xy 62.368076 -6.014626)
			(xy 62.316652 -6.07033) (xy 62.259599 -6.120252) (xy 62.197563 -6.163827) (xy 62.131246 -6.200562)
			(xy 62.0614 -6.230039) (xy 61.988817 -6.251925) (xy 61.914319 -6.265972) (xy 61.838749 -6.272021)
			(xy 61.762965 -6.270002) (xy 61.687825 -6.25994) (xy 61.61418 -6.241948) (xy 61.542864 -6.21623)
			(xy 61.474687 -6.183078) (xy 61.410419 -6.142866) (xy 61.35079 -6.096051) (xy 61.296474 -6.043163)
			(xy 61.248088 -5.984801) (xy 61.20618 -5.921626) (xy 61.171224 -5.854355) (xy 61.143617 -5.78375)
			(xy 61.123671 -5.710609) (xy 61.111612 -5.635764) (xy 61.107577 -5.56006) (xy 59.991498 -5.56006)
			(xy 59.990994 -5.597966) (xy 59.982935 -5.673347) (xy 59.96691 -5.747445) (xy 59.9431 -5.81942) (xy 59.911774 -5.888456)
			(xy 59.873287 -5.953771) (xy 59.828076 -6.014626) (xy 59.776652 -6.07033) (xy 59.719599 -6.120252)
			(xy 59.657563 -6.163827) (xy 59.591246 -6.200562) (xy 59.5214 -6.230039) (xy 59.448817 -6.251925)
			(xy 59.374319 -6.265972) (xy 59.298749 -6.272021) (xy 59.222965 -6.270002) (xy 59.147825 -6.25994)
			(xy 59.07418 -6.241948) (xy 59.002864 -6.21623) (xy 58.934687 -6.183078) (xy 58.870419 -6.142866)
			(xy 58.81079 -6.096051) (xy 58.756474 -6.043163) (xy 58.708088 -5.984801) (xy 58.66618 -5.921626)
			(xy 58.631224 -5.854355) (xy 58.603617 -5.78375) (xy 58.583671 -5.710609) (xy 58.571612 -5.635764)
			(xy 58.567577 -5.56006) (xy 57.451498 -5.56006) (xy 57.450994 -5.597966) (xy 57.442935 -5.673347)
			(xy 57.42691 -5.747445) (xy 57.4031 -5.81942) (xy 57.371774 -5.888456) (xy 57.333287 -5.953771) (xy 57.288076 -6.014626)
			(xy 57.236652 -6.07033) (xy 57.179599 -6.120252) (xy 57.117563 -6.163827) (xy 57.051246 -6.200562)
			(xy 56.9814 -6.230039) (xy 56.908817 -6.251925) (xy 56.834319 -6.265972) (xy 56.758749 -6.272021)
			(xy 56.682965 -6.270002) (xy 56.607825 -6.25994) (xy 56.53418 -6.241948) (xy 56.462864 -6.21623)
			(xy 56.394687 -6.183078) (xy 56.330419 -6.142866) (xy 56.27079 -6.096051) (xy 56.216474 -6.043163)
			(xy 56.168088 -5.984801) (xy 56.12618 -5.921626) (xy 56.091224 -5.854355) (xy 56.063617 -5.78375)
			(xy 56.043671 -5.710609) (xy 56.031612 -5.635764) (xy 56.027577 -5.56006) (xy 54.911498 -5.56006)
			(xy 54.910994 -5.597966) (xy 54.902935 -5.673347) (xy 54.88691 -5.747445) (xy 54.8631 -5.81942) (xy 54.831774 -5.888456)
			(xy 54.793287 -5.953771) (xy 54.748076 -6.014626) (xy 54.696652 -6.07033) (xy 54.639599 -6.120252)
			(xy 54.577563 -6.163827) (xy 54.511246 -6.200562) (xy 54.4414 -6.230039) (xy 54.368817 -6.251925)
			(xy 54.294319 -6.265972) (xy 54.218749 -6.272021) (xy 54.142965 -6.270002) (xy 54.067825 -6.25994)
			(xy 53.99418 -6.241948) (xy 53.922864 -6.21623) (xy 53.854687 -6.183078) (xy 53.790419 -6.142866)
			(xy 53.73079 -6.096051) (xy 53.676474 -6.043163) (xy 53.628088 -5.984801) (xy 53.58618 -5.921626)
			(xy 53.551224 -5.854355) (xy 53.523617 -5.78375) (xy 53.503671 -5.710609) (xy 53.491612 -5.635764)
			(xy 53.487577 -5.56006) (xy 52.371498 -5.56006) (xy 52.370994 -5.597966) (xy 52.362935 -5.673347)
			(xy 52.34691 -5.747445) (xy 52.3231 -5.81942) (xy 52.291774 -5.888456) (xy 52.253287 -5.953771) (xy 52.208076 -6.014626)
			(xy 52.156652 -6.07033) (xy 52.099599 -6.120252) (xy 52.037563 -6.163827) (xy 51.971246 -6.200562)
			(xy 51.9014 -6.230039) (xy 51.828817 -6.251925) (xy 51.754319 -6.265972) (xy 51.678749 -6.272021)
			(xy 51.602965 -6.270002) (xy 51.527825 -6.25994) (xy 51.45418 -6.241948) (xy 51.382864 -6.21623)
			(xy 51.314687 -6.183078) (xy 51.250419 -6.142866) (xy 51.19079 -6.096051) (xy 51.136474 -6.043163)
			(xy 51.088088 -5.984801) (xy 51.04618 -5.921626) (xy 51.011224 -5.854355) (xy 50.983617 -5.78375)
			(xy 50.963671 -5.710609) (xy 50.951612 -5.635764) (xy 50.947577 -5.56006) (xy 49.831498 -5.56006)
			(xy 49.830994 -5.597966) (xy 49.822935 -5.673347) (xy 49.80691 -5.747445) (xy 49.7831 -5.81942) (xy 49.751774 -5.888456)
			(xy 49.713287 -5.953771) (xy 49.668076 -6.014626) (xy 49.616652 -6.07033) (xy 49.559599 -6.120252)
			(xy 49.497563 -6.163827) (xy 49.431246 -6.200562) (xy 49.3614 -6.230039) (xy 49.288817 -6.251925)
			(xy 49.214319 -6.265972) (xy 49.138749 -6.272021) (xy 49.062965 -6.270002) (xy 48.987825 -6.25994)
			(xy 48.91418 -6.241948) (xy 48.842864 -6.21623) (xy 48.774687 -6.183078) (xy 48.710419 -6.142866)
			(xy 48.65079 -6.096051) (xy 48.596474 -6.043163) (xy 48.548088 -5.984801) (xy 48.50618 -5.921626)
			(xy 48.471224 -5.854355) (xy 48.443617 -5.78375) (xy 48.423671 -5.710609) (xy 48.411612 -5.635764)
			(xy 48.407577 -5.56006) (xy 47.291498 -5.56006) (xy 47.290994 -5.597966) (xy 47.282935 -5.673347)
			(xy 47.26691 -5.747445) (xy 47.2431 -5.81942) (xy 47.211774 -5.888456) (xy 47.173287 -5.953771) (xy 47.128076 -6.014626)
			(xy 47.076652 -6.07033) (xy 47.019599 -6.120252) (xy 46.957563 -6.163827) (xy 46.891246 -6.200562)
			(xy 46.8214 -6.230039) (xy 46.748817 -6.251925) (xy 46.674319 -6.265972) (xy 46.598749 -6.272021)
			(xy 46.522965 -6.270002) (xy 46.447825 -6.25994) (xy 46.37418 -6.241948) (xy 46.302864 -6.21623)
			(xy 46.234687 -6.183078) (xy 46.170419 -6.142866) (xy 46.11079 -6.096051) (xy 46.056474 -6.043163)
			(xy 46.008088 -5.984801) (xy 45.96618 -5.921626) (xy 45.931224 -5.854355) (xy 45.903617 -5.78375)
			(xy 45.883671 -5.710609) (xy 45.871612 -5.635764) (xy 45.867577 -5.56006) (xy 44.751498 -5.56006)
			(xy 44.750994 -5.597966) (xy 44.742935 -5.673347) (xy 44.72691 -5.747445) (xy 44.7031 -5.81942) (xy 44.671774 -5.888456)
			(xy 44.633287 -5.953771) (xy 44.588076 -6.014626) (xy 44.536652 -6.07033) (xy 44.479599 -6.120252)
			(xy 44.417563 -6.163827) (xy 44.351246 -6.200562) (xy 44.2814 -6.230039) (xy 44.208817 -6.251925)
			(xy 44.134319 -6.265972) (xy 44.058749 -6.272021) (xy 43.982965 -6.270002) (xy 43.907825 -6.25994)
			(xy 43.83418 -6.241948) (xy 43.762864 -6.21623) (xy 43.694687 -6.183078) (xy 43.630419 -6.142866)
			(xy 43.57079 -6.096051) (xy 43.516474 -6.043163) (xy 43.468088 -5.984801) (xy 43.42618 -5.921626)
			(xy 43.391224 -5.854355) (xy 43.363617 -5.78375) (xy 43.343671 -5.710609) (xy 43.331612 -5.635764)
			(xy 43.327577 -5.56006) (xy 42.502604 -5.56006) (xy 42.593088 -5.632218) (xy 42.678643 -5.710691)
			(xy 42.758581 -5.794879) (xy 42.83252 -5.884381) (xy 42.900108 -5.978772) (xy 42.961022 -6.0776)
			(xy 43.014974 -6.180396) (xy 43.061704 -6.286669) (xy 43.100992 -6.395913) (xy 43.132649 -6.507606)
			(xy 43.156525 -6.621218) (xy 43.172506 -6.736206) (xy 43.180515 -6.852023) (xy 43.181016 -6.91007)
			(xy 43.180515 -6.968117) (xy 43.172506 -7.083934) (xy 43.156525 -7.198922) (xy 43.132649 -7.312534)
			(xy 43.100992 -7.424227) (xy 43.061704 -7.533471) (xy 43.014974 -7.639744) (xy 42.961022 -7.74254)
			(xy 42.900108 -7.841368) (xy 42.83252 -7.935759) (xy 42.758581 -8.025261) (xy 42.678643 -8.109449)
			(xy 42.593088 -8.187922) (xy 42.502604 -8.26008) (xy 43.327577 -8.26008) (xy 43.331612 -8.184376)
			(xy 43.343671 -8.109531) (xy 43.363617 -8.03639) (xy 43.391224 -7.965785) (xy 43.42618 -7.898514)
			(xy 43.468088 -7.835339) (xy 43.516474 -7.776977) (xy 43.57079 -7.724089) (xy 43.630419 -7.677274)
			(xy 43.694687 -7.637062) (xy 43.762864 -7.60391) (xy 43.83418 -7.578192) (xy 43.907825 -7.5602) (xy 43.982965 -7.550138)
			(xy 44.058749 -7.548119) (xy 44.134319 -7.554168) (xy 44.208817 -7.568215) (xy 44.2814 -7.590101)
			(xy 44.351246 -7.619578) (xy 44.417563 -7.656313) (xy 44.479599 -7.699888) (xy 44.536652 -7.74981)
			(xy 44.588076 -7.805514) (xy 44.633287 -7.866369) (xy 44.671774 -7.931684) (xy 44.7031 -8.00072)
			(xy 44.72691 -8.072695) (xy 44.742935 -8.146793) (xy 44.750994 -8.222174) (xy 44.751498 -8.26008)
			(xy 45.867577 -8.26008) (xy 45.871612 -8.184376) (xy 45.883671 -8.109531) (xy 45.903617 -8.03639)
			(xy 45.931224 -7.965785) (xy 45.96618 -7.898514) (xy 46.008088 -7.835339) (xy 46.056474 -7.776977)
			(xy 46.11079 -7.724089) (xy 46.170419 -7.677274) (xy 46.234687 -7.637062) (xy 46.302864 -7.60391)
			(xy 46.37418 -7.578192) (xy 46.447825 -7.5602) (xy 46.522965 -7.550138) (xy 46.598749 -7.548119)
			(xy 46.674319 -7.554168) (xy 46.748817 -7.568215) (xy 46.8214 -7.590101) (xy 46.891246 -7.619578)
			(xy 46.957563 -7.656313) (xy 47.019599 -7.699888) (xy 47.076652 -7.74981) (xy 47.128076 -7.805514)
			(xy 47.173287 -7.866369) (xy 47.211774 -7.931684) (xy 47.2431 -8.00072) (xy 47.26691 -8.072695) (xy 47.282935 -8.146793)
			(xy 47.290994 -8.222174) (xy 47.291498 -8.26008) (xy 48.407577 -8.26008) (xy 48.411612 -8.184376)
			(xy 48.423671 -8.109531) (xy 48.443617 -8.03639) (xy 48.471224 -7.965785) (xy 48.50618 -7.898514)
			(xy 48.548088 -7.835339) (xy 48.596474 -7.776977) (xy 48.65079 -7.724089) (xy 48.710419 -7.677274)
			(xy 48.774687 -7.637062) (xy 48.842864 -7.60391) (xy 48.91418 -7.578192) (xy 48.987825 -7.5602) (xy 49.062965 -7.550138)
			(xy 49.138749 -7.548119) (xy 49.214319 -7.554168) (xy 49.288817 -7.568215) (xy 49.3614 -7.590101)
			(xy 49.431246 -7.619578) (xy 49.497563 -7.656313) (xy 49.559599 -7.699888) (xy 49.616652 -7.74981)
			(xy 49.668076 -7.805514) (xy 49.713287 -7.866369) (xy 49.751774 -7.931684) (xy 49.7831 -8.00072)
			(xy 49.80691 -8.072695) (xy 49.822935 -8.146793) (xy 49.830994 -8.222174) (xy 49.831498 -8.26008)
			(xy 50.947577 -8.26008) (xy 50.951612 -8.184376) (xy 50.963671 -8.109531) (xy 50.983617 -8.03639)
			(xy 51.011224 -7.965785) (xy 51.04618 -7.898514) (xy 51.088088 -7.835339) (xy 51.136474 -7.776977)
			(xy 51.19079 -7.724089) (xy 51.250419 -7.677274) (xy 51.314687 -7.637062) (xy 51.382864 -7.60391)
			(xy 51.45418 -7.578192) (xy 51.527825 -7.5602) (xy 51.602965 -7.550138) (xy 51.678749 -7.548119)
			(xy 51.754319 -7.554168) (xy 51.828817 -7.568215) (xy 51.9014 -7.590101) (xy 51.971246 -7.619578)
			(xy 52.037563 -7.656313) (xy 52.099599 -7.699888) (xy 52.156652 -7.74981) (xy 52.208076 -7.805514)
			(xy 52.253287 -7.866369) (xy 52.291774 -7.931684) (xy 52.3231 -8.00072) (xy 52.34691 -8.072695) (xy 52.362935 -8.146793)
			(xy 52.370994 -8.222174) (xy 52.371498 -8.26008) (xy 53.487577 -8.26008) (xy 53.491612 -8.184376)
			(xy 53.503671 -8.109531) (xy 53.523617 -8.03639) (xy 53.551224 -7.965785) (xy 53.58618 -7.898514)
			(xy 53.628088 -7.835339) (xy 53.676474 -7.776977) (xy 53.73079 -7.724089) (xy 53.790419 -7.677274)
			(xy 53.854687 -7.637062) (xy 53.922864 -7.60391) (xy 53.99418 -7.578192) (xy 54.067825 -7.5602) (xy 54.142965 -7.550138)
			(xy 54.218749 -7.548119) (xy 54.294319 -7.554168) (xy 54.368817 -7.568215) (xy 54.4414 -7.590101)
			(xy 54.511246 -7.619578) (xy 54.577563 -7.656313) (xy 54.639599 -7.699888) (xy 54.696652 -7.74981)
			(xy 54.748076 -7.805514) (xy 54.793287 -7.866369) (xy 54.831774 -7.931684) (xy 54.8631 -8.00072)
			(xy 54.88691 -8.072695) (xy 54.902935 -8.146793) (xy 54.910994 -8.222174) (xy 54.911498 -8.26008)
			(xy 56.027577 -8.26008) (xy 56.031612 -8.184376) (xy 56.043671 -8.109531) (xy 56.063617 -8.03639)
			(xy 56.091224 -7.965785) (xy 56.12618 -7.898514) (xy 56.168088 -7.835339) (xy 56.216474 -7.776977)
			(xy 56.27079 -7.724089) (xy 56.330419 -7.677274) (xy 56.394687 -7.637062) (xy 56.462864 -7.60391)
			(xy 56.53418 -7.578192) (xy 56.607825 -7.5602) (xy 56.682965 -7.550138) (xy 56.758749 -7.548119)
			(xy 56.834319 -7.554168) (xy 56.908817 -7.568215) (xy 56.9814 -7.590101) (xy 57.051246 -7.619578)
			(xy 57.117563 -7.656313) (xy 57.179599 -7.699888) (xy 57.236652 -7.74981) (xy 57.288076 -7.805514)
			(xy 57.333287 -7.866369) (xy 57.371774 -7.931684) (xy 57.4031 -8.00072) (xy 57.42691 -8.072695) (xy 57.442935 -8.146793)
			(xy 57.450994 -8.222174) (xy 57.451498 -8.26008) (xy 58.567577 -8.26008) (xy 58.571612 -8.184376)
			(xy 58.583671 -8.109531) (xy 58.603617 -8.03639) (xy 58.631224 -7.965785) (xy 58.66618 -7.898514)
			(xy 58.708088 -7.835339) (xy 58.756474 -7.776977) (xy 58.81079 -7.724089) (xy 58.870419 -7.677274)
			(xy 58.934687 -7.637062) (xy 59.002864 -7.60391) (xy 59.07418 -7.578192) (xy 59.147825 -7.5602) (xy 59.222965 -7.550138)
			(xy 59.298749 -7.548119) (xy 59.374319 -7.554168) (xy 59.448817 -7.568215) (xy 59.5214 -7.590101)
			(xy 59.591246 -7.619578) (xy 59.657563 -7.656313) (xy 59.719599 -7.699888) (xy 59.776652 -7.74981)
			(xy 59.828076 -7.805514) (xy 59.873287 -7.866369) (xy 59.911774 -7.931684) (xy 59.9431 -8.00072)
			(xy 59.96691 -8.072695) (xy 59.982935 -8.146793) (xy 59.990994 -8.222174) (xy 59.991498 -8.26008)
			(xy 61.107577 -8.26008) (xy 61.111612 -8.184376) (xy 61.123671 -8.109531) (xy 61.143617 -8.03639)
			(xy 61.171224 -7.965785) (xy 61.20618 -7.898514) (xy 61.248088 -7.835339) (xy 61.296474 -7.776977)
			(xy 61.35079 -7.724089) (xy 61.410419 -7.677274) (xy 61.474687 -7.637062) (xy 61.542864 -7.60391)
			(xy 61.61418 -7.578192) (xy 61.687825 -7.5602) (xy 61.762965 -7.550138) (xy 61.838749 -7.548119)
			(xy 61.914319 -7.554168) (xy 61.988817 -7.568215) (xy 62.0614 -7.590101) (xy 62.131246 -7.619578)
			(xy 62.197563 -7.656313) (xy 62.259599 -7.699888) (xy 62.316652 -7.74981) (xy 62.368076 -7.805514)
			(xy 62.413287 -7.866369) (xy 62.451774 -7.931684) (xy 62.4831 -8.00072) (xy 62.50691 -8.072695) (xy 62.522935 -8.146793)
			(xy 62.530994 -8.222174) (xy 62.531498 -8.26008) (xy 62.530994 -8.297986) (xy 62.522935 -8.373367)
			(xy 62.50691 -8.447465) (xy 62.4831 -8.51944) (xy 62.451774 -8.588476) (xy 62.413287 -8.653791) (xy 62.368076 -8.714646)
			(xy 62.316652 -8.77035) (xy 62.259599 -8.820272) (xy 62.197563 -8.863847) (xy 62.131246 -8.900582)
			(xy 62.0614 -8.930059) (xy 61.988817 -8.951945) (xy 61.914319 -8.965992) (xy 61.838749 -8.972041)
			(xy 61.762965 -8.970022) (xy 61.687825 -8.95996) (xy 61.61418 -8.941968) (xy 61.542864 -8.91625)
			(xy 61.474687 -8.883098) (xy 61.410419 -8.842886) (xy 61.35079 -8.796071) (xy 61.296474 -8.743183)
			(xy 61.248088 -8.684821) (xy 61.20618 -8.621646) (xy 61.171224 -8.554375) (xy 61.143617 -8.48377)
			(xy 61.123671 -8.410629) (xy 61.111612 -8.335784) (xy 61.107577 -8.26008) (xy 59.991498 -8.26008)
			(xy 59.990994 -8.297986) (xy 59.982935 -8.373367) (xy 59.96691 -8.447465) (xy 59.9431 -8.51944) (xy 59.911774 -8.588476)
			(xy 59.873287 -8.653791) (xy 59.828076 -8.714646) (xy 59.776652 -8.77035) (xy 59.719599 -8.820272)
			(xy 59.657563 -8.863847) (xy 59.591246 -8.900582) (xy 59.5214 -8.930059) (xy 59.448817 -8.951945)
			(xy 59.374319 -8.965992) (xy 59.298749 -8.972041) (xy 59.222965 -8.970022) (xy 59.147825 -8.95996)
			(xy 59.07418 -8.941968) (xy 59.002864 -8.91625) (xy 58.934687 -8.883098) (xy 58.870419 -8.842886)
			(xy 58.81079 -8.796071) (xy 58.756474 -8.743183) (xy 58.708088 -8.684821) (xy 58.66618 -8.621646)
			(xy 58.631224 -8.554375) (xy 58.603617 -8.48377) (xy 58.583671 -8.410629) (xy 58.571612 -8.335784)
			(xy 58.567577 -8.26008) (xy 57.451498 -8.26008) (xy 57.450994 -8.297986) (xy 57.442935 -8.373367)
			(xy 57.42691 -8.447465) (xy 57.4031 -8.51944) (xy 57.371774 -8.588476) (xy 57.333287 -8.653791) (xy 57.288076 -8.714646)
			(xy 57.236652 -8.77035) (xy 57.179599 -8.820272) (xy 57.117563 -8.863847) (xy 57.051246 -8.900582)
			(xy 56.9814 -8.930059) (xy 56.908817 -8.951945) (xy 56.834319 -8.965992) (xy 56.758749 -8.972041)
			(xy 56.682965 -8.970022) (xy 56.607825 -8.95996) (xy 56.53418 -8.941968) (xy 56.462864 -8.91625)
			(xy 56.394687 -8.883098) (xy 56.330419 -8.842886) (xy 56.27079 -8.796071) (xy 56.216474 -8.743183)
			(xy 56.168088 -8.684821) (xy 56.12618 -8.621646) (xy 56.091224 -8.554375) (xy 56.063617 -8.48377)
			(xy 56.043671 -8.410629) (xy 56.031612 -8.335784) (xy 56.027577 -8.26008) (xy 54.911498 -8.26008)
			(xy 54.910994 -8.297986) (xy 54.902935 -8.373367) (xy 54.88691 -8.447465) (xy 54.8631 -8.51944) (xy 54.831774 -8.588476)
			(xy 54.793287 -8.653791) (xy 54.748076 -8.714646) (xy 54.696652 -8.77035) (xy 54.639599 -8.820272)
			(xy 54.577563 -8.863847) (xy 54.511246 -8.900582) (xy 54.4414 -8.930059) (xy 54.368817 -8.951945)
			(xy 54.294319 -8.965992) (xy 54.218749 -8.972041) (xy 54.142965 -8.970022) (xy 54.067825 -8.95996)
			(xy 53.99418 -8.941968) (xy 53.922864 -8.91625) (xy 53.854687 -8.883098) (xy 53.790419 -8.842886)
			(xy 53.73079 -8.796071) (xy 53.676474 -8.743183) (xy 53.628088 -8.684821) (xy 53.58618 -8.621646)
			(xy 53.551224 -8.554375) (xy 53.523617 -8.48377) (xy 53.503671 -8.410629) (xy 53.491612 -8.335784)
			(xy 53.487577 -8.26008) (xy 52.371498 -8.26008) (xy 52.370994 -8.297986) (xy 52.362935 -8.373367)
			(xy 52.34691 -8.447465) (xy 52.3231 -8.51944) (xy 52.291774 -8.588476) (xy 52.253287 -8.653791) (xy 52.208076 -8.714646)
			(xy 52.156652 -8.77035) (xy 52.099599 -8.820272) (xy 52.037563 -8.863847) (xy 51.971246 -8.900582)
			(xy 51.9014 -8.930059) (xy 51.828817 -8.951945) (xy 51.754319 -8.965992) (xy 51.678749 -8.972041)
			(xy 51.602965 -8.970022) (xy 51.527825 -8.95996) (xy 51.45418 -8.941968) (xy 51.382864 -8.91625)
			(xy 51.314687 -8.883098) (xy 51.250419 -8.842886) (xy 51.19079 -8.796071) (xy 51.136474 -8.743183)
			(xy 51.088088 -8.684821) (xy 51.04618 -8.621646) (xy 51.011224 -8.554375) (xy 50.983617 -8.48377)
			(xy 50.963671 -8.410629) (xy 50.951612 -8.335784) (xy 50.947577 -8.26008) (xy 49.831498 -8.26008)
			(xy 49.830994 -8.297986) (xy 49.822935 -8.373367) (xy 49.80691 -8.447465) (xy 49.7831 -8.51944) (xy 49.751774 -8.588476)
			(xy 49.713287 -8.653791) (xy 49.668076 -8.714646) (xy 49.616652 -8.77035) (xy 49.559599 -8.820272)
			(xy 49.497563 -8.863847) (xy 49.431246 -8.900582) (xy 49.3614 -8.930059) (xy 49.288817 -8.951945)
			(xy 49.214319 -8.965992) (xy 49.138749 -8.972041) (xy 49.062965 -8.970022) (xy 48.987825 -8.95996)
			(xy 48.91418 -8.941968) (xy 48.842864 -8.91625) (xy 48.774687 -8.883098) (xy 48.710419 -8.842886)
			(xy 48.65079 -8.796071) (xy 48.596474 -8.743183) (xy 48.548088 -8.684821) (xy 48.50618 -8.621646)
			(xy 48.471224 -8.554375) (xy 48.443617 -8.48377) (xy 48.423671 -8.410629) (xy 48.411612 -8.335784)
			(xy 48.407577 -8.26008) (xy 47.291498 -8.26008) (xy 47.290994 -8.297986) (xy 47.282935 -8.373367)
			(xy 47.26691 -8.447465) (xy 47.2431 -8.51944) (xy 47.211774 -8.588476) (xy 47.173287 -8.653791) (xy 47.128076 -8.714646)
			(xy 47.076652 -8.77035) (xy 47.019599 -8.820272) (xy 46.957563 -8.863847) (xy 46.891246 -8.900582)
			(xy 46.8214 -8.930059) (xy 46.748817 -8.951945) (xy 46.674319 -8.965992) (xy 46.598749 -8.972041)
			(xy 46.522965 -8.970022) (xy 46.447825 -8.95996) (xy 46.37418 -8.941968) (xy 46.302864 -8.91625)
			(xy 46.234687 -8.883098) (xy 46.170419 -8.842886) (xy 46.11079 -8.796071) (xy 46.056474 -8.743183)
			(xy 46.008088 -8.684821) (xy 45.96618 -8.621646) (xy 45.931224 -8.554375) (xy 45.903617 -8.48377)
			(xy 45.883671 -8.410629) (xy 45.871612 -8.335784) (xy 45.867577 -8.26008) (xy 44.751498 -8.26008)
			(xy 44.750994 -8.297986) (xy 44.742935 -8.373367) (xy 44.72691 -8.447465) (xy 44.7031 -8.51944) (xy 44.671774 -8.588476)
			(xy 44.633287 -8.653791) (xy 44.588076 -8.714646) (xy 44.536652 -8.77035) (xy 44.479599 -8.820272)
			(xy 44.417563 -8.863847) (xy 44.351246 -8.900582) (xy 44.2814 -8.930059) (xy 44.208817 -8.951945)
			(xy 44.134319 -8.965992) (xy 44.058749 -8.972041) (xy 43.982965 -8.970022) (xy 43.907825 -8.95996)
			(xy 43.83418 -8.941968) (xy 43.762864 -8.91625) (xy 43.694687 -8.883098) (xy 43.630419 -8.842886)
			(xy 43.57079 -8.796071) (xy 43.516474 -8.743183) (xy 43.468088 -8.684821) (xy 43.42618 -8.621646)
			(xy 43.391224 -8.554375) (xy 43.363617 -8.48377) (xy 43.343671 -8.410629) (xy 43.331612 -8.335784)
			(xy 43.327577 -8.26008) (xy 42.502604 -8.26008) (xy 42.502322 -8.260305) (xy 42.406779 -8.326254)
			(xy 42.306914 -8.385454) (xy 42.203202 -8.437623) (xy 42.096139 -8.482512) (xy 41.986233 -8.519908)
			(xy 41.874009 -8.549633) (xy 41.760003 -8.571544) (xy 41.644756 -8.585537) (xy 41.528818 -8.591546)
			(xy 41.412742 -8.589543) (xy 41.29708 -8.579535) (xy 41.182385 -8.561572) (xy 41.069202 -8.535739)
			(xy 40.958071 -8.502159) (xy 40.849522 -8.460991) (xy 40.744072 -8.412433) (xy 40.642223 -8.356716)
			(xy 40.54446 -8.294104) (xy 40.45125 -8.224897) (xy 40.363037 -8.149424) (xy 40.280241 -8.068045)
			(xy 40.203257 -7.981148) (xy 40.132452 -7.889147) (xy 40.068162 -7.79248) (xy 40.010695 -7.691608)
			(xy 39.960324 -7.587011) (xy 39.917289 -7.479188) (xy 39.881795 -7.368654) (xy 39.854012 -7.255934)
			(xy 39.834072 -7.141566) (xy 39.82207 -7.026094) (xy 39.818063 -6.91007) (xy 36.454201 -6.91007)
			(xy 36.4555 -6.914635) (xy 36.471468 -7.000055) (xy 36.479486 -7.086584) (xy 36.479988 -7.130034)
			(xy 36.479486 -7.173484) (xy 36.471468 -7.260013) (xy 36.4555 -7.345433) (xy 36.431719 -7.429015)
			(xy 36.400327 -7.510047) (xy 36.361593 -7.587836) (xy 36.315846 -7.66172) (xy 36.263477 -7.731067)
			(xy 36.204933 -7.795287) (xy 36.140713 -7.853831) (xy 36.071366 -7.9062) (xy 35.997482 -7.951947)
			(xy 35.919693 -7.990681) (xy 35.838661 -8.022073) (xy 35.755079 -8.045854) (xy 35.669659 -8.061822)
			(xy 35.58313 -8.06984) (xy 35.49623 -8.06984) (xy 35.409701 -8.061822) (xy 35.324281 -8.045854) (xy 35.240699 -8.022073)
			(xy 35.159667 -7.990681) (xy 35.081878 -7.951947) (xy 35.007994 -7.9062) (xy 34.938647 -7.853831)
			(xy 34.874427 -7.795287) (xy 34.815883 -7.731067) (xy 34.763514 -7.66172) (xy 34.717767 -7.587836)
			(xy 34.679033 -7.510047) (xy 34.647641 -7.429015) (xy 34.62386 -7.345433) (xy 34.607892 -7.260013)
			(xy 34.599874 -7.173484) (xy 31.399486 -7.173484) (xy 31.391468 -7.260013) (xy 31.3755 -7.345433)
			(xy 31.351719 -7.429015) (xy 31.320327 -7.510047) (xy 31.281593 -7.587836) (xy 31.235846 -7.66172)
			(xy 31.183477 -7.731067) (xy 31.124933 -7.795287) (xy 31.060713 -7.853831) (xy 30.991366 -7.9062)
			(xy 30.917482 -7.951947) (xy 30.839693 -7.990681) (xy 30.758661 -8.022073) (xy 30.675079 -8.045854)
			(xy 30.589659 -8.061822) (xy 30.50313 -8.06984) (xy 30.41623 -8.06984) (xy 30.329701 -8.061822) (xy 30.244281 -8.045854)
			(xy 30.160699 -8.022073) (xy 30.079667 -7.990681) (xy 30.001878 -7.951947) (xy 29.927994 -7.9062)
			(xy 29.858647 -7.853831) (xy 29.794427 -7.795287) (xy 29.735883 -7.731067) (xy 29.683514 -7.66172)
			(xy 29.637767 -7.587836) (xy 29.599033 -7.510047) (xy 29.567641 -7.429015) (xy 29.54386 -7.345433)
			(xy 29.527892 -7.260013) (xy 29.519874 -7.173484) (xy 12.442698 -7.173484) (xy 12.442444 -7.180834)
			(xy 12.442444 -8.062214) (xy 12.443581 -8.083916) (xy 12.452335 -8.126479) (xy 12.4682 -8.166933)
			(xy 12.490714 -8.204099) (xy 12.519221 -8.236895) (xy 12.552891 -8.264365) (xy 12.590742 -8.285709)
			(xy 12.631671 -8.300304) (xy 12.674486 -8.307726) (xy 12.71794 -8.307758) (xy 12.760767 -8.300399)
			(xy 12.801717 -8.285864) (xy 12.8396 -8.264576) (xy 12.856718 -8.25119) (xy 12.888695 -8.22443) (xy 12.95712 -8.176772)
			(xy 13.030001 -8.136255) (xy 13.106596 -8.10329) (xy 13.186122 -8.078213) (xy 13.267772 -8.061281)
			(xy 13.350712 -8.052665) (xy 13.392404 -8.052054) (xy 13.433083 -8.052429) (xy 13.514067 -8.060203)
			(xy 13.593895 -8.075901) (xy 13.671792 -8.099371) (xy 13.747005 -8.130386) (xy 13.818804 -8.168644)
			(xy 13.886494 -8.213776) (xy 13.949419 -8.265344) (xy 14.00697 -8.322849) (xy 14.024875 -8.344662)
			(xy 24.3619 -8.344662) (xy 24.365971 -8.28904) (xy 24.378097 -8.234603) (xy 24.39802 -8.182512) (xy 24.425316 -8.133877)
			(xy 24.459402 -8.089734) (xy 24.499551 -8.051025) (xy 24.544909 -8.018574) (xy 24.594509 -7.993073)
			(xy 24.647293 -7.975066) (xy 24.702136 -7.964936) (xy 24.75787 -7.962899) (xy 24.813307 -7.968999)
			(xy 24.867264 -7.983105) (xy 24.918593 -8.004917) (xy 24.966199 -8.033971) (xy 25.009067 -8.069646)
			(xy 25.046284 -8.111183) (xy 25.077057 -8.157696) (xy 25.100729 -8.208193) (xy 25.116797 -8.2616)
			(xy 25.124917 -8.316776) (xy 25.125426 -8.344662) (xy 25.124917 -8.372548) (xy 25.116797 -8.427724)
			(xy 25.100729 -8.481131) (xy 25.077057 -8.531628) (xy 25.046284 -8.578141) (xy 25.009067 -8.619678)
			(xy 24.966199 -8.655353) (xy 24.918593 -8.684407) (xy 24.867264 -8.706219) (xy 24.813307 -8.720325)
			(xy 24.75787 -8.726425) (xy 24.702136 -8.724388) (xy 24.647293 -8.714258) (xy 24.594509 -8.696251)
			(xy 24.544909 -8.67075) (xy 24.499551 -8.638299) (xy 24.459402 -8.59959) (xy 24.425316 -8.555447)
			(xy 24.39802 -8.506812) (xy 24.378097 -8.454721) (xy 24.365971 -8.400284) (xy 24.3619 -8.344662)
			(xy 14.024875 -8.344662) (xy 14.058588 -8.385733) (xy 14.103775 -8.453386) (xy 14.142091 -8.525155)
			(xy 14.173166 -8.600342) (xy 14.196698 -8.678221) (xy 14.212461 -8.758036) (xy 14.21754 -8.810498)
			(xy 26.80538 -8.810498) (xy 26.809451 -8.754876) (xy 26.821577 -8.700439) (xy 26.8415 -8.648348)
			(xy 26.868796 -8.599713) (xy 26.902882 -8.55557) (xy 26.943031 -8.516861) (xy 26.988389 -8.48441)
			(xy 27.037989 -8.458909) (xy 27.090773 -8.440902) (xy 27.145616 -8.430772) (xy 27.20135 -8.428735)
			(xy 27.256787 -8.434835) (xy 27.310744 -8.448941) (xy 27.362073 -8.470753) (xy 27.409679 -8.499807)
			(xy 27.452547 -8.535482) (xy 27.489764 -8.577019) (xy 27.520537 -8.623532) (xy 27.544209 -8.674029)
			(xy 27.560277 -8.727436) (xy 27.568397 -8.782612) (xy 27.568906 -8.810498) (xy 27.568397 -8.838384)
			(xy 27.560277 -8.89356) (xy 27.544209 -8.946967) (xy 27.520537 -8.997464) (xy 27.489764 -9.043977)
			(xy 27.452547 -9.085514) (xy 27.409679 -9.121189) (xy 27.362073 -9.150243) (xy 27.310744 -9.172055)
			(xy 27.256787 -9.186161) (xy 27.20135 -9.192261) (xy 27.145616 -9.190224) (xy 27.090773 -9.180094)
			(xy 27.037989 -9.162087) (xy 26.988389 -9.136586) (xy 26.943031 -9.104135) (xy 26.902882 -9.065426)
			(xy 26.868796 -9.021283) (xy 26.8415 -8.972648) (xy 26.821577 -8.920557) (xy 26.809451 -8.86612)
			(xy 26.80538 -8.810498) (xy 14.21754 -8.810498) (xy 14.2203 -8.839013) (xy 14.22014 -8.920369) (xy 14.211983 -9.001316)
			(xy 14.195907 -9.081068) (xy 14.172069 -9.158853) (xy 14.140699 -9.233918) (xy 14.102101 -9.305536)
			(xy 14.056649 -9.373012) (xy 14.004784 -9.435692) (xy 13.947008 -9.49297) (xy 13.92698 -9.509252)
			(xy 24.3619 -9.509252) (xy 24.365971 -9.45363) (xy 24.378097 -9.399193) (xy 24.39802 -9.347102) (xy 24.425316 -9.298467)
			(xy 24.459402 -9.254324) (xy 24.499551 -9.215615) (xy 24.544909 -9.183164) (xy 24.594509 -9.157663)
			(xy 24.647293 -9.139656) (xy 24.702136 -9.129526) (xy 24.75787 -9.127489) (xy 24.813307 -9.133589)
			(xy 24.867264 -9.147695) (xy 24.918593 -9.169507) (xy 24.966199 -9.198561) (xy 25.009067 -9.234236)
			(xy 25.046284 -9.275773) (xy 25.077057 -9.322286) (xy 25.100729 -9.372783) (xy 25.116797 -9.42619)
			(xy 25.124917 -9.481366) (xy 25.125426 -9.509252) (xy 25.124917 -9.537138) (xy 25.116797 -9.592314)
			(xy 25.100729 -9.645721) (xy 25.077057 -9.696218) (xy 25.046284 -9.742731) (xy 25.009067 -9.784268)
			(xy 24.966199 -9.819943) (xy 24.918593 -9.848997) (xy 24.867264 -9.870809) (xy 24.830784 -9.880346)
			(xy 27.07081 -9.880346) (xy 27.074881 -9.824724) (xy 27.087007 -9.770287) (xy 27.10693 -9.718196)
			(xy 27.134226 -9.669561) (xy 27.168312 -9.625418) (xy 27.208461 -9.586709) (xy 27.253819 -9.554258)
			(xy 27.303419 -9.528757) (xy 27.356203 -9.51075) (xy 27.411046 -9.50062) (xy 27.46678 -9.498583)
			(xy 27.522217 -9.504683) (xy 27.576174 -9.518789) (xy 27.627503 -9.540601) (xy 27.675109 -9.569655)
			(xy 27.717977 -9.60533) (xy 27.755194 -9.646867) (xy 27.785967 -9.69338) (xy 27.795391 -9.713484)
			(xy 29.519874 -9.713484) (xy 29.519874 -9.626584) (xy 29.527892 -9.540055) (xy 29.54386 -9.454635)
			(xy 29.567641 -9.371053) (xy 29.599033 -9.290021) (xy 29.637767 -9.212232) (xy 29.683514 -9.138348)
			(xy 29.735883 -9.069001) (xy 29.794427 -9.004781) (xy 29.858647 -8.946237) (xy 29.927994 -8.893868)
			(xy 30.001878 -8.848121) (xy 30.079667 -8.809387) (xy 30.160699 -8.777995) (xy 30.244281 -8.754214)
			(xy 30.329701 -8.738246) (xy 30.41623 -8.730228) (xy 30.50313 -8.730228) (xy 30.589659 -8.738246)
			(xy 30.675079 -8.754214) (xy 30.758661 -8.777995) (xy 30.839693 -8.809387) (xy 30.917482 -8.848121)
			(xy 30.991366 -8.893868) (xy 31.060713 -8.946237) (xy 31.124933 -9.004781) (xy 31.183477 -9.069001)
			(xy 31.235846 -9.138348) (xy 31.281593 -9.212232) (xy 31.320327 -9.290021) (xy 31.351719 -9.371053)
			(xy 31.3755 -9.454635) (xy 31.391468 -9.540055) (xy 31.399486 -9.626584) (xy 31.399988 -9.670034)
			(xy 31.399486 -9.713484) (xy 34.599874 -9.713484) (xy 34.599874 -9.626584) (xy 34.607892 -9.540055)
			(xy 34.62386 -9.454635) (xy 34.647641 -9.371053) (xy 34.679033 -9.290021) (xy 34.717767 -9.212232)
			(xy 34.763514 -9.138348) (xy 34.815883 -9.069001) (xy 34.874427 -9.004781) (xy 34.938647 -8.946237)
			(xy 35.007994 -8.893868) (xy 35.081878 -8.848121) (xy 35.159667 -8.809387) (xy 35.240699 -8.777995)
			(xy 35.324281 -8.754214) (xy 35.409701 -8.738246) (xy 35.49623 -8.730228) (xy 35.58313 -8.730228)
			(xy 35.669659 -8.738246) (xy 35.755079 -8.754214) (xy 35.838661 -8.777995) (xy 35.919693 -8.809387)
			(xy 35.997482 -8.848121) (xy 36.071366 -8.893868) (xy 36.140713 -8.946237) (xy 36.204933 -9.004781)
			(xy 36.263477 -9.069001) (xy 36.315846 -9.138348) (xy 36.361593 -9.212232) (xy 36.400327 -9.290021)
			(xy 36.431719 -9.371053) (xy 36.4555 -9.454635) (xy 36.471468 -9.540055) (xy 36.479486 -9.626584)
			(xy 36.479988 -9.670034) (xy 36.479486 -9.713484) (xy 36.471468 -9.800013) (xy 36.4555 -9.885433)
			(xy 36.431719 -9.969015) (xy 36.400327 -10.050047) (xy 36.361593 -10.127836) (xy 36.315846 -10.20172)
			(xy 36.263477 -10.271067) (xy 36.204933 -10.335287) (xy 36.140713 -10.393831) (xy 36.071366 -10.4462)
			(xy 35.997482 -10.491947) (xy 35.919693 -10.530681) (xy 35.838661 -10.562073) (xy 35.755079 -10.585854)
			(xy 35.669659 -10.601822) (xy 35.58313 -10.60984) (xy 35.49623 -10.60984) (xy 35.409701 -10.601822)
			(xy 35.324281 -10.585854) (xy 35.240699 -10.562073) (xy 35.159667 -10.530681) (xy 35.081878 -10.491947)
			(xy 35.007994 -10.4462) (xy 34.938647 -10.393831) (xy 34.874427 -10.335287) (xy 34.815883 -10.271067)
			(xy 34.763514 -10.20172) (xy 34.717767 -10.127836) (xy 34.679033 -10.050047) (xy 34.647641 -9.969015)
			(xy 34.62386 -9.885433) (xy 34.607892 -9.800013) (xy 34.599874 -9.713484) (xy 31.399486 -9.713484)
			(xy 31.391468 -9.800013) (xy 31.3755 -9.885433) (xy 31.351719 -9.969015) (xy 31.320327 -10.050047)
			(xy 31.281593 -10.127836) (xy 31.235846 -10.20172) (xy 31.183477 -10.271067) (xy 31.124933 -10.335287)
			(xy 31.060713 -10.393831) (xy 30.991366 -10.4462) (xy 30.917482 -10.491947) (xy 30.839693 -10.530681)
			(xy 30.758661 -10.562073) (xy 30.675079 -10.585854) (xy 30.589659 -10.601822) (xy 30.50313 -10.60984)
			(xy 30.41623 -10.60984) (xy 30.329701 -10.601822) (xy 30.244281 -10.585854) (xy 30.160699 -10.562073)
			(xy 30.079667 -10.530681) (xy 30.001878 -10.491947) (xy 29.927994 -10.4462) (xy 29.858647 -10.393831)
			(xy 29.794427 -10.335287) (xy 29.735883 -10.271067) (xy 29.683514 -10.20172) (xy 29.637767 -10.127836)
			(xy 29.599033 -10.050047) (xy 29.567641 -9.969015) (xy 29.54386 -9.885433) (xy 29.527892 -9.800013)
			(xy 29.519874 -9.713484) (xy 27.795391 -9.713484) (xy 27.809639 -9.743877) (xy 27.825707 -9.797284)
			(xy 27.833827 -9.85246) (xy 27.834336 -9.880346) (xy 27.833827 -9.908232) (xy 27.825707 -9.963408)
			(xy 27.809639 -10.016815) (xy 27.785967 -10.067312) (xy 27.755194 -10.113825) (xy 27.717977 -10.155362)
			(xy 27.675109 -10.191037) (xy 27.627503 -10.220091) (xy 27.576174 -10.241903) (xy 27.522217 -10.256009)
			(xy 27.46678 -10.262109) (xy 27.411046 -10.260072) (xy 27.356203 -10.249942) (xy 27.303419 -10.231935)
			(xy 27.253819 -10.206434) (xy 27.208461 -10.173983) (xy 27.168312 -10.135274) (xy 27.134226 -10.091131)
			(xy 27.10693 -10.042496) (xy 27.087007 -9.990405) (xy 27.074881 -9.935968) (xy 27.07081 -9.880346)
			(xy 24.830784 -9.880346) (xy 24.813307 -9.884915) (xy 24.75787 -9.891015) (xy 24.702136 -9.888978)
			(xy 24.647293 -9.878848) (xy 24.594509 -9.860841) (xy 24.544909 -9.83534) (xy 24.499551 -9.802889)
			(xy 24.459402 -9.76418) (xy 24.425316 -9.720037) (xy 24.39802 -9.671402) (xy 24.378097 -9.619311)
			(xy 24.365971 -9.564874) (xy 24.3619 -9.509252) (xy 13.92698 -9.509252) (xy 13.883881 -9.54429) (xy 13.816014 -9.589156)
			(xy 13.780262 -9.608566) (xy 13.765273 -9.617129) (xy 13.740181 -9.640817) (xy 13.722337 -9.670351)
			(xy 13.713041 -9.703582) (xy 13.712444 -9.720834) (xy 13.712444 -10.617962) (xy 25.381202 -10.617962)
			(xy 25.385273 -10.56234) (xy 25.397399 -10.507903) (xy 25.417322 -10.455812) (xy 25.444618 -10.407177)
			(xy 25.478704 -10.363034) (xy 25.518853 -10.324325) (xy 25.564211 -10.291874) (xy 25.613811 -10.266373)
			(xy 25.666595 -10.248366) (xy 25.721438 -10.238236) (xy 25.777172 -10.236199) (xy 25.832609 -10.242299)
			(xy 25.886566 -10.256405) (xy 25.937895 -10.278217) (xy 25.985501 -10.307271) (xy 26.028369 -10.342946)
			(xy 26.065586 -10.384483) (xy 26.096359 -10.430996) (xy 26.120031 -10.481493) (xy 26.136099 -10.5349)
			(xy 26.144219 -10.590076) (xy 26.144728 -10.617962) (xy 26.144219 -10.645848) (xy 26.136099 -10.701024)
			(xy 26.120031 -10.754431) (xy 26.096359 -10.804928) (xy 26.065586 -10.851441) (xy 26.028369 -10.892978)
			(xy 25.985501 -10.928653) (xy 25.937895 -10.957707) (xy 25.886566 -10.979519) (xy 25.832609 -10.993625)
			(xy 25.777172 -10.999725) (xy 25.721438 -10.997688) (xy 25.666595 -10.987558) (xy 25.613811 -10.969551)
			(xy 25.564211 -10.94405) (xy 25.518853 -10.911599) (xy 25.478704 -10.87289) (xy 25.444618 -10.828747)
			(xy 25.417322 -10.780112) (xy 25.397399 -10.728021) (xy 25.385273 -10.673584) (xy 25.381202 -10.617962)
			(xy 13.712444 -10.617962) (xy 13.712444 -11.692636) (xy 12.842094 -12.563094) (xy 25.690066 -12.563094)
			(xy 25.694137 -12.507472) (xy 25.706263 -12.453035) (xy 25.726186 -12.400944) (xy 25.753482 -12.352309)
			(xy 25.787568 -12.308166) (xy 25.827717 -12.269457) (xy 25.873075 -12.237006) (xy 25.922675 -12.211505)
			(xy 25.975459 -12.193498) (xy 26.030302 -12.183368) (xy 26.086036 -12.181331) (xy 26.141473 -12.187431)
			(xy 26.19543 -12.201537) (xy 26.246759 -12.223349) (xy 26.294365 -12.252403) (xy 26.295664 -12.253484)
			(xy 29.519874 -12.253484) (xy 29.519874 -12.166584) (xy 29.527892 -12.080055) (xy 29.54386 -11.994635)
			(xy 29.567641 -11.911053) (xy 29.599033 -11.830021) (xy 29.637767 -11.752232) (xy 29.683514 -11.678348)
			(xy 29.735883 -11.609001) (xy 29.794427 -11.544781) (xy 29.858647 -11.486237) (xy 29.927994 -11.433868)
			(xy 30.001878 -11.388121) (xy 30.079667 -11.349387) (xy 30.160699 -11.317995) (xy 30.244281 -11.294214)
			(xy 30.329701 -11.278246) (xy 30.41623 -11.270228) (xy 30.50313 -11.270228) (xy 30.589659 -11.278246)
			(xy 30.675079 -11.294214) (xy 30.758661 -11.317995) (xy 30.839693 -11.349387) (xy 30.917482 -11.388121)
			(xy 30.991366 -11.433868) (xy 31.060713 -11.486237) (xy 31.124933 -11.544781) (xy 31.183477 -11.609001)
			(xy 31.235846 -11.678348) (xy 31.281593 -11.752232) (xy 31.320327 -11.830021) (xy 31.351719 -11.911053)
			(xy 31.3755 -11.994635) (xy 31.391468 -12.080055) (xy 31.399486 -12.166584) (xy 31.399988 -12.210034)
			(xy 31.399486 -12.253484) (xy 34.599874 -12.253484) (xy 34.599874 -12.166584) (xy 34.607892 -12.080055)
			(xy 34.62386 -11.994635) (xy 34.647641 -11.911053) (xy 34.679033 -11.830021) (xy 34.717767 -11.752232)
			(xy 34.763514 -11.678348) (xy 34.815883 -11.609001) (xy 34.874427 -11.544781) (xy 34.938647 -11.486237)
			(xy 35.007994 -11.433868) (xy 35.081878 -11.388121) (xy 35.159667 -11.349387) (xy 35.240699 -11.317995)
			(xy 35.324281 -11.294214) (xy 35.409701 -11.278246) (xy 35.49623 -11.270228) (xy 35.58313 -11.270228)
			(xy 35.669659 -11.278246) (xy 35.755079 -11.294214) (xy 35.838661 -11.317995) (xy 35.919693 -11.349387)
			(xy 35.997482 -11.388121) (xy 36.071366 -11.433868) (xy 36.140713 -11.486237) (xy 36.204933 -11.544781)
			(xy 36.263477 -11.609001) (xy 36.315846 -11.678348) (xy 36.361593 -11.752232) (xy 36.400327 -11.830021)
			(xy 36.431719 -11.911053) (xy 36.4555 -11.994635) (xy 36.471468 -12.080055) (xy 36.479486 -12.166584)
			(xy 36.479988 -12.210034) (xy 36.479486 -12.253484) (xy 36.471468 -12.340013) (xy 36.4555 -12.425433)
			(xy 36.431719 -12.509015) (xy 36.400327 -12.590047) (xy 36.361593 -12.667836) (xy 36.315846 -12.74172)
			(xy 36.263477 -12.811067) (xy 36.204933 -12.875287) (xy 36.140713 -12.933831) (xy 36.071366 -12.9862)
			(xy 35.997482 -13.031947) (xy 35.936717 -13.062204) (xy 39.637714 -13.062204) (xy 39.641785 -13.006582)
			(xy 39.653911 -12.952145) (xy 39.673834 -12.900054) (xy 39.70113 -12.851419) (xy 39.735216 -12.807276)
			(xy 39.775365 -12.768567) (xy 39.820723 -12.736116) (xy 39.870323 -12.710615) (xy 39.923107 -12.692608)
			(xy 39.97795 -12.682478) (xy 40.033684 -12.680441) (xy 40.089121 -12.686541) (xy 40.143078 -12.700647)
			(xy 40.194407 -12.722459) (xy 40.242013 -12.751513) (xy 40.284881 -12.787188) (xy 40.322098 -12.828725)
			(xy 40.352871 -12.875238) (xy 40.376543 -12.925735) (xy 40.392611 -12.979142) (xy 40.400731 -13.034318)
			(xy 40.40124 -13.062204) (xy 40.400731 -13.09009) (xy 40.392611 -13.145266) (xy 40.376543 -13.198673)
			(xy 40.352871 -13.24917) (xy 40.322098 -13.295683) (xy 40.284881 -13.33722) (xy 40.242013 -13.372895)
			(xy 40.194407 -13.401949) (xy 40.143078 -13.423761) (xy 40.089121 -13.437867) (xy 40.033684 -13.443967)
			(xy 39.97795 -13.44193) (xy 39.923107 -13.4318) (xy 39.870323 -13.413793) (xy 39.820723 -13.388292)
			(xy 39.775365 -13.355841) (xy 39.735216 -13.317132) (xy 39.70113 -13.272989) (xy 39.673834 -13.224354)
			(xy 39.653911 -13.172263) (xy 39.641785 -13.117826) (xy 39.637714 -13.062204) (xy 35.936717 -13.062204)
			(xy 35.919693 -13.070681) (xy 35.838661 -13.102073) (xy 35.755079 -13.125854) (xy 35.669659 -13.141822)
			(xy 35.58313 -13.14984) (xy 35.49623 -13.14984) (xy 35.409701 -13.141822) (xy 35.324281 -13.125854)
			(xy 35.240699 -13.102073) (xy 35.159667 -13.070681) (xy 35.081878 -13.031947) (xy 35.007994 -12.9862)
			(xy 34.938647 -12.933831) (xy 34.874427 -12.875287) (xy 34.815883 -12.811067) (xy 34.763514 -12.74172)
			(xy 34.717767 -12.667836) (xy 34.679033 -12.590047) (xy 34.647641 -12.509015) (xy 34.62386 -12.425433)
			(xy 34.607892 -12.340013) (xy 34.599874 -12.253484) (xy 31.399486 -12.253484) (xy 31.391468 -12.340013)
			(xy 31.3755 -12.425433) (xy 31.351719 -12.509015) (xy 31.320327 -12.590047) (xy 31.281593 -12.667836)
			(xy 31.235846 -12.74172) (xy 31.183477 -12.811067) (xy 31.124933 -12.875287) (xy 31.060713 -12.933831)
			(xy 30.991366 -12.9862) (xy 30.917482 -13.031947) (xy 30.839693 -13.070681) (xy 30.758661 -13.102073)
			(xy 30.675079 -13.125854) (xy 30.589659 -13.141822) (xy 30.50313 -13.14984) (xy 30.41623 -13.14984)
			(xy 30.329701 -13.141822) (xy 30.244281 -13.125854) (xy 30.160699 -13.102073) (xy 30.079667 -13.070681)
			(xy 30.001878 -13.031947) (xy 29.927994 -12.9862) (xy 29.858647 -12.933831) (xy 29.794427 -12.875287)
			(xy 29.735883 -12.811067) (xy 29.683514 -12.74172) (xy 29.637767 -12.667836) (xy 29.599033 -12.590047)
			(xy 29.567641 -12.509015) (xy 29.54386 -12.425433) (xy 29.527892 -12.340013) (xy 29.519874 -12.253484)
			(xy 26.295664 -12.253484) (xy 26.337233 -12.288078) (xy 26.37445 -12.329615) (xy 26.405223 -12.376128)
			(xy 26.428895 -12.426625) (xy 26.444963 -12.480032) (xy 26.453083 -12.535208) (xy 26.453592 -12.563094)
			(xy 26.453083 -12.59098) (xy 26.444963 -12.646156) (xy 26.436558 -12.674092) (xy 26.898852 -12.674092)
			(xy 26.902923 -12.61847) (xy 26.915049 -12.564033) (xy 26.934972 -12.511942) (xy 26.962268 -12.463307)
			(xy 26.996354 -12.419164) (xy 27.036503 -12.380455) (xy 27.081861 -12.348004) (xy 27.131461 -12.322503)
			(xy 27.184245 -12.304496) (xy 27.239088 -12.294366) (xy 27.294822 -12.292329) (xy 27.350259 -12.298429)
			(xy 27.404216 -12.312535) (xy 27.455545 -12.334347) (xy 27.503151 -12.363401) (xy 27.546019 -12.399076)
			(xy 27.583236 -12.440613) (xy 27.614009 -12.487126) (xy 27.637681 -12.537623) (xy 27.653749 -12.59103)
			(xy 27.661869 -12.646206) (xy 27.662378 -12.674092) (xy 27.661869 -12.701978) (xy 27.653749 -12.757154)
			(xy 27.637681 -12.810561) (xy 27.614009 -12.861058) (xy 27.583236 -12.907571) (xy 27.546019 -12.949108)
			(xy 27.503151 -12.984783) (xy 27.455545 -13.013837) (xy 27.404216 -13.035649) (xy 27.350259 -13.049755)
			(xy 27.294822 -13.055855) (xy 27.239088 -13.053818) (xy 27.184245 -13.043688) (xy 27.131461 -13.025681)
			(xy 27.081861 -13.00018) (xy 27.036503 -12.967729) (xy 26.996354 -12.92902) (xy 26.962268 -12.884877)
			(xy 26.934972 -12.836242) (xy 26.915049 -12.784151) (xy 26.902923 -12.729714) (xy 26.898852 -12.674092)
			(xy 26.436558 -12.674092) (xy 26.428895 -12.699563) (xy 26.405223 -12.75006) (xy 26.37445 -12.796573)
			(xy 26.337233 -12.83811) (xy 26.294365 -12.873785) (xy 26.246759 -12.902839) (xy 26.19543 -12.924651)
			(xy 26.141473 -12.938757) (xy 26.086036 -12.944857) (xy 26.030302 -12.94282) (xy 25.975459 -12.93269)
			(xy 25.922675 -12.914683) (xy 25.873075 -12.889182) (xy 25.827717 -12.856731) (xy 25.787568 -12.818022)
			(xy 25.753482 -12.773879) (xy 25.726186 -12.725244) (xy 25.706263 -12.673153) (xy 25.694137 -12.618716)
			(xy 25.690066 -12.563094) (xy 12.842094 -12.563094) (xy 11.659362 -13.745972) (xy 11.401044 -14.00429)
			(xy 11.401044 -15.228062) (xy 12.580624 -15.228062) (xy 12.584655 -15.098496) (xy 12.596734 -14.969432)
			(xy 12.616813 -14.841368) (xy 12.644815 -14.714801) (xy 12.680632 -14.590218) (xy 12.724124 -14.468104)
			(xy 12.775124 -14.34893) (xy 12.833435 -14.233157) (xy 12.89883 -14.121233) (xy 12.971057 -14.013591)
			(xy 13.049837 -13.910648) (xy 13.134864 -13.812802) (xy 13.225809 -13.72043) (xy 13.322321 -13.633892)
			(xy 13.424027 -13.553521) (xy 13.530533 -13.479629) (xy 13.641426 -13.412501) (xy 13.756278 -13.352397)
			(xy 13.874645 -13.29955) (xy 13.996068 -13.254163) (xy 14.120078 -13.216414) (xy 14.246195 -13.186447)
			(xy 14.373931 -13.164378) (xy 14.502792 -13.150294) (xy 14.632279 -13.144248) (xy 14.761892 -13.146264)
			(xy 14.891128 -13.156334) (xy 15.019489 -13.174419) (xy 15.146477 -13.200449) (xy 15.271601 -13.234324)
			(xy 15.394377 -13.275912) (xy 15.51433 -13.325053) (xy 15.630995 -13.381556) (xy 15.743923 -13.445203)
			(xy 15.852675 -13.515747) (xy 15.956831 -13.592916) (xy 16.055988 -13.676411) (xy 16.149762 -13.765909)
			(xy 16.237791 -13.861064) (xy 16.319734 -13.961507) (xy 16.395273 -14.06685) (xy 16.464118 -14.176686)
			(xy 16.526001 -14.29059) (xy 16.580682 -14.40812) (xy 16.627952 -14.528823) (xy 16.667625 -14.652231)
			(xy 16.69955 -14.777867) (xy 16.70288 -14.7955) (xy 27.317698 -14.7955) (xy 27.321769 -14.739878)
			(xy 27.333895 -14.685441) (xy 27.353818 -14.63335) (xy 27.381114 -14.584715) (xy 27.4152 -14.540572)
			(xy 27.455349 -14.501863) (xy 27.500707 -14.469412) (xy 27.550307 -14.443911) (xy 27.603091 -14.425904)
			(xy 27.657934 -14.415774) (xy 27.713668 -14.413737) (xy 27.769105 -14.419837) (xy 27.823062 -14.433943)
			(xy 27.874391 -14.455755) (xy 27.921997 -14.484809) (xy 27.964865 -14.520484) (xy 28.002082 -14.562021)
			(xy 28.032855 -14.608534) (xy 28.056527 -14.659031) (xy 28.072595 -14.712438) (xy 28.080715 -14.767614)
			(xy 28.081187 -14.793484) (xy 29.519874 -14.793484) (xy 29.519874 -14.706584) (xy 29.527892 -14.620055)
			(xy 29.54386 -14.534635) (xy 29.567641 -14.451053) (xy 29.599033 -14.370021) (xy 29.637767 -14.292232)
			(xy 29.683514 -14.218348) (xy 29.735883 -14.149001) (xy 29.794427 -14.084781) (xy 29.858647 -14.026237)
			(xy 29.927994 -13.973868) (xy 30.001878 -13.928121) (xy 30.079667 -13.889387) (xy 30.160699 -13.857995)
			(xy 30.244281 -13.834214) (xy 30.329701 -13.818246) (xy 30.41623 -13.810228) (xy 30.50313 -13.810228)
			(xy 30.589659 -13.818246) (xy 30.675079 -13.834214) (xy 30.758661 -13.857995) (xy 30.839693 -13.889387)
			(xy 30.917482 -13.928121) (xy 30.991366 -13.973868) (xy 31.060713 -14.026237) (xy 31.124933 -14.084781)
			(xy 31.183477 -14.149001) (xy 31.235846 -14.218348) (xy 31.281593 -14.292232) (xy 31.320327 -14.370021)
			(xy 31.351719 -14.451053) (xy 31.3755 -14.534635) (xy 31.391468 -14.620055) (xy 31.399486 -14.706584)
			(xy 31.399988 -14.750034) (xy 31.399486 -14.793484) (xy 31.391468 -14.880013) (xy 31.3755 -14.965433)
			(xy 31.351719 -15.049015) (xy 31.320327 -15.130047) (xy 31.281593 -15.207836) (xy 31.235846 -15.28172)
			(xy 31.183477 -15.351067) (xy 31.124933 -15.415287) (xy 31.060713 -15.473831) (xy 30.991366 -15.5262)
			(xy 30.917482 -15.571947) (xy 30.839693 -15.610681) (xy 30.758661 -15.642073) (xy 30.675079 -15.665854)
			(xy 30.589659 -15.681822) (xy 30.50313 -15.68984) (xy 30.41623 -15.68984) (xy 30.329701 -15.681822)
			(xy 30.244281 -15.665854) (xy 30.160699 -15.642073) (xy 30.079667 -15.610681) (xy 30.001878 -15.571947)
			(xy 29.927994 -15.5262) (xy 29.858647 -15.473831) (xy 29.794427 -15.415287) (xy 29.735883 -15.351067)
			(xy 29.683514 -15.28172) (xy 29.637767 -15.207836) (xy 29.599033 -15.130047) (xy 29.567641 -15.049015)
			(xy 29.54386 -14.965433) (xy 29.527892 -14.880013) (xy 29.519874 -14.793484) (xy 28.081187 -14.793484)
			(xy 28.081224 -14.7955) (xy 28.080715 -14.823386) (xy 28.072595 -14.878562) (xy 28.056527 -14.931969)
			(xy 28.032855 -14.982466) (xy 28.002082 -15.028979) (xy 27.964865 -15.070516) (xy 27.921997 -15.106191)
			(xy 27.874391 -15.135245) (xy 27.823062 -15.157057) (xy 27.769105 -15.171163) (xy 27.713668 -15.177263)
			(xy 27.657934 -15.175226) (xy 27.603091 -15.165096) (xy 27.550307 -15.147089) (xy 27.500707 -15.121588)
			(xy 27.455349 -15.089137) (xy 27.4152 -15.050428) (xy 27.381114 -15.006285) (xy 27.353818 -14.95765)
			(xy 27.333895 -14.905559) (xy 27.321769 -14.851122) (xy 27.317698 -14.7955) (xy 16.70288 -14.7955)
			(xy 16.723602 -14.905244) (xy 16.739689 -15.03387) (xy 16.747748 -15.163248) (xy 16.748252 -15.228062)
			(xy 16.747748 -15.292876) (xy 16.739689 -15.422254) (xy 16.723602 -15.55088) (xy 16.69955 -15.678257)
			(xy 16.667625 -15.803893) (xy 16.661668 -15.822422) (xy 26.122882 -15.822422) (xy 26.126953 -15.7668)
			(xy 26.139079 -15.712363) (xy 26.159002 -15.660272) (xy 26.186298 -15.611637) (xy 26.220384 -15.567494)
			(xy 26.260533 -15.528785) (xy 26.305891 -15.496334) (xy 26.355491 -15.470833) (xy 26.408275 -15.452826)
			(xy 26.463118 -15.442696) (xy 26.518852 -15.440659) (xy 26.574289 -15.446759) (xy 26.628246 -15.460865)
			(xy 26.679575 -15.482677) (xy 26.727181 -15.511731) (xy 26.770049 -15.547406) (xy 26.807266 -15.588943)
			(xy 26.838039 -15.635456) (xy 26.861711 -15.685953) (xy 26.877779 -15.73936) (xy 26.885899 -15.794536)
			(xy 26.886408 -15.822422) (xy 26.885899 -15.850308) (xy 26.877779 -15.905484) (xy 26.861711 -15.958891)
			(xy 26.838039 -16.009388) (xy 26.807266 -16.055901) (xy 26.770049 -16.097438) (xy 26.727181 -16.133113)
			(xy 26.679575 -16.162167) (xy 26.628246 -16.183979) (xy 26.574289 -16.198085) (xy 26.518852 -16.204185)
			(xy 26.463118 -16.202148) (xy 26.408275 -16.192018) (xy 26.355491 -16.174011) (xy 26.305891 -16.14851)
			(xy 26.260533 -16.116059) (xy 26.220384 -16.07735) (xy 26.186298 -16.033207) (xy 26.159002 -15.984572)
			(xy 26.139079 -15.932481) (xy 26.126953 -15.878044) (xy 26.122882 -15.822422) (xy 16.661668 -15.822422)
			(xy 16.627952 -15.927301) (xy 16.580682 -16.048004) (xy 16.526001 -16.165534) (xy 16.464118 -16.279438)
			(xy 16.395273 -16.389274) (xy 16.319734 -16.494617) (xy 16.237791 -16.59506) (xy 16.149762 -16.690215)
			(xy 16.055988 -16.779713) (xy 15.956831 -16.863208) (xy 15.852675 -16.940377) (xy 15.743923 -17.010921)
			(xy 15.630995 -17.074568) (xy 15.51433 -17.131071) (xy 15.394377 -17.180212) (xy 15.271601 -17.2218)
			(xy 15.146477 -17.255675) (xy 15.019489 -17.281705) (xy 14.891128 -17.29979) (xy 14.761892 -17.30986)
			(xy 14.632279 -17.311876) (xy 14.502792 -17.30583) (xy 14.373931 -17.291746) (xy 14.246195 -17.269677)
			(xy 14.120078 -17.23971) (xy 13.996068 -17.201961) (xy 13.874645 -17.156574) (xy 13.756278 -17.103727)
			(xy 13.641426 -17.043623) (xy 13.530533 -16.976495) (xy 13.424027 -16.902603) (xy 13.322321 -16.822232)
			(xy 13.225809 -16.735694) (xy 13.134864 -16.643322) (xy 13.049837 -16.545476) (xy 12.971057 -16.442533)
			(xy 12.89883 -16.334891) (xy 12.833435 -16.222967) (xy 12.775124 -16.107194) (xy 12.724124 -15.98802)
			(xy 12.680632 -15.865906) (xy 12.644815 -15.741323) (xy 12.616813 -15.614756) (xy 12.596734 -15.486692)
			(xy 12.584655 -15.357628) (xy 12.580624 -15.228062) (xy 11.401044 -15.228062) (xy 11.401044 -18.349976)
			(xy 26.862784 -18.349976) (xy 26.866855 -18.294354) (xy 26.878981 -18.239917) (xy 26.898904 -18.187826)
			(xy 26.9262 -18.139191) (xy 26.960286 -18.095048) (xy 27.000435 -18.056339) (xy 27.045793 -18.023888)
			(xy 27.095393 -17.998387) (xy 27.148177 -17.98038) (xy 27.20302 -17.97025) (xy 27.258754 -17.968213)
			(xy 27.314191 -17.974313) (xy 27.368148 -17.988419) (xy 27.419477 -18.010231) (xy 27.467083 -18.039285)
			(xy 27.509951 -18.07496) (xy 27.547168 -18.116497) (xy 27.577941 -18.16301) (xy 27.601613 -18.213507)
			(xy 27.617681 -18.266914) (xy 27.625801 -18.32209) (xy 27.62631 -18.349976) (xy 27.625801 -18.377862)
			(xy 27.617681 -18.433038) (xy 27.601613 -18.486445) (xy 27.577941 -18.536942) (xy 27.547168 -18.583455)
			(xy 27.509951 -18.624992) (xy 27.467083 -18.660667) (xy 27.419477 -18.689721) (xy 27.368148 -18.711533)
			(xy 27.314191 -18.725639) (xy 27.258754 -18.731739) (xy 27.20302 -18.729702) (xy 27.148177 -18.719572)
			(xy 27.095393 -18.701565) (xy 27.045793 -18.676064) (xy 27.000435 -18.643613) (xy 26.960286 -18.604904)
			(xy 26.9262 -18.560761) (xy 26.898904 -18.512126) (xy 26.878981 -18.460035) (xy 26.866855 -18.405598)
			(xy 26.862784 -18.349976) (xy 11.401044 -18.349976) (xy 11.401044 -20.969478) (xy 26.063446 -20.969478)
			(xy 26.067517 -20.913856) (xy 26.079643 -20.859419) (xy 26.099566 -20.807328) (xy 26.126862 -20.758693)
			(xy 26.160948 -20.71455) (xy 26.201097 -20.675841) (xy 26.246455 -20.64339) (xy 26.296055 -20.617889)
			(xy 26.348839 -20.599882) (xy 26.403682 -20.589752) (xy 26.459416 -20.587715) (xy 26.514853 -20.593815)
			(xy 26.56881 -20.607921) (xy 26.620139 -20.629733) (xy 26.667745 -20.658787) (xy 26.710613 -20.694462)
			(xy 26.74783 -20.735999) (xy 26.778603 -20.782512) (xy 26.802275 -20.833009) (xy 26.818343 -20.886416)
			(xy 26.826463 -20.941592) (xy 26.826972 -20.969478) (xy 26.826463 -20.997364) (xy 26.818343 -21.05254)
			(xy 26.802275 -21.105947) (xy 26.778603 -21.156444) (xy 26.74783 -21.202957) (xy 26.710613 -21.244494)
			(xy 26.667745 -21.280169) (xy 26.620139 -21.309223) (xy 26.56881 -21.331035) (xy 26.514853 -21.345141)
			(xy 26.459416 -21.351241) (xy 26.403682 -21.349204) (xy 26.348839 -21.339074) (xy 26.296055 -21.321067)
			(xy 26.246455 -21.295566) (xy 26.201097 -21.263115) (xy 26.160948 -21.224406) (xy 26.126862 -21.180263)
			(xy 26.099566 -21.131628) (xy 26.079643 -21.079537) (xy 26.067517 -21.0251) (xy 26.063446 -20.969478)
			(xy 11.401044 -20.969478) (xy 11.401044 -26.772362) (xy 11.401546 -26.795107) (xy 11.409639 -26.839871)
			(xy 11.425572 -26.882478) (xy 11.448837 -26.921568) (xy 11.47869 -26.955892) (xy 11.514177 -26.984351)
			(xy 11.554164 -27.006038) (xy 11.597374 -27.020258) (xy 11.642425 -27.026558) (xy 11.687878 -27.024736)
			(xy 11.73228 -27.01485) (xy 11.774213 -26.997217) (xy 11.812336 -26.972399) (xy 11.845432 -26.941191)
			(xy 11.872441 -26.904588) (xy 11.882882 -26.884376) (xy 11.927809 -26.793948) (xy 12.023697 -26.616218)
			(xy 12.126342 -26.442305) (xy 12.235593 -26.272463) (xy 12.351289 -26.106943) (xy 12.473259 -25.945991)
			(xy 12.601322 -25.789844) (xy 12.735289 -25.638732) (xy 12.874964 -25.492879) (xy 13.020138 -25.3525)
			(xy 13.170599 -25.217802) (xy 13.326124 -25.088983) (xy 13.486483 -24.966236) (xy 13.65144 -24.849739)
			(xy 13.820751 -24.739666) (xy 13.994165 -24.63618) (xy 14.171428 -24.539432) (xy 14.352276 -24.449566)
			(xy 14.536444 -24.366714) (xy 14.723658 -24.290999) (xy 14.913644 -24.222533) (xy 15.106119 -24.161416)
			(xy 15.300801 -24.107739) (xy 15.497401 -24.061582) (xy 15.695629 -24.023012) (xy 15.895193 -23.992086)
			(xy 16.095798 -23.96885) (xy 16.297147 -23.953338) (xy 16.498943 -23.945574) (xy 16.599916 -23.945088)
			(xy 16.703096 -23.945588) (xy 16.909298 -23.953689) (xy 17.115022 -23.96988) (xy 17.319953 -23.994135)
			(xy 17.523773 -24.026417) (xy 17.726168 -24.066676) (xy 17.926827 -24.11485) (xy 18.12544 -24.170864)
			(xy 18.3217 -24.234633) (xy 18.515306 -24.306058) (xy 18.705959 -24.385028) (xy 18.893364 -24.471423)
			(xy 19.077232 -24.565109) (xy 19.257281 -24.665941) (xy 19.433233 -24.773764) (xy 19.604815 -24.888412)
			(xy 19.771765 -25.009707) (xy 19.933823 -25.137464) (xy 20.090741 -25.271484) (xy 20.242276 -25.411562)
			(xy 20.388195 -25.557481) (xy 20.528273 -25.709016) (xy 20.662294 -25.865934) (xy 20.79005 -26.027992)
			(xy 20.911346 -26.194941) (xy 21.025994 -26.366524) (xy 21.133817 -26.542475) (xy 21.234649 -26.722524)
			(xy 21.328335 -26.906393) (xy 21.41473 -27.093798) (xy 21.493701 -27.28445) (xy 21.565126 -27.478056)
			(xy 21.628895 -27.674316) (xy 21.684909 -27.872929) (xy 21.733083 -28.073588) (xy 21.773342 -28.275984)
			(xy 21.805624 -28.479803) (xy 21.829879 -28.684734) (xy 21.84607 -28.890458) (xy 21.854172 -29.09666)
			(xy 21.854668 -29.19984) (xy 21.854164 -29.302868) (xy 21.846086 -29.508765) (xy 21.829943 -29.714187)
			(xy 21.805759 -29.918819) (xy 21.773572 -30.122345) (xy 21.733431 -30.324453) (xy 21.685397 -30.524832)
			(xy 21.629546 -30.723174) (xy 21.565962 -30.919174) (xy 21.494744 -31.112531) (xy 21.416 -31.302947)
			(xy 21.329852 -31.49013) (xy 21.236433 -31.673792) (xy 21.135885 -31.85365) (xy 21.028364 -32.029429)
			(xy 20.914035 -32.200858) (xy 20.793074 -32.367673) (xy 20.665666 -32.529617) (xy 20.532007 -32.686443)
			(xy 20.392303 -32.837909) (xy 20.246769 -32.983781) (xy 20.095629 -33.123836) (xy 19.939114 -33.257859)
			(xy 19.777466 -33.385643) (xy 19.610932 -33.506991) (xy 19.43977 -33.621719) (xy 19.264241 -33.729648)
			(xy 19.084617 -33.830613) (xy 18.901172 -33.924459) (xy 18.71419 -34.011041) (xy 18.523957 -34.090227)
			(xy 18.330766 -34.161894) (xy 18.134915 -34.225933) (xy 17.936703 -34.282245) (xy 17.736436 -34.330744)
			(xy 17.534422 -34.371354) (xy 17.330971 -34.404014) (xy 17.126396 -34.428674) (xy 16.921012 -34.445294)
			(xy 16.715134 -34.453851) (xy 16.612108 -34.454592) (xy 16.6116 -34.454592) (xy 16.599408 -34.454338)
			(xy 16.498186 -34.453847) (xy 16.295894 -34.446042) (xy 16.094052 -34.430451) (xy 15.892961 -34.407096)
			(xy 15.692918 -34.376013) (xy 15.494221 -34.337247) (xy 15.297165 -34.290857) (xy 15.102042 -34.236911)
			(xy 14.909142 -34.175489) (xy 14.71875 -34.106682) (xy 14.531151 -34.030593) (xy 14.346621 -33.947334)
			(xy 14.165435 -33.857029) (xy 13.987863 -33.759812) (xy 13.814167 -33.655827) (xy 13.644605 -33.545229)
			(xy 13.479429 -33.428182) (xy 13.318884 -33.304859) (xy 13.163208 -33.175444) (xy 13.087604 -33.108138)
			(xy 13.013194 -33.040628) (xy 12.868977 -32.900705) (xy 12.730216 -32.755371) (xy 12.597112 -32.604838)
			(xy 12.469861 -32.449326) (xy 12.348648 -32.289063) (xy 12.23365 -32.124283) (xy 12.125037 -31.955227)
			(xy 12.022965 -31.782142) (xy 11.927586 -31.605282) (xy 11.882882 -31.515304) (xy 11.872398 -31.495131)
			(xy 11.845395 -31.458562) (xy 11.812317 -31.42738) (xy 11.774219 -31.402581) (xy 11.732317 -31.384956)
			(xy 11.687947 -31.375068) (xy 11.642526 -31.373232) (xy 11.597503 -31.379507) (xy 11.554315 -31.393692)
			(xy 11.514339 -31.415335) (xy 11.478853 -31.443746) (xy 11.448987 -31.478017) (xy 11.425695 -31.517054)
			(xy 11.409721 -31.559613) (xy 11.401574 -31.604336) (xy 11.401044 -31.627064) (xy 11.401044 -32.587438)
			(xy 18.837656 -40.024304) (xy 18.837656 -61.028072) (xy 14.067282 -65.7987) (xy 14.051544 -65.815166)
			(xy 14.025605 -65.852601) (xy 14.006751 -65.89406) (xy 13.995586 -65.938214) (xy 13.992467 -65.983651)
			(xy 13.997493 -66.028917) (xy 14.010504 -66.072562) (xy 14.031083 -66.113192) (xy 14.058572 -66.149504)
			(xy 14.092091 -66.180338) (xy 14.130568 -66.204706) (xy 14.172771 -66.221828) (xy 14.217349 -66.231157)
			(xy 14.262876 -66.232394) (xy 14.285468 -66.229484) (xy 14.34913 -66.218207) (xy 14.477488 -66.202603)
			(xy 14.606566 -66.19499) (xy 14.735868 -66.195396) (xy 14.864896 -66.203821) (xy 14.993153 -66.220232)
			(xy 15.120145 -66.244565) (xy 15.245384 -66.276728) (xy 15.368387 -66.316596) (xy 15.48868 -66.364015)
			(xy 15.605801 -66.418804) (xy 15.719299 -66.480751) (xy 15.828736 -66.549617) (xy 15.933692 -66.625139)
			(xy 16.033762 -66.707024) (xy 16.128561 -66.794957) (xy 16.217724 -66.888601) (xy 16.300907 -66.987594)
			(xy 16.377791 -67.091556) (xy 16.448079 -67.200086) (xy 16.511502 -67.312766) (xy 16.567813 -67.429162)
			(xy 16.616798 -67.548827) (xy 16.658267 -67.671299) (xy 16.69206 -67.796108) (xy 16.718048 -67.922772)
			(xy 16.736131 -68.050804) (xy 16.746238 -68.179711) (xy 16.748331 -68.308996) (xy 16.742402 -68.438163)
			(xy 16.728473 -68.566713) (xy 16.706599 -68.694152) (xy 16.676864 -68.819989) (xy 16.65859 -68.882006)
			(xy 16.639151 -68.944409) (xy 16.593481 -69.066889) (xy 16.540222 -69.186265) (xy 16.479584 -69.302066)
			(xy 16.411805 -69.413839) (xy 16.337153 -69.521142) (xy 16.25592 -69.623554) (xy 16.168426 -69.720672)
			(xy 16.075016 -69.812114) (xy 15.976056 -69.897519) (xy 15.871937 -69.976553) (xy 15.763068 -70.048903)
			(xy 15.649877 -70.114286) (xy 15.53281 -70.172444) (xy 15.412327 -70.223148) (xy 15.288902 -70.266198)
			(xy 15.163022 -70.301427) (xy 15.03518 -70.328694) (xy 14.90588 -70.347892) (xy 14.775631 -70.358947)
			(xy 14.644945 -70.361814) (xy 14.514336 -70.356482) (xy 14.384318 -70.342973) (xy 14.255404 -70.321339)
			(xy 14.128099 -70.291665) (xy 14.002905 -70.254069) (xy 13.880314 -70.208698) (xy 13.760809 -70.15573)
			(xy 13.64486 -70.095375) (xy 13.532922 -70.027868) (xy 13.425437 -69.953477) (xy 13.322827 -69.872494)
			(xy 13.225497 -69.785237) (xy 13.179298 -69.739002) (xy 13.162935 -69.723101) (xy 13.125648 -69.696816)
			(xy 13.084268 -69.677608) (xy 13.040124 -69.666093) (xy 12.994634 -69.662643) (xy 12.949259 -69.667366)
			(xy 12.905455 -69.680112) (xy 12.864629 -69.700472) (xy 12.828092 -69.727791) (xy 12.797018 -69.761193)
			(xy 12.772405 -69.799604) (xy 12.755042 -69.841792) (xy 12.745487 -69.886401) (xy 12.744196 -69.909182)
			(xy 12.744196 -97.640648) (xy 12.745374 -97.663452) (xy 12.754897 -97.708106) (xy 12.772243 -97.750342)
			(xy 12.796855 -97.788799) (xy 12.827941 -97.822241) (xy 12.864501 -97.849592) (xy 12.905359 -97.869972)
			(xy 12.9492 -97.882725) (xy 12.994614 -97.887442) (xy 13.04014 -97.883971) (xy 13.084314 -97.872423)
			(xy 13.125715 -97.853169) (xy 13.16301 -97.826829) (xy 13.179298 -97.810828) (xy 13.226145 -97.763951)
			(xy 13.324917 -97.675568) (xy 13.429108 -97.593643) (xy 13.538295 -97.518506) (xy 13.652037 -97.45046)
			(xy 13.769874 -97.389782) (xy 13.89133 -97.336717) (xy 14.015913 -97.291478) (xy 14.143119 -97.25425)
			(xy 14.272435 -97.225182) (xy 14.403336 -97.204393) (xy 14.535295 -97.191966) (xy 14.667776 -97.187952)
			(xy 14.800245 -97.192366) (xy 14.932165 -97.205191) (xy 15.063003 -97.226376) (xy 15.127732 -97.240598)
			(xy 15.189628 -97.255183) (xy 15.311676 -97.290936) (xy 15.431316 -97.334068) (xy 15.548102 -97.38442)
			(xy 15.661598 -97.441804) (xy 15.771381 -97.506005) (xy 15.877043 -97.576785) (xy 15.97819 -97.653879)
			(xy 16.074444 -97.737001) (xy 16.165448 -97.825841) (xy 16.250862 -97.920067) (xy 16.330367 -98.01933)
			(xy 16.403669 -98.123258) (xy 16.470493 -98.231465) (xy 16.53059 -98.343547) (xy 16.583738 -98.459088)
			(xy 16.629737 -98.577655) (xy 16.668416 -98.698809) (xy 16.699631 -98.822096) (xy 16.71193 -98.884486)
			(xy 16.723527 -98.948465) (xy 16.739687 -99.077497) (xy 16.747768 -99.207286) (xy 16.747739 -99.337326)
			(xy 16.7396 -99.467111) (xy 16.723382 -99.596135) (xy 16.699149 -99.723897) (xy 16.666995 -99.849899)
			(xy 16.627045 -99.97365) (xy 16.579454 -100.094669) (xy 16.524409 -100.212484) (xy 16.462123 -100.326637)
			(xy 16.392839 -100.436683) (xy 16.316827 -100.542194) (xy 16.234382 -100.642758) (xy 16.145826 -100.737985)
			(xy 16.051503 -100.827504) (xy 15.951781 -100.910965) (xy 15.847047 -100.988045) (xy 15.73771 -101.058442)
			(xy 15.624196 -101.121884) (xy 15.506946 -101.178122) (xy 15.386416 -101.226939) (xy 15.263077 -101.268143)
			(xy 15.137408 -101.301575) (xy 15.009898 -101.327103) (xy 14.881045 -101.34463) (xy 14.75135 -101.354087)
			(xy 14.621317 -101.355436) (xy 14.491453 -101.348673) (xy 14.362263 -101.333824) (xy 14.298168 -101.322886)
			(xy 14.275449 -101.319331) (xy 14.229468 -101.31952) (xy 14.184272 -101.327979) (xy 14.141336 -101.344431)
			(xy 14.10206 -101.36834) (xy 14.067727 -101.398925) (xy 14.039457 -101.435189) (xy 14.018173 -101.475947)
			(xy 14.004569 -101.519869) (xy 13.99909 -101.565522) (xy 14.001914 -101.611416) (xy 14.01295 -101.656053)
			(xy 14.031836 -101.697975) (xy 14.057957 -101.735816) (xy 14.073886 -101.7524) (xy 14.323568 -102.002082)
			(xy 16.308324 -103.987092) (xy 16.308324 -110.344204) (xy 11.140948 -115.511834) (xy 11.140948 -116.297202)
			(xy 11.141428 -116.31949) (xy 11.149238 -116.363376) (xy 11.164588 -116.405225) (xy 11.187006 -116.443754)
			(xy 11.215804 -116.477778) (xy 11.250099 -116.506253) (xy 11.288838 -116.528306) (xy 11.330831 -116.543259)
			(xy 11.374789 -116.550653) (xy 11.419363 -116.550261) (xy 11.463185 -116.542096) (xy 11.504909 -116.526408)
			(xy 11.543254 -116.503678) (xy 11.577043 -116.474604) (xy 11.60524 -116.44008) (xy 11.626978 -116.401164)
			(xy 11.634724 -116.38026) (xy 11.668433 -116.284412) (xy 11.742303 -116.09511) (xy 11.823436 -115.908806)
			(xy 11.911711 -115.725778) (xy 12.006996 -115.546299) (xy 12.109148 -115.370638) (xy 12.218015 -115.199057)
			(xy 12.333433 -115.031814) (xy 12.455231 -114.869158) (xy 12.583226 -114.711332) (xy 12.717227 -114.558572)
			(xy 12.857034 -114.411107) (xy 13.002437 -114.269157) (xy 13.153219 -114.132934) (xy 13.309154 -114.002643)
			(xy 13.470011 -113.878477) (xy 13.635547 -113.760623) (xy 13.805515 -113.649256) (xy 13.979662 -113.544544)
			(xy 14.157727 -113.446642) (xy 14.339444 -113.355698) (xy 14.524541 -113.271847) (xy 14.712741 -113.195214)
			(xy 14.903763 -113.125914) (xy 15.097321 -113.064051) (xy 15.293126 -113.009718) (xy 15.490885 -112.962994)
			(xy 15.690303 -112.923951) (xy 15.891081 -112.892647) (xy 16.092919 -112.869128) (xy 16.295516 -112.853429)
			(xy 16.498568 -112.845575) (xy 16.60017 -112.845088) (xy 16.70335 -112.845595) (xy 16.909551 -112.853696)
			(xy 17.115275 -112.869887) (xy 17.320205 -112.894142) (xy 17.524025 -112.926424) (xy 17.72642 -112.966683)
			(xy 17.927079 -113.014857) (xy 18.125691 -113.070871) (xy 18.321951 -113.13464) (xy 18.515557 -113.206065)
			(xy 18.706209 -113.285035) (xy 18.893613 -113.37143) (xy 19.077482 -113.465116) (xy 19.25753 -113.565948)
			(xy 19.433481 -113.673771) (xy 19.605064 -113.788418) (xy 19.772012 -113.909714) (xy 19.934071 -114.03747)
			(xy 20.090988 -114.171491) (xy 20.242523 -114.311568) (xy 20.388442 -114.457487) (xy 20.528519 -114.609022)
			(xy 20.66254 -114.765939) (xy 20.790296 -114.927998) (xy 20.911592 -115.094946) (xy 21.026239 -115.266529)
			(xy 21.134062 -115.44248) (xy 21.234894 -115.622528) (xy 21.32858 -115.806397) (xy 21.414975 -115.993801)
			(xy 21.493945 -116.184453) (xy 21.56537 -116.378059) (xy 21.629139 -116.574319) (xy 21.685153 -116.772931)
			(xy 21.733327 -116.97359) (xy 21.773586 -117.175985) (xy 21.805868 -117.379805) (xy 21.830123 -117.584735)
			(xy 21.846314 -117.790459) (xy 21.854415 -117.99666) (xy 21.854922 -118.09984) (xy 21.854423 -118.202319)
			(xy 21.846431 -118.40712) (xy 21.830459 -118.611454) (xy 21.806531 -118.81501) (xy 21.774685 -119.017478)
			(xy 21.734968 -119.21855) (xy 21.68744 -119.41792) (xy 21.632175 -119.615286) (xy 21.569256 -119.810347)
			(xy 21.498779 -120.002806) (xy 21.420851 -120.19237) (xy 21.33559 -120.378752) (xy 21.243127 -120.561667)
			(xy 21.143602 -120.740838) (xy 21.037166 -120.915991) (xy 20.923981 -121.086862) (xy 20.804219 -121.253189)
			(xy 20.678063 -121.414719) (xy 20.545704 -121.571208) (xy 20.407345 -121.722416) (xy 20.263194 -121.868114)
			(xy 20.113471 -122.008081) (xy 19.958405 -122.142103) (xy 19.798231 -122.269977) (xy 19.633192 -122.391508)
			(xy 19.463541 -122.506511) (xy 19.289533 -122.614811) (xy 19.111436 -122.716244) (xy 18.929518 -122.810655)
			(xy 18.744057 -122.897901) (xy 18.555336 -122.977849) (xy 18.363641 -123.050377) (xy 18.169263 -123.115376)
			(xy 17.972499 -123.172745) (xy 17.773647 -123.222399) (xy 17.57301 -123.264261) (xy 17.370894 -123.298268)
			(xy 17.167605 -123.324367) (xy 16.963454 -123.34252) (xy 16.758749 -123.352699) (xy 16.553804 -123.354888)
			(xy 16.348929 -123.349084) (xy 16.144436 -123.335296) (xy 15.940636 -123.313544) (xy 15.73784 -123.283862)
			(xy 15.536355 -123.246295) (xy 15.336488 -123.2009) (xy 15.138543 -123.147746) (xy 14.942821 -123.086915)
			(xy 14.749621 -123.018497) (xy 14.559235 -122.942599) (xy 14.371953 -122.859334) (xy 14.18806 -122.76883)
			(xy 14.007837 -122.671224) (xy 13.831556 -122.566665) (xy 13.659486 -122.455312) (xy 13.49189 -122.337334)
			(xy 13.329021 -122.21291) (xy 13.171127 -122.082231) (xy 13.018449 -121.945494) (xy 12.871219 -121.802908)
			(xy 12.729661 -121.654689) (xy 12.59399 -121.501064) (xy 12.464413 -121.342264) (xy 12.341126 -121.178534)
			(xy 12.224318 -121.01012) (xy 12.114165 -120.837279) (xy 12.010835 -120.660275) (xy 11.914486 -120.479377)
			(xy 11.825264 -120.294859) (xy 11.743305 -120.107002) (xy 11.668733 -119.916092) (xy 11.634724 -119.81942)
			(xy 11.626969 -119.798529) (xy 11.605219 -119.759642) (xy 11.577018 -119.725145) (xy 11.543232 -119.696097)
			(xy 11.504895 -119.673389) (xy 11.463185 -119.657717) (xy 11.419381 -119.649562) (xy 11.374825 -119.649175)
			(xy 11.330886 -119.656567) (xy 11.288909 -119.671511) (xy 11.250184 -119.693549) (xy 11.215897 -119.722006)
			(xy 11.187101 -119.756007) (xy 11.164678 -119.794511) (xy 11.149317 -119.836336) (xy 11.141488 -119.8802)
			(xy 11.140948 -119.902478) (xy 11.140948 -121.141236) (xy 21.265388 -131.26593) (xy 21.265388 -169.031412)
			(xy 21.266575 -169.053775) (xy 21.275822 -169.09759) (xy 21.292601 -169.139107) (xy 21.316392 -169.177044)
			(xy 21.346461 -169.210226) (xy 21.381878 -169.237629) (xy 21.421546 -169.258404) (xy 21.464241 -169.271909)
			(xy 21.508641 -169.277728) (xy 21.553374 -169.275679) (xy 21.597056 -169.265826) (xy 21.638337 -169.248474)
			(xy 21.67594 -169.224159) (xy 21.692616 -169.209212) (xy 22.460966 -168.440862) (xy 22.472359 -168.428731)
			(xy 22.489035 -168.399947) (xy 22.497707 -168.367832) (xy 22.498304 -168.3512) (xy 22.498304 -106.688636)
			(xy 21.530056 -105.720388) (xy 21.530056 -91.046808) (xy 23.522686 -89.053924) (xy 23.773384 -88.803226)
			(xy 23.773384 -25.68448) (xy 27.094688 -22.363176) (xy 27.110796 -22.346333) (xy 27.137194 -22.307933)
			(xy 27.156146 -22.265361) (xy 27.167017 -22.220048) (xy 27.169441 -22.173512) (xy 27.163337 -22.127314)
			(xy 27.14891 -22.083004) (xy 27.126645 -22.042069) (xy 27.097287 -22.00588) (xy 27.061822 -21.975653)
			(xy 27.041856 -21.963634) (xy 27.017824 -21.949242) (xy 26.973874 -21.914513) (xy 26.935475 -21.873731)
			(xy 26.90345 -21.827773) (xy 26.878489 -21.777627) (xy 26.861129 -21.72437) (xy 26.851742 -21.669147)
			(xy 26.85053 -21.613145) (xy 26.857518 -21.557568) (xy 26.872558 -21.503609) (xy 26.895326 -21.45243)
			(xy 26.925332 -21.40513) (xy 26.961931 -21.362724) (xy 27.004337 -21.326126) (xy 27.051638 -21.296122)
			(xy 27.102818 -21.273355) (xy 27.156776 -21.258317) (xy 27.212354 -21.251329) (xy 27.268356 -21.252543)
			(xy 27.323579 -21.261931) (xy 27.376835 -21.279293) (xy 27.426981 -21.304255) (xy 27.472938 -21.33628)
			(xy 27.513719 -21.374681) (xy 27.548447 -21.418631) (xy 27.56281 -21.44268) (xy 27.574898 -21.462591)
			(xy 27.60513 -21.49802) (xy 27.641312 -21.527347) (xy 27.682233 -21.549588) (xy 27.726521 -21.564)
			(xy 27.772695 -21.5701) (xy 27.819207 -21.567683) (xy 27.864499 -21.556831) (xy 27.907056 -21.537906)
			(xy 27.945451 -21.511543) (xy 27.962352 -21.495512) (xy 28.72867 -20.729194) (xy 28.739529 -20.717769)
			(xy 28.755763 -20.690762) (xy 28.764829 -20.660585) (xy 28.766008 -20.644866) (xy 28.766008 -18.53438)
			(xy 29.46146 -17.838674) (xy 29.547058 -17.753076) (xy 29.557585 -17.741939) (xy 29.573493 -17.715758)
			(xy 29.582689 -17.686535) (xy 29.584639 -17.655962) (xy 29.582364 -17.640808) (xy 29.578046 -17.61744)
			(xy 29.57449 -17.607534) (xy 29.560408 -17.566845) (xy 29.538865 -17.483474) (xy 29.525034 -17.398483)
			(xy 29.51903 -17.312584) (xy 29.520904 -17.226495) (xy 29.530641 -17.140938) (xy 29.548158 -17.05663)
			(xy 29.573309 -16.974276) (xy 29.605884 -16.894566) (xy 29.645609 -16.818168) (xy 29.692152 -16.745721)
			(xy 29.745123 -16.677832) (xy 29.804078 -16.615071) (xy 29.868524 -16.557961) (xy 29.937921 -16.506982)
			(xy 30.011688 -16.462561) (xy 30.089206 -16.42507) (xy 30.169828 -16.394822) (xy 30.252877 -16.372071)
			(xy 30.337658 -16.357007) (xy 30.423461 -16.349757) (xy 30.509568 -16.350381) (xy 30.595257 -16.358875)
			(xy 30.679811 -16.375166) (xy 30.762522 -16.399119) (xy 30.842696 -16.430533) (xy 30.919663 -16.469144)
			(xy 30.992778 -16.51463) (xy 31.061428 -16.56661) (xy 31.125039 -16.624648) (xy 31.183078 -16.688258)
			(xy 31.235059 -16.756907) (xy 31.280547 -16.830021) (xy 31.31916 -16.906988) (xy 31.350575 -16.987161)
			(xy 31.37453 -17.069871) (xy 31.390823 -17.154425) (xy 31.399318 -17.240114) (xy 31.399944 -17.326221)
			(xy 31.392695 -17.412024) (xy 31.377633 -17.496806) (xy 31.354884 -17.579855) (xy 31.324637 -17.660477)
			(xy 31.287147 -17.737997) (xy 31.242727 -17.811764) (xy 31.19175 -17.881162) (xy 31.134642 -17.945609)
			(xy 31.071881 -18.004566) (xy 31.003994 -18.057538) (xy 30.931548 -18.104082) (xy 30.85515 -18.143809)
			(xy 30.775441 -18.176385) (xy 30.693088 -18.201537) (xy 30.608779 -18.219056) (xy 30.523223 -18.228794)
			(xy 30.437134 -18.23067) (xy 30.351235 -18.224669) (xy 30.266243 -18.210839) (xy 30.182872 -18.189298)
			(xy 30.14218 -18.175224) (xy 30.132274 -18.171668) (xy 30.108906 -18.16735) (xy 30.093751 -18.165111)
			(xy 30.063189 -18.167077) (xy 30.033976 -18.176269) (xy 30.007795 -18.192157) (xy 29.996638 -18.202656)
			(xy 29.438854 -18.76044) (xy 29.427987 -18.771862) (xy 29.411737 -18.798866) (xy 29.402652 -18.829044)
			(xy 29.401516 -18.844768) (xy 29.401516 -18.955004) (xy 29.402685 -18.976984) (xy 29.411644 -19.020076)
			(xy 29.42789 -19.06098) (xy 29.450938 -19.098475) (xy 29.4801 -19.131441) (xy 29.514503 -19.158891)
			(xy 29.55312 -19.180007) (xy 29.594796 -19.194156) (xy 29.638287 -19.200916) (xy 29.682291 -19.200085)
			(xy 29.725496 -19.191688) (xy 29.766608 -19.175975) (xy 29.8044 -19.153417) (xy 29.821378 -19.139408)
			(xy 29.853574 -19.110327) (xy 29.922445 -19.057553) (xy 29.995884 -19.011347) (xy 30.073267 -18.972103)
			(xy 30.153936 -18.940154) (xy 30.237205 -18.915772) (xy 30.322366 -18.899163) (xy 30.408695 -18.89047)
			(xy 30.495458 -18.889767) (xy 30.581916 -18.897058) (xy 30.667336 -18.912283) (xy 30.750989 -18.935311)
			(xy 30.832166 -18.965948) (xy 30.910176 -19.003931) (xy 30.984354 -19.04894) (xy 31.054072 -19.10059)
			(xy 31.118735 -19.158442) (xy 31.177794 -19.222005) (xy 31.230747 -19.290738) (xy 31.277144 -19.364057)
			(xy 31.316589 -19.441337) (xy 31.348748 -19.521923) (xy 31.373347 -19.605129) (xy 31.390177 -19.690246)
			(xy 31.399094 -19.776552) (xy 31.400023 -19.863313) (xy 31.392957 -19.94979) (xy 31.377954 -20.035249)
			(xy 31.355143 -20.118962) (xy 31.324718 -20.200218) (xy 31.306262 -20.239482) (xy 31.296756 -20.260722)
			(xy 31.284788 -20.305686) (xy 31.281204 -20.352077) (xy 31.286126 -20.398345) (xy 31.299389 -20.442943)
			(xy 31.320548 -20.484383) (xy 31.348898 -20.521278) (xy 31.383491 -20.552395) (xy 31.423171 -20.576695)
			(xy 31.466611 -20.593366) (xy 31.51236 -20.60185) (xy 31.535624 -20.602448) (xy 32.203898 -20.602448)
			(xy 32.72028 -20.086066) (xy 32.72028 -17.116806) (xy 34.628074 -15.209012) (xy 34.638055 -15.198523)
			(xy 34.653423 -15.173992) (xy 34.662843 -15.146621) (xy 34.665828 -15.117828) (xy 34.662223 -15.089107)
			(xy 34.657538 -15.075408) (xy 34.642743 -15.033843) (xy 34.620102 -14.948565) (xy 34.605549 -14.861541)
			(xy 34.599213 -14.773536) (xy 34.601149 -14.685324) (xy 34.61134 -14.597682) (xy 34.629697 -14.51138)
			(xy 34.656058 -14.427177) (xy 34.690191 -14.345814) (xy 34.731797 -14.268007) (xy 34.780508 -14.194439)
			(xy 34.835898 -14.125759) (xy 34.897478 -14.062569) (xy 34.964706 -14.005426) (xy 35.036993 -13.954833)
			(xy 35.113701 -13.911233) (xy 35.194156 -13.875012) (xy 35.277651 -13.846487) (xy 35.36345 -13.82591)
			(xy 35.450801 -13.813461) (xy 35.538933 -13.80925) (xy 35.627072 -13.813314) (xy 35.714443 -13.825616)
			(xy 35.800277 -13.84605) (xy 35.883819 -13.874435) (xy 35.964335 -13.910522) (xy 36.041116 -13.953992)
			(xy 36.113487 -14.004465) (xy 36.180811 -14.061495) (xy 36.212018 -14.092682) (xy 36.242293 -14.12437)
			(xy 36.297465 -14.192471) (xy 36.34606 -14.26541) (xy 36.387658 -14.342555) (xy 36.417542 -14.412976)
			(xy 40.863518 -14.412976) (xy 40.867589 -14.357354) (xy 40.879715 -14.302917) (xy 40.899638 -14.250826)
			(xy 40.926934 -14.202191) (xy 40.96102 -14.158048) (xy 41.001169 -14.119339) (xy 41.046527 -14.086888)
			(xy 41.096127 -14.061387) (xy 41.148911 -14.04338) (xy 41.203754 -14.03325) (xy 41.259488 -14.031213)
			(xy 41.314925 -14.037313) (xy 41.368882 -14.051419) (xy 41.420211 -14.073231) (xy 41.467817 -14.102285)
			(xy 41.510685 -14.13796) (xy 41.547902 -14.179497) (xy 41.578675 -14.22601) (xy 41.602347 -14.276507)
			(xy 41.618415 -14.329914) (xy 41.626535 -14.38509) (xy 41.627044 -14.412976) (xy 41.626535 -14.440862)
			(xy 41.618415 -14.496038) (xy 41.613189 -14.513407) (xy 60.567562 -14.513407) (xy 60.567562 -14.442085)
			(xy 60.575548 -14.371211) (xy 60.591418 -14.301676) (xy 60.614975 -14.234356) (xy 60.64592 -14.170097)
			(xy 60.683866 -14.109706) (xy 60.728335 -14.053944) (xy 60.778768 -14.003511) (xy 60.83453 -13.959042)
			(xy 60.894921 -13.921096) (xy 60.95918 -13.890151) (xy 61.0265 -13.866594) (xy 61.096035 -13.850724)
			(xy 61.166909 -13.842738) (xy 61.238231 -13.842738) (xy 61.309105 -13.850724) (xy 61.37864 -13.866594)
			(xy 61.44596 -13.890151) (xy 61.510219 -13.921096) (xy 61.57061 -13.959042) (xy 61.626372 -14.003511)
			(xy 61.676805 -14.053944) (xy 61.721274 -14.109706) (xy 61.75922 -14.170097) (xy 61.790165 -14.234356)
			(xy 61.813722 -14.301676) (xy 61.829592 -14.371211) (xy 61.837578 -14.442085) (xy 61.838078 -14.477746)
			(xy 61.837578 -14.513407) (xy 62.471546 -14.513407) (xy 62.471546 -14.442085) (xy 62.479532 -14.371211)
			(xy 62.495402 -14.301676) (xy 62.518959 -14.234356) (xy 62.549904 -14.170097) (xy 62.58785 -14.109706)
			(xy 62.632319 -14.053944) (xy 62.682752 -14.003511) (xy 62.738514 -13.959042) (xy 62.798905 -13.921096)
			(xy 62.863164 -13.890151) (xy 62.930484 -13.866594) (xy 63.000019 -13.850724) (xy 63.070893 -13.842738)
			(xy 63.142215 -13.842738) (xy 63.213089 -13.850724) (xy 63.282624 -13.866594) (xy 63.349944 -13.890151)
			(xy 63.414203 -13.921096) (xy 63.474594 -13.959042) (xy 63.530356 -14.003511) (xy 63.580789 -14.053944)
			(xy 63.625258 -14.109706) (xy 63.663204 -14.170097) (xy 63.694149 -14.234356) (xy 63.717706 -14.301676)
			(xy 63.733576 -14.371211) (xy 63.741562 -14.442085) (xy 63.742062 -14.477746) (xy 63.741562 -14.513407)
			(xy 63.733576 -14.584281) (xy 63.717706 -14.653816) (xy 63.694149 -14.721136) (xy 63.663204 -14.785395)
			(xy 63.625258 -14.845786) (xy 63.580789 -14.901548) (xy 63.530356 -14.951981) (xy 63.474594 -14.99645)
			(xy 63.414203 -15.034396) (xy 63.349944 -15.065341) (xy 63.282624 -15.088898) (xy 63.213089 -15.104768)
			(xy 63.142215 -15.112754) (xy 63.070893 -15.112754) (xy 63.000019 -15.104768) (xy 62.930484 -15.088898)
			(xy 62.863164 -15.065341) (xy 62.798905 -15.034396) (xy 62.738514 -14.99645) (xy 62.682752 -14.951981)
			(xy 62.632319 -14.901548) (xy 62.58785 -14.845786) (xy 62.549904 -14.785395) (xy 62.518959 -14.721136)
			(xy 62.495402 -14.653816) (xy 62.479532 -14.584281) (xy 62.471546 -14.513407) (xy 61.837578 -14.513407)
			(xy 61.829592 -14.584281) (xy 61.813722 -14.653816) (xy 61.790165 -14.721136) (xy 61.75922 -14.785395)
			(xy 61.721274 -14.845786) (xy 61.676805 -14.901548) (xy 61.626372 -14.951981) (xy 61.57061 -14.99645)
			(xy 61.510219 -15.034396) (xy 61.44596 -15.065341) (xy 61.37864 -15.088898) (xy 61.309105 -15.104768)
			(xy 61.238231 -15.112754) (xy 61.166909 -15.112754) (xy 61.096035 -15.104768) (xy 61.0265 -15.088898)
			(xy 60.95918 -15.065341) (xy 60.894921 -15.034396) (xy 60.83453 -14.99645) (xy 60.778768 -14.951981)
			(xy 60.728335 -14.901548) (xy 60.683866 -14.845786) (xy 60.64592 -14.785395) (xy 60.614975 -14.721136)
			(xy 60.591418 -14.653816) (xy 60.575548 -14.584281) (xy 60.567562 -14.513407) (xy 41.613189 -14.513407)
			(xy 41.602347 -14.549445) (xy 41.578675 -14.599942) (xy 41.547902 -14.646455) (xy 41.510685 -14.687992)
			(xy 41.467817 -14.723667) (xy 41.420211 -14.752721) (xy 41.368882 -14.774533) (xy 41.314925 -14.788639)
			(xy 41.259488 -14.794739) (xy 41.203754 -14.792702) (xy 41.148911 -14.782572) (xy 41.096127 -14.764565)
			(xy 41.046527 -14.739064) (xy 41.001169 -14.706613) (xy 40.96102 -14.667904) (xy 40.926934 -14.623761)
			(xy 40.899638 -14.575126) (xy 40.879715 -14.523035) (xy 40.867589 -14.468598) (xy 40.863518 -14.412976)
			(xy 36.417542 -14.412976) (xy 36.421896 -14.423236) (xy 36.448478 -14.506752) (xy 36.467174 -14.59238)
			(xy 36.47782 -14.679376) (xy 36.480325 -14.766986) (xy 36.474666 -14.854448) (xy 36.460893 -14.941004)
			(xy 36.439126 -15.025903) (xy 36.409553 -15.108409) (xy 36.372431 -15.187804) (xy 36.328082 -15.263401)
			(xy 36.276891 -15.334542) (xy 36.219303 -15.400612) (xy 36.155816 -15.461036) (xy 36.086981 -15.51529)
			(xy 36.013397 -15.562904) (xy 35.935702 -15.603463) (xy 35.854569 -15.636617) (xy 35.770704 -15.662078)
			(xy 35.684833 -15.679623) (xy 35.597702 -15.689103) (xy 35.510067 -15.690433) (xy 35.422688 -15.683603)
			(xy 35.336324 -15.668671) (xy 35.251725 -15.645768) (xy 35.210496 -15.630906) (xy 35.175444 -15.617698)
			(xy 35.1028 -15.633446) (xy 33.402762 -17.333484) (xy 34.599874 -17.333484) (xy 34.599874 -17.246584)
			(xy 34.607892 -17.160055) (xy 34.62386 -17.074635) (xy 34.647641 -16.991053) (xy 34.679033 -16.910021)
			(xy 34.717767 -16.832232) (xy 34.763514 -16.758348) (xy 34.815883 -16.689001) (xy 34.874427 -16.624781)
			(xy 34.938647 -16.566237) (xy 35.007994 -16.513868) (xy 35.081878 -16.468121) (xy 35.159667 -16.429387)
			(xy 35.240699 -16.397995) (xy 35.324281 -16.374214) (xy 35.409701 -16.358246) (xy 35.49623 -16.350228)
			(xy 35.58313 -16.350228) (xy 35.669659 -16.358246) (xy 35.755079 -16.374214) (xy 35.838661 -16.397995)
			(xy 35.88086 -16.414343) (xy 60.567562 -16.414343) (xy 60.567562 -16.343021) (xy 60.575548 -16.272147)
			(xy 60.591418 -16.202612) (xy 60.614975 -16.135292) (xy 60.64592 -16.071033) (xy 60.683866 -16.010642)
			(xy 60.728335 -15.95488) (xy 60.778768 -15.904447) (xy 60.83453 -15.859978) (xy 60.894921 -15.822032)
			(xy 60.95918 -15.791087) (xy 61.0265 -15.76753) (xy 61.096035 -15.75166) (xy 61.166909 -15.743674)
			(xy 61.238231 -15.743674) (xy 61.309105 -15.75166) (xy 61.37864 -15.76753) (xy 61.44596 -15.791087)
			(xy 61.510219 -15.822032) (xy 61.57061 -15.859978) (xy 61.626372 -15.904447) (xy 61.676805 -15.95488)
			(xy 61.721274 -16.010642) (xy 61.75922 -16.071033) (xy 61.790165 -16.135292) (xy 61.813722 -16.202612)
			(xy 61.829592 -16.272147) (xy 61.837578 -16.343021) (xy 61.838078 -16.378682) (xy 61.837578 -16.414343)
			(xy 62.471546 -16.414343) (xy 62.471546 -16.343021) (xy 62.479532 -16.272147) (xy 62.495402 -16.202612)
			(xy 62.518959 -16.135292) (xy 62.549904 -16.071033) (xy 62.58785 -16.010642) (xy 62.632319 -15.95488)
			(xy 62.682752 -15.904447) (xy 62.738514 -15.859978) (xy 62.798905 -15.822032) (xy 62.863164 -15.791087)
			(xy 62.930484 -15.76753) (xy 63.000019 -15.75166) (xy 63.070893 -15.743674) (xy 63.142215 -15.743674)
			(xy 63.213089 -15.75166) (xy 63.282624 -15.76753) (xy 63.349944 -15.791087) (xy 63.414203 -15.822032)
			(xy 63.474594 -15.859978) (xy 63.530356 -15.904447) (xy 63.580789 -15.95488) (xy 63.625258 -16.010642)
			(xy 63.663204 -16.071033) (xy 63.694149 -16.135292) (xy 63.716656 -16.199612) (xy 75.73848 -16.199612)
			(xy 75.742551 -16.14399) (xy 75.754677 -16.089553) (xy 75.7746 -16.037462) (xy 75.801896 -15.988827)
			(xy 75.835982 -15.944684) (xy 75.876131 -15.905975) (xy 75.921489 -15.873524) (xy 75.971089 -15.848023)
			(xy 76.023873 -15.830016) (xy 76.078716 -15.819886) (xy 76.13445 -15.817849) (xy 76.189887 -15.823949)
			(xy 76.243844 -15.838055) (xy 76.295173 -15.859867) (xy 76.342779 -15.888921) (xy 76.385647 -15.924596)
			(xy 76.422864 -15.966133) (xy 76.453637 -16.012646) (xy 76.477309 -16.063143) (xy 76.493377 -16.11655)
			(xy 76.501497 -16.171726) (xy 76.502006 -16.199612) (xy 76.872336 -16.199612) (xy 76.876407 -16.14399)
			(xy 76.888533 -16.089553) (xy 76.908456 -16.037462) (xy 76.935752 -15.988827) (xy 76.969838 -15.944684)
			(xy 77.009987 -15.905975) (xy 77.055345 -15.873524) (xy 77.104945 -15.848023) (xy 77.157729 -15.830016)
			(xy 77.212572 -15.819886) (xy 77.268306 -15.817849) (xy 77.323743 -15.823949) (xy 77.3777 -15.838055)
			(xy 77.429029 -15.859867) (xy 77.476635 -15.888921) (xy 77.519503 -15.924596) (xy 77.55672 -15.966133)
			(xy 77.587493 -16.012646) (xy 77.611165 -16.063143) (xy 77.627233 -16.11655) (xy 77.635353 -16.171726)
			(xy 77.635862 -16.199612) (xy 78.015336 -16.199612) (xy 78.019407 -16.14399) (xy 78.031533 -16.089553)
			(xy 78.051456 -16.037462) (xy 78.078752 -15.988827) (xy 78.112838 -15.944684) (xy 78.152987 -15.905975)
			(xy 78.198345 -15.873524) (xy 78.247945 -15.848023) (xy 78.300729 -15.830016) (xy 78.355572 -15.819886)
			(xy 78.411306 -15.817849) (xy 78.466743 -15.823949) (xy 78.5207 -15.838055) (xy 78.572029 -15.859867)
			(xy 78.619635 -15.888921) (xy 78.662503 -15.924596) (xy 78.69972 -15.966133) (xy 78.730493 -16.012646)
			(xy 78.754165 -16.063143) (xy 78.770233 -16.11655) (xy 78.778353 -16.171726) (xy 78.778862 -16.199612)
			(xy 79.142588 -16.199612) (xy 79.146659 -16.14399) (xy 79.158785 -16.089553) (xy 79.178708 -16.037462)
			(xy 79.206004 -15.988827) (xy 79.24009 -15.944684) (xy 79.280239 -15.905975) (xy 79.325597 -15.873524)
			(xy 79.375197 -15.848023) (xy 79.427981 -15.830016) (xy 79.482824 -15.819886) (xy 79.538558 -15.817849)
			(xy 79.593995 -15.823949) (xy 79.647952 -15.838055) (xy 79.699281 -15.859867) (xy 79.746887 -15.888921)
			(xy 79.789755 -15.924596) (xy 79.826972 -15.966133) (xy 79.857745 -16.012646) (xy 79.881417 -16.063143)
			(xy 79.897485 -16.11655) (xy 79.905605 -16.171726) (xy 79.906114 -16.199612) (xy 80.28 -16.199612)
			(xy 80.284071 -16.14399) (xy 80.296197 -16.089553) (xy 80.31612 -16.037462) (xy 80.343416 -15.988827)
			(xy 80.377502 -15.944684) (xy 80.417651 -15.905975) (xy 80.463009 -15.873524) (xy 80.512609 -15.848023)
			(xy 80.565393 -15.830016) (xy 80.620236 -15.819886) (xy 80.67597 -15.817849) (xy 80.731407 -15.823949)
			(xy 80.785364 -15.838055) (xy 80.836693 -15.859867) (xy 80.884299 -15.888921) (xy 80.927167 -15.924596)
			(xy 80.964384 -15.966133) (xy 80.995157 -16.012646) (xy 81.018829 -16.063143) (xy 81.034897 -16.11655)
			(xy 81.043017 -16.171726) (xy 81.043526 -16.199612) (xy 81.407252 -16.199612) (xy 81.411323 -16.14399)
			(xy 81.423449 -16.089553) (xy 81.443372 -16.037462) (xy 81.470668 -15.988827) (xy 81.504754 -15.944684)
			(xy 81.544903 -15.905975) (xy 81.590261 -15.873524) (xy 81.639861 -15.848023) (xy 81.692645 -15.830016)
			(xy 81.747488 -15.819886) (xy 81.803222 -15.817849) (xy 81.858659 -15.823949) (xy 81.912616 -15.838055)
			(xy 81.963945 -15.859867) (xy 82.011551 -15.888921) (xy 82.054419 -15.924596) (xy 82.091636 -15.966133)
			(xy 82.122409 -16.012646) (xy 82.146081 -16.063143) (xy 82.162149 -16.11655) (xy 82.170269 -16.171726)
			(xy 82.170778 -16.199612) (xy 82.170269 -16.227498) (xy 82.162149 -16.282674) (xy 82.146081 -16.336081)
			(xy 82.122409 -16.386578) (xy 82.091636 -16.433091) (xy 82.054419 -16.474628) (xy 82.011551 -16.510303)
			(xy 81.963945 -16.539357) (xy 81.912616 -16.561169) (xy 81.858659 -16.575275) (xy 81.803222 -16.581375)
			(xy 81.747488 -16.579338) (xy 81.692645 -16.569208) (xy 81.639861 -16.551201) (xy 81.590261 -16.5257)
			(xy 81.544903 -16.493249) (xy 81.504754 -16.45454) (xy 81.470668 -16.410397) (xy 81.443372 -16.361762)
			(xy 81.423449 -16.309671) (xy 81.411323 -16.255234) (xy 81.407252 -16.199612) (xy 81.043526 -16.199612)
			(xy 81.043017 -16.227498) (xy 81.034897 -16.282674) (xy 81.018829 -16.336081) (xy 80.995157 -16.386578)
			(xy 80.964384 -16.433091) (xy 80.927167 -16.474628) (xy 80.884299 -16.510303) (xy 80.836693 -16.539357)
			(xy 80.785364 -16.561169) (xy 80.731407 -16.575275) (xy 80.67597 -16.581375) (xy 80.620236 -16.579338)
			(xy 80.565393 -16.569208) (xy 80.512609 -16.551201) (xy 80.463009 -16.5257) (xy 80.417651 -16.493249)
			(xy 80.377502 -16.45454) (xy 80.343416 -16.410397) (xy 80.31612 -16.361762) (xy 80.296197 -16.309671)
			(xy 80.284071 -16.255234) (xy 80.28 -16.199612) (xy 79.906114 -16.199612) (xy 79.905605 -16.227498)
			(xy 79.897485 -16.282674) (xy 79.881417 -16.336081) (xy 79.857745 -16.386578) (xy 79.826972 -16.433091)
			(xy 79.789755 -16.474628) (xy 79.746887 -16.510303) (xy 79.699281 -16.539357) (xy 79.647952 -16.561169)
			(xy 79.593995 -16.575275) (xy 79.538558 -16.581375) (xy 79.482824 -16.579338) (xy 79.427981 -16.569208)
			(xy 79.375197 -16.551201) (xy 79.325597 -16.5257) (xy 79.280239 -16.493249) (xy 79.24009 -16.45454)
			(xy 79.206004 -16.410397) (xy 79.178708 -16.361762) (xy 79.158785 -16.309671) (xy 79.146659 -16.255234)
			(xy 79.142588 -16.199612) (xy 78.778862 -16.199612) (xy 78.778353 -16.227498) (xy 78.770233 -16.282674)
			(xy 78.754165 -16.336081) (xy 78.730493 -16.386578) (xy 78.69972 -16.433091) (xy 78.662503 -16.474628)
			(xy 78.619635 -16.510303) (xy 78.572029 -16.539357) (xy 78.5207 -16.561169) (xy 78.466743 -16.575275)
			(xy 78.411306 -16.581375) (xy 78.355572 -16.579338) (xy 78.300729 -16.569208) (xy 78.247945 -16.551201)
			(xy 78.198345 -16.5257) (xy 78.152987 -16.493249) (xy 78.112838 -16.45454) (xy 78.078752 -16.410397)
			(xy 78.051456 -16.361762) (xy 78.031533 -16.309671) (xy 78.019407 -16.255234) (xy 78.015336 -16.199612)
			(xy 77.635862 -16.199612) (xy 77.635353 -16.227498) (xy 77.627233 -16.282674) (xy 77.611165 -16.336081)
			(xy 77.587493 -16.386578) (xy 77.55672 -16.433091) (xy 77.519503 -16.474628) (xy 77.476635 -16.510303)
			(xy 77.429029 -16.539357) (xy 77.3777 -16.561169) (xy 77.323743 -16.575275) (xy 77.268306 -16.581375)
			(xy 77.212572 -16.579338) (xy 77.157729 -16.569208) (xy 77.104945 -16.551201) (xy 77.055345 -16.5257)
			(xy 77.009987 -16.493249) (xy 76.969838 -16.45454) (xy 76.935752 -16.410397) (xy 76.908456 -16.361762)
			(xy 76.888533 -16.309671) (xy 76.876407 -16.255234) (xy 76.872336 -16.199612) (xy 76.502006 -16.199612)
			(xy 76.501497 -16.227498) (xy 76.493377 -16.282674) (xy 76.477309 -16.336081) (xy 76.453637 -16.386578)
			(xy 76.422864 -16.433091) (xy 76.385647 -16.474628) (xy 76.342779 -16.510303) (xy 76.295173 -16.539357)
			(xy 76.243844 -16.561169) (xy 76.189887 -16.575275) (xy 76.13445 -16.581375) (xy 76.078716 -16.579338)
			(xy 76.023873 -16.569208) (xy 75.971089 -16.551201) (xy 75.921489 -16.5257) (xy 75.876131 -16.493249)
			(xy 75.835982 -16.45454) (xy 75.801896 -16.410397) (xy 75.7746 -16.361762) (xy 75.754677 -16.309671)
			(xy 75.742551 -16.255234) (xy 75.73848 -16.199612) (xy 63.716656 -16.199612) (xy 63.717706 -16.202612)
			(xy 63.733576 -16.272147) (xy 63.741562 -16.343021) (xy 63.742062 -16.378682) (xy 63.741562 -16.414343)
			(xy 63.733576 -16.485217) (xy 63.717706 -16.554752) (xy 63.694149 -16.622072) (xy 63.663204 -16.686331)
			(xy 63.625258 -16.746722) (xy 63.580789 -16.802484) (xy 63.530356 -16.852917) (xy 63.474594 -16.897386)
			(xy 63.414203 -16.935332) (xy 63.349944 -16.966277) (xy 63.282624 -16.989834) (xy 63.213089 -17.005704)
			(xy 63.142215 -17.01369) (xy 63.070893 -17.01369) (xy 63.000019 -17.005704) (xy 62.930484 -16.989834)
			(xy 62.863164 -16.966277) (xy 62.798905 -16.935332) (xy 62.738514 -16.897386) (xy 62.682752 -16.852917)
			(xy 62.632319 -16.802484) (xy 62.58785 -16.746722) (xy 62.549904 -16.686331) (xy 62.518959 -16.622072)
			(xy 62.495402 -16.554752) (xy 62.479532 -16.485217) (xy 62.471546 -16.414343) (xy 61.837578 -16.414343)
			(xy 61.829592 -16.485217) (xy 61.813722 -16.554752) (xy 61.790165 -16.622072) (xy 61.75922 -16.686331)
			(xy 61.721274 -16.746722) (xy 61.676805 -16.802484) (xy 61.626372 -16.852917) (xy 61.57061 -16.897386)
			(xy 61.510219 -16.935332) (xy 61.44596 -16.966277) (xy 61.37864 -16.989834) (xy 61.309105 -17.005704)
			(xy 61.238231 -17.01369) (xy 61.166909 -17.01369) (xy 61.096035 -17.005704) (xy 61.0265 -16.989834)
			(xy 60.95918 -16.966277) (xy 60.894921 -16.935332) (xy 60.83453 -16.897386) (xy 60.778768 -16.852917)
			(xy 60.728335 -16.802484) (xy 60.683866 -16.746722) (xy 60.64592 -16.686331) (xy 60.614975 -16.622072)
			(xy 60.591418 -16.554752) (xy 60.575548 -16.485217) (xy 60.567562 -16.414343) (xy 35.88086 -16.414343)
			(xy 35.919693 -16.429387) (xy 35.997482 -16.468121) (xy 36.071366 -16.513868) (xy 36.140713 -16.566237)
			(xy 36.204933 -16.624781) (xy 36.263477 -16.689001) (xy 36.315846 -16.758348) (xy 36.361593 -16.832232)
			(xy 36.400327 -16.910021) (xy 36.431719 -16.991053) (xy 36.4555 -17.074635) (xy 36.471468 -17.160055)
			(xy 36.479486 -17.246584) (xy 36.479988 -17.290034) (xy 36.479815 -17.30502) (xy 40.914826 -17.30502)
			(xy 40.918897 -17.249398) (xy 40.931023 -17.194961) (xy 40.950946 -17.14287) (xy 40.978242 -17.094235)
			(xy 41.012328 -17.050092) (xy 41.052477 -17.011383) (xy 41.097835 -16.978932) (xy 41.147435 -16.953431)
			(xy 41.200219 -16.935424) (xy 41.255062 -16.925294) (xy 41.310796 -16.923257) (xy 41.366233 -16.929357)
			(xy 41.42019 -16.943463) (xy 41.471519 -16.965275) (xy 41.519125 -16.994329) (xy 41.561993 -17.030004)
			(xy 41.59921 -17.071541) (xy 41.629983 -17.118054) (xy 41.653655 -17.168551) (xy 41.664299 -17.203928)
			(xy 74.416664 -17.203928) (xy 74.420735 -17.148306) (xy 74.432861 -17.093869) (xy 74.452784 -17.041778)
			(xy 74.48008 -16.993143) (xy 74.514166 -16.949) (xy 74.554315 -16.910291) (xy 74.599673 -16.87784)
			(xy 74.649273 -16.852339) (xy 74.702057 -16.834332) (xy 74.7569 -16.824202) (xy 74.812634 -16.822165)
			(xy 74.868071 -16.828265) (xy 74.922028 -16.842371) (xy 74.973357 -16.864183) (xy 75.020963 -16.893237)
			(xy 75.063831 -16.928912) (xy 75.101048 -16.970449) (xy 75.131821 -17.016962) (xy 75.155493 -17.067459)
			(xy 75.171561 -17.120866) (xy 75.179681 -17.176042) (xy 75.18019 -17.203928) (xy 75.179681 -17.231814)
			(xy 75.171561 -17.28699) (xy 75.155493 -17.340397) (xy 75.131821 -17.390894) (xy 75.101048 -17.437407)
			(xy 75.063831 -17.478944) (xy 75.020963 -17.514619) (xy 74.973357 -17.543673) (xy 74.922028 -17.565485)
			(xy 74.868071 -17.579591) (xy 74.812634 -17.585691) (xy 74.7569 -17.583654) (xy 74.702057 -17.573524)
			(xy 74.649273 -17.555517) (xy 74.599673 -17.530016) (xy 74.554315 -17.497565) (xy 74.514166 -17.458856)
			(xy 74.48008 -17.414713) (xy 74.452784 -17.366078) (xy 74.432861 -17.313987) (xy 74.420735 -17.25955)
			(xy 74.416664 -17.203928) (xy 41.664299 -17.203928) (xy 41.669723 -17.221958) (xy 41.677843 -17.277134)
			(xy 41.678352 -17.30502) (xy 41.677843 -17.332906) (xy 41.669723 -17.388082) (xy 41.653655 -17.441489)
			(xy 41.629983 -17.491986) (xy 41.59921 -17.538499) (xy 41.561993 -17.580036) (xy 41.519125 -17.615711)
			(xy 41.471519 -17.644765) (xy 41.42019 -17.666577) (xy 41.366233 -17.680683) (xy 41.310796 -17.686783)
			(xy 41.255062 -17.684746) (xy 41.200219 -17.674616) (xy 41.147435 -17.656609) (xy 41.097835 -17.631108)
			(xy 41.052477 -17.598657) (xy 41.012328 -17.559948) (xy 40.978242 -17.515805) (xy 40.950946 -17.46717)
			(xy 40.931023 -17.415079) (xy 40.918897 -17.360642) (xy 40.914826 -17.30502) (xy 36.479815 -17.30502)
			(xy 36.479486 -17.333484) (xy 36.471468 -17.420013) (xy 36.4555 -17.505433) (xy 36.431719 -17.589015)
			(xy 36.400327 -17.670047) (xy 36.361593 -17.747836) (xy 36.315846 -17.82172) (xy 36.263477 -17.891067)
			(xy 36.204933 -17.955287) (xy 36.140713 -18.013831) (xy 36.071366 -18.0662) (xy 35.997482 -18.111947)
			(xy 35.919693 -18.150681) (xy 35.838661 -18.182073) (xy 35.755079 -18.205854) (xy 35.669659 -18.221822)
			(xy 35.58313 -18.22984) (xy 35.49623 -18.22984) (xy 35.409701 -18.221822) (xy 35.324281 -18.205854)
			(xy 35.240699 -18.182073) (xy 35.159667 -18.150681) (xy 35.081878 -18.111947) (xy 35.007994 -18.0662)
			(xy 34.938647 -18.013831) (xy 34.874427 -17.955287) (xy 34.815883 -17.891067) (xy 34.763514 -17.82172)
			(xy 34.717767 -17.747836) (xy 34.679033 -17.670047) (xy 34.647641 -17.589015) (xy 34.62386 -17.505433)
			(xy 34.607892 -17.420013) (xy 34.599874 -17.333484) (xy 33.402762 -17.333484) (xy 33.356296 -17.37995)
			(xy 33.356296 -18.414238) (xy 40.70045 -18.414238) (xy 40.704521 -18.358616) (xy 40.716647 -18.304179)
			(xy 40.73657 -18.252088) (xy 40.763866 -18.203453) (xy 40.797952 -18.15931) (xy 40.838101 -18.120601)
			(xy 40.883459 -18.08815) (xy 40.933059 -18.062649) (xy 40.985843 -18.044642) (xy 41.040686 -18.034512)
			(xy 41.09642 -18.032475) (xy 41.151857 -18.038575) (xy 41.205814 -18.052681) (xy 41.257143 -18.074493)
			(xy 41.304749 -18.103547) (xy 41.347617 -18.139222) (xy 41.384834 -18.180759) (xy 41.415607 -18.227272)
			(xy 41.439279 -18.277769) (xy 41.455347 -18.331176) (xy 41.463467 -18.386352) (xy 41.463976 -18.414238)
			(xy 41.463467 -18.442124) (xy 41.455347 -18.4973) (xy 41.439279 -18.550707) (xy 41.415607 -18.601204)
			(xy 41.4103 -18.609225) (xy 47.374038 -18.609225) (xy 47.374038 -18.528115) (xy 47.381988 -18.447396)
			(xy 47.397811 -18.367845) (xy 47.421356 -18.290229) (xy 47.452395 -18.215293) (xy 47.49063 -18.143761)
			(xy 47.535692 -18.076321) (xy 47.587147 -18.013622) (xy 47.6445 -17.956269) (xy 47.707199 -17.904814)
			(xy 47.774639 -17.859752) (xy 47.846171 -17.821517) (xy 47.921107 -17.790478) (xy 47.998723 -17.766933)
			(xy 48.078274 -17.75111) (xy 48.158993 -17.74316) (xy 48.240103 -17.74316) (xy 48.320822 -17.75111)
			(xy 48.400373 -17.766933) (xy 48.477989 -17.790478) (xy 48.552925 -17.821517) (xy 48.624457 -17.859752)
			(xy 48.691897 -17.904814) (xy 48.754596 -17.956269) (xy 48.811949 -18.013622) (xy 48.863404 -18.076321)
			(xy 48.872192 -18.089473) (xy 60.567562 -18.089473) (xy 60.567562 -18.018151) (xy 60.575548 -17.947277)
			(xy 60.591418 -17.877742) (xy 60.614975 -17.810422) (xy 60.64592 -17.746163) (xy 60.683866 -17.685772)
			(xy 60.728335 -17.63001) (xy 60.778768 -17.579577) (xy 60.83453 -17.535108) (xy 60.894921 -17.497162)
			(xy 60.95918 -17.466217) (xy 61.0265 -17.44266) (xy 61.096035 -17.42679) (xy 61.166909 -17.418804)
			(xy 61.238231 -17.418804) (xy 61.309105 -17.42679) (xy 61.37864 -17.44266) (xy 61.44596 -17.466217)
			(xy 61.510219 -17.497162) (xy 61.57061 -17.535108) (xy 61.626372 -17.579577) (xy 61.676805 -17.63001)
			(xy 61.721274 -17.685772) (xy 61.75922 -17.746163) (xy 61.790165 -17.810422) (xy 61.813722 -17.877742)
			(xy 61.829592 -17.947277) (xy 61.837578 -18.018151) (xy 61.838078 -18.053812) (xy 61.837578 -18.089473)
			(xy 62.471546 -18.089473) (xy 62.471546 -18.018151) (xy 62.479532 -17.947277) (xy 62.495402 -17.877742)
			(xy 62.518959 -17.810422) (xy 62.549904 -17.746163) (xy 62.58785 -17.685772) (xy 62.632319 -17.63001)
			(xy 62.682752 -17.579577) (xy 62.738514 -17.535108) (xy 62.798905 -17.497162) (xy 62.863164 -17.466217)
			(xy 62.930484 -17.44266) (xy 63.000019 -17.42679) (xy 63.070893 -17.418804) (xy 63.142215 -17.418804)
			(xy 63.213089 -17.42679) (xy 63.282624 -17.44266) (xy 63.349944 -17.466217) (xy 63.414203 -17.497162)
			(xy 63.474594 -17.535108) (xy 63.530356 -17.579577) (xy 63.580789 -17.63001) (xy 63.625258 -17.685772)
			(xy 63.663204 -17.746163) (xy 63.694149 -17.810422) (xy 63.717706 -17.877742) (xy 63.733576 -17.947277)
			(xy 63.741562 -18.018151) (xy 63.742062 -18.053812) (xy 63.741562 -18.089473) (xy 63.733576 -18.160347)
			(xy 63.717706 -18.229882) (xy 63.694149 -18.297202) (xy 63.663204 -18.361461) (xy 63.625258 -18.421852)
			(xy 63.580789 -18.477614) (xy 63.530356 -18.528047) (xy 63.474594 -18.572516) (xy 63.414203 -18.610462)
			(xy 63.349944 -18.641407) (xy 63.282624 -18.664964) (xy 63.213089 -18.680834) (xy 63.142215 -18.68882)
			(xy 63.070893 -18.68882) (xy 63.000019 -18.680834) (xy 62.930484 -18.664964) (xy 62.863164 -18.641407)
			(xy 62.798905 -18.610462) (xy 62.738514 -18.572516) (xy 62.682752 -18.528047) (xy 62.632319 -18.477614)
			(xy 62.58785 -18.421852) (xy 62.549904 -18.361461) (xy 62.518959 -18.297202) (xy 62.495402 -18.229882)
			(xy 62.479532 -18.160347) (xy 62.471546 -18.089473) (xy 61.837578 -18.089473) (xy 61.829592 -18.160347)
			(xy 61.813722 -18.229882) (xy 61.790165 -18.297202) (xy 61.75922 -18.361461) (xy 61.721274 -18.421852)
			(xy 61.676805 -18.477614) (xy 61.626372 -18.528047) (xy 61.57061 -18.572516) (xy 61.510219 -18.610462)
			(xy 61.44596 -18.641407) (xy 61.37864 -18.664964) (xy 61.309105 -18.680834) (xy 61.238231 -18.68882)
			(xy 61.166909 -18.68882) (xy 61.096035 -18.680834) (xy 61.0265 -18.664964) (xy 60.95918 -18.641407)
			(xy 60.894921 -18.610462) (xy 60.83453 -18.572516) (xy 60.778768 -18.528047) (xy 60.728335 -18.477614)
			(xy 60.683866 -18.421852) (xy 60.64592 -18.361461) (xy 60.614975 -18.297202) (xy 60.591418 -18.229882)
			(xy 60.575548 -18.160347) (xy 60.567562 -18.089473) (xy 48.872192 -18.089473) (xy 48.908466 -18.143761)
			(xy 48.946701 -18.215293) (xy 48.97774 -18.290229) (xy 49.001285 -18.367845) (xy 49.017108 -18.447396)
			(xy 49.025058 -18.528115) (xy 49.025556 -18.56867) (xy 49.025058 -18.609225) (xy 49.017108 -18.689944)
			(xy 49.001285 -18.769495) (xy 48.97774 -18.847111) (xy 48.946701 -18.922047) (xy 48.908466 -18.993579)
			(xy 48.863404 -19.061019) (xy 48.811949 -19.123718) (xy 48.754596 -19.181071) (xy 48.691897 -19.232526)
			(xy 48.624457 -19.277588) (xy 48.552925 -19.315823) (xy 48.477989 -19.346862) (xy 48.400373 -19.370407)
			(xy 48.320822 -19.38623) (xy 48.240103 -19.39418) (xy 48.158993 -19.39418) (xy 48.078274 -19.38623)
			(xy 47.998723 -19.370407) (xy 47.921107 -19.346862) (xy 47.846171 -19.315823) (xy 47.774639 -19.277588)
			(xy 47.707199 -19.232526) (xy 47.6445 -19.181071) (xy 47.587147 -19.123718) (xy 47.535692 -19.061019)
			(xy 47.49063 -18.993579) (xy 47.452395 -18.922047) (xy 47.421356 -18.847111) (xy 47.397811 -18.769495)
			(xy 47.381988 -18.689944) (xy 47.374038 -18.609225) (xy 41.4103 -18.609225) (xy 41.384834 -18.647717)
			(xy 41.347617 -18.689254) (xy 41.304749 -18.724929) (xy 41.257143 -18.753983) (xy 41.205814 -18.775795)
			(xy 41.151857 -18.789901) (xy 41.09642 -18.796001) (xy 41.040686 -18.793964) (xy 40.985843 -18.783834)
			(xy 40.933059 -18.765827) (xy 40.883459 -18.740326) (xy 40.838101 -18.707875) (xy 40.797952 -18.669166)
			(xy 40.763866 -18.625023) (xy 40.73657 -18.576388) (xy 40.716647 -18.524297) (xy 40.704521 -18.46986)
			(xy 40.70045 -18.414238) (xy 33.356296 -18.414238) (xy 33.356296 -19.873484) (xy 34.599874 -19.873484)
			(xy 34.599874 -19.786584) (xy 34.607892 -19.700055) (xy 34.62386 -19.614635) (xy 34.647641 -19.531053)
			(xy 34.679033 -19.450021) (xy 34.717767 -19.372232) (xy 34.763514 -19.298348) (xy 34.815883 -19.229001)
			(xy 34.874427 -19.164781) (xy 34.938647 -19.106237) (xy 35.007994 -19.053868) (xy 35.081878 -19.008121)
			(xy 35.159667 -18.969387) (xy 35.240699 -18.937995) (xy 35.324281 -18.914214) (xy 35.409701 -18.898246)
			(xy 35.49623 -18.890228) (xy 35.58313 -18.890228) (xy 35.669659 -18.898246) (xy 35.755079 -18.914214)
			(xy 35.838661 -18.937995) (xy 35.919693 -18.969387) (xy 35.997482 -19.008121) (xy 36.071366 -19.053868)
			(xy 36.140713 -19.106237) (xy 36.204933 -19.164781) (xy 36.263477 -19.229001) (xy 36.315846 -19.298348)
			(xy 36.361593 -19.372232) (xy 36.400327 -19.450021) (xy 36.431719 -19.531053) (xy 36.4555 -19.614635)
			(xy 36.471468 -19.700055) (xy 36.479486 -19.786584) (xy 36.479988 -19.830034) (xy 36.479486 -19.873484)
			(xy 36.471468 -19.960013) (xy 36.4555 -20.045433) (xy 36.439791 -20.100645) (xy 60.524128 -20.100645)
			(xy 60.524128 -20.029323) (xy 60.532114 -19.958449) (xy 60.547984 -19.888914) (xy 60.571541 -19.821594)
			(xy 60.602486 -19.757335) (xy 60.640432 -19.696944) (xy 60.684901 -19.641182) (xy 60.735334 -19.590749)
			(xy 60.791096 -19.54628) (xy 60.851487 -19.508334) (xy 60.915746 -19.477389) (xy 60.983066 -19.453832)
			(xy 61.052601 -19.437962) (xy 61.123475 -19.429976) (xy 61.194797 -19.429976) (xy 61.265671 -19.437962)
			(xy 61.335206 -19.453832) (xy 61.402526 -19.477389) (xy 61.466785 -19.508334) (xy 61.527176 -19.54628)
			(xy 61.582938 -19.590749) (xy 61.633371 -19.641182) (xy 61.67784 -19.696944) (xy 61.715786 -19.757335)
			(xy 61.746731 -19.821594) (xy 61.770288 -19.888914) (xy 61.786158 -19.958449) (xy 61.794144 -20.029323)
			(xy 61.794644 -20.064984) (xy 61.794144 -20.100645) (xy 62.428112 -20.100645) (xy 62.428112 -20.029323)
			(xy 62.436098 -19.958449) (xy 62.451968 -19.888914) (xy 62.475525 -19.821594) (xy 62.50647 -19.757335)
			(xy 62.544416 -19.696944) (xy 62.588885 -19.641182) (xy 62.639318 -19.590749) (xy 62.69508 -19.54628)
			(xy 62.755471 -19.508334) (xy 62.81973 -19.477389) (xy 62.88705 -19.453832) (xy 62.956585 -19.437962)
			(xy 63.027459 -19.429976) (xy 63.098781 -19.429976) (xy 63.169655 -19.437962) (xy 63.23919 -19.453832)
			(xy 63.30651 -19.477389) (xy 63.370769 -19.508334) (xy 63.43116 -19.54628) (xy 63.486922 -19.590749)
			(xy 63.537355 -19.641182) (xy 63.581824 -19.696944) (xy 63.61977 -19.757335) (xy 63.650715 -19.821594)
			(xy 63.674272 -19.888914) (xy 63.690142 -19.958449) (xy 63.698128 -20.029323) (xy 63.698628 -20.064984)
			(xy 63.698128 -20.100645) (xy 63.690142 -20.171519) (xy 63.674272 -20.241054) (xy 63.650715 -20.308374)
			(xy 63.61977 -20.372633) (xy 63.581824 -20.433024) (xy 63.537355 -20.488786) (xy 63.486922 -20.539219)
			(xy 63.43116 -20.583688) (xy 63.370769 -20.621634) (xy 63.30651 -20.652579) (xy 63.23919 -20.676136)
			(xy 63.169655 -20.692006) (xy 63.098781 -20.699992) (xy 63.027459 -20.699992) (xy 62.956585 -20.692006)
			(xy 62.88705 -20.676136) (xy 62.81973 -20.652579) (xy 62.755471 -20.621634) (xy 62.69508 -20.583688)
			(xy 62.639318 -20.539219) (xy 62.588885 -20.488786) (xy 62.544416 -20.433024) (xy 62.50647 -20.372633)
			(xy 62.475525 -20.308374) (xy 62.451968 -20.241054) (xy 62.436098 -20.171519) (xy 62.428112 -20.100645)
			(xy 61.794144 -20.100645) (xy 61.786158 -20.171519) (xy 61.770288 -20.241054) (xy 61.746731 -20.308374)
			(xy 61.715786 -20.372633) (xy 61.67784 -20.433024) (xy 61.633371 -20.488786) (xy 61.582938 -20.539219)
			(xy 61.527176 -20.583688) (xy 61.466785 -20.621634) (xy 61.402526 -20.652579) (xy 61.335206 -20.676136)
			(xy 61.265671 -20.692006) (xy 61.194797 -20.699992) (xy 61.123475 -20.699992) (xy 61.052601 -20.692006)
			(xy 60.983066 -20.676136) (xy 60.915746 -20.652579) (xy 60.851487 -20.621634) (xy 60.791096 -20.583688)
			(xy 60.735334 -20.539219) (xy 60.684901 -20.488786) (xy 60.640432 -20.433024) (xy 60.602486 -20.372633)
			(xy 60.571541 -20.308374) (xy 60.547984 -20.241054) (xy 60.532114 -20.171519) (xy 60.524128 -20.100645)
			(xy 36.439791 -20.100645) (xy 36.431719 -20.129015) (xy 36.400327 -20.210047) (xy 36.361593 -20.287836)
			(xy 36.315846 -20.36172) (xy 36.263477 -20.431067) (xy 36.204933 -20.495287) (xy 36.140713 -20.553831)
			(xy 36.071366 -20.6062) (xy 35.997482 -20.651947) (xy 35.919693 -20.690681) (xy 35.838661 -20.722073)
			(xy 35.755079 -20.745854) (xy 35.669659 -20.761822) (xy 35.58313 -20.76984) (xy 35.49623 -20.76984)
			(xy 35.409701 -20.761822) (xy 35.324281 -20.745854) (xy 35.240699 -20.722073) (xy 35.159667 -20.690681)
			(xy 35.081878 -20.651947) (xy 35.007994 -20.6062) (xy 34.938647 -20.553831) (xy 34.874427 -20.495287)
			(xy 34.815883 -20.431067) (xy 34.763514 -20.36172) (xy 34.717767 -20.287836) (xy 34.679033 -20.210047)
			(xy 34.647641 -20.129015) (xy 34.62386 -20.045433) (xy 34.607892 -19.960013) (xy 34.599874 -19.873484)
			(xy 33.356296 -19.873484) (xy 33.356296 -20.34921) (xy 32.467042 -21.238464) (xy 31.269686 -21.238464)
			(xy 31.246269 -21.238993) (xy 31.200225 -21.247563) (xy 31.156533 -21.26443) (xy 31.116674 -21.289021)
			(xy 31.081998 -21.320502) (xy 31.053682 -21.357807) (xy 31.032685 -21.399671) (xy 31.019718 -21.444675)
			(xy 31.015222 -21.491293) (xy 31.019349 -21.537946) (xy 31.031959 -21.583051) (xy 31.052624 -21.62508)
			(xy 31.080644 -21.662608) (xy 31.097474 -21.6789) (xy 31.129148 -21.708789) (xy 31.187425 -21.773513)
			(xy 31.239469 -21.843348) (xy 31.284831 -21.917696) (xy 31.323125 -21.99592) (xy 31.354021 -22.07735)
			(xy 31.377256 -22.161288) (xy 31.392629 -22.247014) (xy 31.400009 -22.333795) (xy 31.399391 -22.413484)
			(xy 34.599874 -22.413484) (xy 34.599874 -22.326584) (xy 34.607892 -22.240055) (xy 34.62386 -22.154635)
			(xy 34.647641 -22.071053) (xy 34.679033 -21.990021) (xy 34.717767 -21.912232) (xy 34.763514 -21.838348)
			(xy 34.815883 -21.769001) (xy 34.874427 -21.704781) (xy 34.938647 -21.646237) (xy 35.007994 -21.593868)
			(xy 35.081878 -21.548121) (xy 35.159667 -21.509387) (xy 35.240699 -21.477995) (xy 35.324281 -21.454214)
			(xy 35.409701 -21.438246) (xy 35.49623 -21.430228) (xy 35.58313 -21.430228) (xy 35.669659 -21.438246)
			(xy 35.755079 -21.454214) (xy 35.838661 -21.477995) (xy 35.919693 -21.509387) (xy 35.997482 -21.548121)
			(xy 36.071366 -21.593868) (xy 36.071962 -21.594318) (xy 39.978836 -21.594318) (xy 39.982907 -21.538696)
			(xy 39.995033 -21.484259) (xy 40.014956 -21.432168) (xy 40.042252 -21.383533) (xy 40.076338 -21.33939)
			(xy 40.116487 -21.300681) (xy 40.161845 -21.26823) (xy 40.211445 -21.242729) (xy 40.264229 -21.224722)
			(xy 40.319072 -21.214592) (xy 40.374806 -21.212555) (xy 40.430243 -21.218655) (xy 40.4842 -21.232761)
			(xy 40.535529 -21.254573) (xy 40.583135 -21.283627) (xy 40.626003 -21.319302) (xy 40.66322 -21.360839)
			(xy 40.693993 -21.407352) (xy 40.717665 -21.457849) (xy 40.733733 -21.511256) (xy 40.741853 -21.566432)
			(xy 40.742362 -21.594318) (xy 40.741853 -21.622204) (xy 40.733733 -21.67738) (xy 40.717665 -21.730787)
			(xy 40.693993 -21.781284) (xy 40.66322 -21.827797) (xy 40.626003 -21.869334) (xy 40.583135 -21.905009)
			(xy 40.535529 -21.934063) (xy 40.4842 -21.955875) (xy 40.430243 -21.969981) (xy 40.374806 -21.976081)
			(xy 40.319072 -21.974044) (xy 40.264229 -21.963914) (xy 40.211445 -21.945907) (xy 40.161845 -21.920406)
			(xy 40.116487 -21.887955) (xy 40.076338 -21.849246) (xy 40.042252 -21.805103) (xy 40.014956 -21.756468)
			(xy 39.995033 -21.704377) (xy 39.982907 -21.64994) (xy 39.978836 -21.594318) (xy 36.071962 -21.594318)
			(xy 36.140713 -21.646237) (xy 36.204933 -21.704781) (xy 36.263477 -21.769001) (xy 36.315846 -21.838348)
			(xy 36.361593 -21.912232) (xy 36.400327 -21.990021) (xy 36.400771 -21.991167) (xy 60.524128 -21.991167)
			(xy 60.524128 -21.919845) (xy 60.532114 -21.848971) (xy 60.547984 -21.779436) (xy 60.571541 -21.712116)
			(xy 60.602486 -21.647857) (xy 60.640432 -21.587466) (xy 60.684901 -21.531704) (xy 60.735334 -21.481271)
			(xy 60.791096 -21.436802) (xy 60.851487 -21.398856) (xy 60.915746 -21.367911) (xy 60.983066 -21.344354)
			(xy 61.052601 -21.328484) (xy 61.123475 -21.320498) (xy 61.194797 -21.320498) (xy 61.265671 -21.328484)
			(xy 61.335206 -21.344354) (xy 61.402526 -21.367911) (xy 61.466785 -21.398856) (xy 61.527176 -21.436802)
			(xy 61.582938 -21.481271) (xy 61.633371 -21.531704) (xy 61.67784 -21.587466) (xy 61.715786 -21.647857)
			(xy 61.746731 -21.712116) (xy 61.770288 -21.779436) (xy 61.786158 -21.848971) (xy 61.794144 -21.919845)
			(xy 61.794644 -21.955506) (xy 61.794144 -21.991167) (xy 62.428112 -21.991167) (xy 62.428112 -21.919845)
			(xy 62.436098 -21.848971) (xy 62.451968 -21.779436) (xy 62.475525 -21.712116) (xy 62.50647 -21.647857)
			(xy 62.544416 -21.587466) (xy 62.588885 -21.531704) (xy 62.639318 -21.481271) (xy 62.69508 -21.436802)
			(xy 62.755471 -21.398856) (xy 62.81973 -21.367911) (xy 62.88705 -21.344354) (xy 62.956585 -21.328484)
			(xy 63.027459 -21.320498) (xy 63.098781 -21.320498) (xy 63.169655 -21.328484) (xy 63.23919 -21.344354)
			(xy 63.30651 -21.367911) (xy 63.370769 -21.398856) (xy 63.43116 -21.436802) (xy 63.486922 -21.481271)
			(xy 63.537355 -21.531704) (xy 63.581824 -21.587466) (xy 63.61977 -21.647857) (xy 63.650715 -21.712116)
			(xy 63.674272 -21.779436) (xy 63.690142 -21.848971) (xy 63.698128 -21.919845) (xy 63.698628 -21.955506)
			(xy 63.698128 -21.991167) (xy 63.690142 -22.062041) (xy 63.674272 -22.131576) (xy 63.650715 -22.198896)
			(xy 63.61977 -22.263155) (xy 63.581824 -22.323546) (xy 63.537355 -22.379308) (xy 63.486922 -22.429741)
			(xy 63.43116 -22.47421) (xy 63.370769 -22.512156) (xy 63.30651 -22.543101) (xy 63.23919 -22.566658)
			(xy 63.169655 -22.582528) (xy 63.098781 -22.590514) (xy 63.027459 -22.590514) (xy 62.956585 -22.582528)
			(xy 62.88705 -22.566658) (xy 62.81973 -22.543101) (xy 62.755471 -22.512156) (xy 62.69508 -22.47421)
			(xy 62.639318 -22.429741) (xy 62.588885 -22.379308) (xy 62.544416 -22.323546) (xy 62.50647 -22.263155)
			(xy 62.475525 -22.198896) (xy 62.451968 -22.131576) (xy 62.436098 -22.062041) (xy 62.428112 -21.991167)
			(xy 61.794144 -21.991167) (xy 61.786158 -22.062041) (xy 61.770288 -22.131576) (xy 61.746731 -22.198896)
			(xy 61.715786 -22.263155) (xy 61.67784 -22.323546) (xy 61.633371 -22.379308) (xy 61.582938 -22.429741)
			(xy 61.527176 -22.47421) (xy 61.466785 -22.512156) (xy 61.402526 -22.543101) (xy 61.335206 -22.566658)
			(xy 61.265671 -22.582528) (xy 61.194797 -22.590514) (xy 61.123475 -22.590514) (xy 61.052601 -22.582528)
			(xy 60.983066 -22.566658) (xy 60.915746 -22.543101) (xy 60.851487 -22.512156) (xy 60.791096 -22.47421)
			(xy 60.735334 -22.429741) (xy 60.684901 -22.379308) (xy 60.640432 -22.323546) (xy 60.602486 -22.263155)
			(xy 60.571541 -22.198896) (xy 60.547984 -22.131576) (xy 60.532114 -22.062041) (xy 60.524128 -21.991167)
			(xy 36.400771 -21.991167) (xy 36.431719 -22.071053) (xy 36.4555 -22.154635) (xy 36.471468 -22.240055)
			(xy 36.479486 -22.326584) (xy 36.479988 -22.370034) (xy 36.479486 -22.413484) (xy 36.471468 -22.500013)
			(xy 36.4555 -22.585433) (xy 36.431719 -22.669015) (xy 36.400327 -22.750047) (xy 36.361593 -22.827836)
			(xy 36.315846 -22.90172) (xy 36.263477 -22.971067) (xy 36.204933 -23.035287) (xy 36.140713 -23.093831)
			(xy 36.071366 -23.1462) (xy 36.008098 -23.185374) (xy 40.1099 -23.185374) (xy 40.113971 -23.129752)
			(xy 40.126097 -23.075315) (xy 40.14602 -23.023224) (xy 40.173316 -22.974589) (xy 40.207402 -22.930446)
			(xy 40.247551 -22.891737) (xy 40.292909 -22.859286) (xy 40.342509 -22.833785) (xy 40.395293 -22.815778)
			(xy 40.450136 -22.805648) (xy 40.50587 -22.803611) (xy 40.561307 -22.809711) (xy 40.615264 -22.823817)
			(xy 40.666593 -22.845629) (xy 40.714199 -22.874683) (xy 40.757067 -22.910358) (xy 40.794284 -22.951895)
			(xy 40.825057 -22.998408) (xy 40.848729 -23.048905) (xy 40.864797 -23.102312) (xy 40.872917 -23.157488)
			(xy 40.873426 -23.185374) (xy 40.872917 -23.21326) (xy 40.864797 -23.268436) (xy 40.848729 -23.321843)
			(xy 40.825057 -23.37234) (xy 40.794284 -23.418853) (xy 40.757067 -23.46039) (xy 40.714199 -23.496065)
			(xy 40.666593 -23.525119) (xy 40.615264 -23.546931) (xy 40.561307 -23.561037) (xy 40.50587 -23.567137)
			(xy 40.450136 -23.5651) (xy 40.395293 -23.55497) (xy 40.342509 -23.536963) (xy 40.292909 -23.511462)
			(xy 40.247551 -23.479011) (xy 40.207402 -23.440302) (xy 40.173316 -23.396159) (xy 40.14602 -23.347524)
			(xy 40.126097 -23.295433) (xy 40.113971 -23.240996) (xy 40.1099 -23.185374) (xy 36.008098 -23.185374)
			(xy 35.997482 -23.191947) (xy 35.919693 -23.230681) (xy 35.838661 -23.262073) (xy 35.755079 -23.285854)
			(xy 35.669659 -23.301822) (xy 35.58313 -23.30984) (xy 35.49623 -23.30984) (xy 35.409701 -23.301822)
			(xy 35.324281 -23.285854) (xy 35.240699 -23.262073) (xy 35.159667 -23.230681) (xy 35.081878 -23.191947)
			(xy 35.007994 -23.1462) (xy 34.938647 -23.093831) (xy 34.874427 -23.035287) (xy 34.815883 -22.971067)
			(xy 34.763514 -22.90172) (xy 34.717767 -22.827836) (xy 34.679033 -22.750047) (xy 34.647641 -22.669015)
			(xy 34.62386 -22.585433) (xy 34.607892 -22.500013) (xy 34.599874 -22.413484) (xy 31.399391 -22.413484)
			(xy 31.399334 -22.420887) (xy 31.390608 -22.507543) (xy 31.373906 -22.593021) (xy 31.349373 -22.676589)
			(xy 31.317216 -22.757529) (xy 31.277714 -22.83515) (xy 31.231203 -22.908785) (xy 31.178082 -22.977804)
			(xy 31.118808 -23.041616) (xy 31.053886 -23.099673) (xy 30.983874 -23.151478) (xy 30.909372 -23.196587)
			(xy 30.831018 -23.234614) (xy 30.749483 -23.265233) (xy 30.665467 -23.288181) (xy 30.579688 -23.303263)
			(xy 30.492883 -23.310347) (xy 30.405794 -23.309375) (xy 30.319168 -23.300354) (xy 30.233747 -23.283362)
			(xy 30.150264 -23.258543) (xy 30.109668 -23.242778) (xy 30.069795 -23.226258) (xy 29.992966 -23.186918)
			(xy 29.920066 -23.140703) (xy 29.851708 -23.088001) (xy 29.788467 -23.029258) (xy 29.730875 -22.964966)
			(xy 29.679417 -22.895667) (xy 29.634526 -22.821945) (xy 29.596579 -22.744419) (xy 29.565897 -22.663741)
			(xy 29.542736 -22.580592) (xy 29.527293 -22.49567) (xy 29.519697 -22.40969) (xy 29.520011 -22.323375)
			(xy 29.528235 -22.237453) (xy 29.544297 -22.152646) (xy 29.568063 -22.069668) (xy 29.599333 -21.989216)
			(xy 29.637844 -21.911969) (xy 29.683272 -21.838575) (xy 29.735234 -21.769654) (xy 29.793293 -21.705784)
			(xy 29.856961 -21.647503) (xy 29.925702 -21.595302) (xy 29.998937 -21.54962) (xy 30.037278 -21.529802)
			(xy 30.062826 -21.51724) (xy 30.115186 -21.494869) (xy 30.141926 -21.485098) (xy 30.156468 -21.47941)
			(xy 30.182416 -21.462057) (xy 30.203361 -21.438911) (xy 30.218045 -21.411365) (xy 30.225585 -21.381073)
			(xy 30.226 -21.365464) (xy 30.225452 -21.348819) (xy 30.216829 -21.316664) (xy 30.200178 -21.287837)
			(xy 30.176634 -21.2643) (xy 30.147802 -21.247658) (xy 30.115645 -21.239043) (xy 30.099 -21.238464)
			(xy 29.79166 -21.238464) (xy 26.07664 -24.953484) (xy 29.519874 -24.953484) (xy 29.519874 -24.866584)
			(xy 29.527892 -24.780055) (xy 29.54386 -24.694635) (xy 29.567641 -24.611053) (xy 29.599033 -24.530021)
			(xy 29.637767 -24.452232) (xy 29.683514 -24.378348) (xy 29.735883 -24.309001) (xy 29.794427 -24.244781)
			(xy 29.858647 -24.186237) (xy 29.927994 -24.133868) (xy 30.001878 -24.088121) (xy 30.079667 -24.049387)
			(xy 30.160699 -24.017995) (xy 30.244281 -23.994214) (xy 30.329701 -23.978246) (xy 30.41623 -23.970228)
			(xy 30.50313 -23.970228) (xy 30.589659 -23.978246) (xy 30.675079 -23.994214) (xy 30.758661 -24.017995)
			(xy 30.839693 -24.049387) (xy 30.917482 -24.088121) (xy 30.991366 -24.133868) (xy 31.060713 -24.186237)
			(xy 31.124933 -24.244781) (xy 31.183477 -24.309001) (xy 31.235846 -24.378348) (xy 31.281593 -24.452232)
			(xy 31.320327 -24.530021) (xy 31.351719 -24.611053) (xy 31.3755 -24.694635) (xy 31.391468 -24.780055)
			(xy 31.399486 -24.866584) (xy 31.399988 -24.910034) (xy 31.399486 -24.953484) (xy 34.599874 -24.953484)
			(xy 34.599874 -24.866584) (xy 34.607892 -24.780055) (xy 34.62386 -24.694635) (xy 34.647641 -24.611053)
			(xy 34.679033 -24.530021) (xy 34.717767 -24.452232) (xy 34.763514 -24.378348) (xy 34.815883 -24.309001)
			(xy 34.874427 -24.244781) (xy 34.938647 -24.186237) (xy 35.007994 -24.133868) (xy 35.081878 -24.088121)
			(xy 35.159667 -24.049387) (xy 35.240699 -24.017995) (xy 35.324281 -23.994214) (xy 35.409701 -23.978246)
			(xy 35.49623 -23.970228) (xy 35.58313 -23.970228) (xy 35.669659 -23.978246) (xy 35.755079 -23.994214)
			(xy 35.838661 -24.017995) (xy 35.875615 -24.032311) (xy 60.524128 -24.032311) (xy 60.524128 -23.960989)
			(xy 60.532114 -23.890115) (xy 60.547984 -23.82058) (xy 60.571541 -23.75326) (xy 60.602486 -23.689001)
			(xy 60.640432 -23.62861) (xy 60.684901 -23.572848) (xy 60.735334 -23.522415) (xy 60.791096 -23.477946)
			(xy 60.851487 -23.44) (xy 60.915746 -23.409055) (xy 60.983066 -23.385498) (xy 61.052601 -23.369628)
			(xy 61.123475 -23.361642) (xy 61.194797 -23.361642) (xy 61.265671 -23.369628) (xy 61.335206 -23.385498)
			(xy 61.402526 -23.409055) (xy 61.466785 -23.44) (xy 61.527176 -23.477946) (xy 61.582938 -23.522415)
			(xy 61.633371 -23.572848) (xy 61.67784 -23.62861) (xy 61.715786 -23.689001) (xy 61.746731 -23.75326)
			(xy 61.770288 -23.82058) (xy 61.786158 -23.890115) (xy 61.794144 -23.960989) (xy 61.794644 -23.99665)
			(xy 61.794144 -24.032311) (xy 62.428112 -24.032311) (xy 62.428112 -23.960989) (xy 62.436098 -23.890115)
			(xy 62.451968 -23.82058) (xy 62.475525 -23.75326) (xy 62.50647 -23.689001) (xy 62.544416 -23.62861)
			(xy 62.588885 -23.572848) (xy 62.639318 -23.522415) (xy 62.69508 -23.477946) (xy 62.755471 -23.44)
			(xy 62.81973 -23.409055) (xy 62.88705 -23.385498) (xy 62.956585 -23.369628) (xy 63.027459 -23.361642)
			(xy 63.098781 -23.361642) (xy 63.169655 -23.369628) (xy 63.23919 -23.385498) (xy 63.30651 -23.409055)
			(xy 63.370769 -23.44) (xy 63.43116 -23.477946) (xy 63.486922 -23.522415) (xy 63.537355 -23.572848)
			(xy 63.581824 -23.62861) (xy 63.61977 -23.689001) (xy 63.650715 -23.75326) (xy 63.674272 -23.82058)
			(xy 63.690142 -23.890115) (xy 63.698128 -23.960989) (xy 63.698628 -23.99665) (xy 63.698128 -24.032311)
			(xy 63.690142 -24.103185) (xy 63.674272 -24.17272) (xy 63.650715 -24.24004) (xy 63.61977 -24.304299)
			(xy 63.581824 -24.36469) (xy 63.537355 -24.420452) (xy 63.486922 -24.470885) (xy 63.43116 -24.515354)
			(xy 63.370769 -24.5533) (xy 63.30651 -24.584245) (xy 63.23919 -24.607802) (xy 63.169655 -24.623672)
			(xy 63.098781 -24.631658) (xy 63.027459 -24.631658) (xy 62.956585 -24.623672) (xy 62.88705 -24.607802)
			(xy 62.81973 -24.584245) (xy 62.755471 -24.5533) (xy 62.69508 -24.515354) (xy 62.639318 -24.470885)
			(xy 62.588885 -24.420452) (xy 62.544416 -24.36469) (xy 62.50647 -24.304299) (xy 62.475525 -24.24004)
			(xy 62.451968 -24.17272) (xy 62.436098 -24.103185) (xy 62.428112 -24.032311) (xy 61.794144 -24.032311)
			(xy 61.786158 -24.103185) (xy 61.770288 -24.17272) (xy 61.746731 -24.24004) (xy 61.715786 -24.304299)
			(xy 61.67784 -24.36469) (xy 61.633371 -24.420452) (xy 61.582938 -24.470885) (xy 61.527176 -24.515354)
			(xy 61.466785 -24.5533) (xy 61.402526 -24.584245) (xy 61.335206 -24.607802) (xy 61.265671 -24.623672)
			(xy 61.194797 -24.631658) (xy 61.123475 -24.631658) (xy 61.052601 -24.623672) (xy 60.983066 -24.607802)
			(xy 60.915746 -24.584245) (xy 60.851487 -24.5533) (xy 60.791096 -24.515354) (xy 60.735334 -24.470885)
			(xy 60.684901 -24.420452) (xy 60.640432 -24.36469) (xy 60.602486 -24.304299) (xy 60.571541 -24.24004)
			(xy 60.547984 -24.17272) (xy 60.532114 -24.103185) (xy 60.524128 -24.032311) (xy 35.875615 -24.032311)
			(xy 35.919693 -24.049387) (xy 35.997482 -24.088121) (xy 36.071366 -24.133868) (xy 36.140713 -24.186237)
			(xy 36.204933 -24.244781) (xy 36.263477 -24.309001) (xy 36.315846 -24.378348) (xy 36.361593 -24.452232)
			(xy 36.400327 -24.530021) (xy 36.431719 -24.611053) (xy 36.4555 -24.694635) (xy 36.471468 -24.780055)
			(xy 36.479486 -24.866584) (xy 36.479988 -24.910034) (xy 36.479486 -24.953484) (xy 36.471468 -25.040013)
			(xy 36.4555 -25.125433) (xy 36.431719 -25.209015) (xy 36.400327 -25.290047) (xy 36.361593 -25.367836)
			(xy 36.315846 -25.44172) (xy 36.263477 -25.511067) (xy 36.204933 -25.575287) (xy 36.140713 -25.633831)
			(xy 36.071366 -25.6862) (xy 35.997482 -25.731947) (xy 35.919693 -25.770681) (xy 35.838661 -25.802073)
			(xy 35.755079 -25.825854) (xy 35.669659 -25.841822) (xy 35.58313 -25.84984) (xy 35.49623 -25.84984)
			(xy 35.409701 -25.841822) (xy 35.324281 -25.825854) (xy 35.240699 -25.802073) (xy 35.159667 -25.770681)
			(xy 35.081878 -25.731947) (xy 35.007994 -25.6862) (xy 34.938647 -25.633831) (xy 34.874427 -25.575287)
			(xy 34.815883 -25.511067) (xy 34.763514 -25.44172) (xy 34.717767 -25.367836) (xy 34.679033 -25.290047)
			(xy 34.647641 -25.209015) (xy 34.62386 -25.125433) (xy 34.607892 -25.040013) (xy 34.599874 -24.953484)
			(xy 31.399486 -24.953484) (xy 31.391468 -25.040013) (xy 31.3755 -25.125433) (xy 31.351719 -25.209015)
			(xy 31.320327 -25.290047) (xy 31.281593 -25.367836) (xy 31.235846 -25.44172) (xy 31.183477 -25.511067)
			(xy 31.124933 -25.575287) (xy 31.060713 -25.633831) (xy 30.991366 -25.6862) (xy 30.917482 -25.731947)
			(xy 30.839693 -25.770681) (xy 30.758661 -25.802073) (xy 30.675079 -25.825854) (xy 30.589659 -25.841822)
			(xy 30.50313 -25.84984) (xy 30.41623 -25.84984) (xy 30.329701 -25.841822) (xy 30.244281 -25.825854)
			(xy 30.160699 -25.802073) (xy 30.079667 -25.770681) (xy 30.001878 -25.731947) (xy 29.927994 -25.6862)
			(xy 29.858647 -25.633831) (xy 29.794427 -25.575287) (xy 29.735883 -25.511067) (xy 29.683514 -25.44172)
			(xy 29.637767 -25.367836) (xy 29.599033 -25.290047) (xy 29.567641 -25.209015) (xy 29.54386 -25.125433)
			(xy 29.527892 -25.040013) (xy 29.519874 -24.953484) (xy 26.07664 -24.953484) (xy 25.087987 -25.942137)
			(xy 60.524128 -25.942137) (xy 60.524128 -25.870815) (xy 60.532114 -25.799941) (xy 60.547984 -25.730406)
			(xy 60.571541 -25.663086) (xy 60.602486 -25.598827) (xy 60.640432 -25.538436) (xy 60.684901 -25.482674)
			(xy 60.735334 -25.432241) (xy 60.791096 -25.387772) (xy 60.851487 -25.349826) (xy 60.915746 -25.318881)
			(xy 60.983066 -25.295324) (xy 61.052601 -25.279454) (xy 61.123475 -25.271468) (xy 61.194797 -25.271468)
			(xy 61.265671 -25.279454) (xy 61.335206 -25.295324) (xy 61.402526 -25.318881) (xy 61.466785 -25.349826)
			(xy 61.527176 -25.387772) (xy 61.582938 -25.432241) (xy 61.633371 -25.482674) (xy 61.67784 -25.538436)
			(xy 61.715786 -25.598827) (xy 61.746731 -25.663086) (xy 61.770288 -25.730406) (xy 61.786158 -25.799941)
			(xy 61.794144 -25.870815) (xy 61.794644 -25.906476) (xy 61.794144 -25.942137) (xy 62.428112 -25.942137)
			(xy 62.428112 -25.870815) (xy 62.436098 -25.799941) (xy 62.451968 -25.730406) (xy 62.475525 -25.663086)
			(xy 62.50647 -25.598827) (xy 62.544416 -25.538436) (xy 62.588885 -25.482674) (xy 62.639318 -25.432241)
			(xy 62.69508 -25.387772) (xy 62.755471 -25.349826) (xy 62.81973 -25.318881) (xy 62.88705 -25.295324)
			(xy 62.956585 -25.279454) (xy 63.027459 -25.271468) (xy 63.098781 -25.271468) (xy 63.169655 -25.279454)
			(xy 63.23919 -25.295324) (xy 63.30651 -25.318881) (xy 63.370769 -25.349826) (xy 63.43116 -25.387772)
			(xy 63.486922 -25.432241) (xy 63.537355 -25.482674) (xy 63.581824 -25.538436) (xy 63.61977 -25.598827)
			(xy 63.650715 -25.663086) (xy 63.674272 -25.730406) (xy 63.690142 -25.799941) (xy 63.698128 -25.870815)
			(xy 63.698628 -25.906476) (xy 63.698128 -25.942137) (xy 63.690142 -26.013011) (xy 63.674272 -26.082546)
			(xy 63.650715 -26.149866) (xy 63.61977 -26.214125) (xy 63.581824 -26.274516) (xy 63.537355 -26.330278)
			(xy 63.486922 -26.380711) (xy 63.43116 -26.42518) (xy 63.370769 -26.463126) (xy 63.30651 -26.494071)
			(xy 63.23919 -26.517628) (xy 63.169655 -26.533498) (xy 63.098781 -26.541484) (xy 63.027459 -26.541484)
			(xy 62.956585 -26.533498) (xy 62.88705 -26.517628) (xy 62.81973 -26.494071) (xy 62.755471 -26.463126)
			(xy 62.69508 -26.42518) (xy 62.639318 -26.380711) (xy 62.588885 -26.330278) (xy 62.544416 -26.274516)
			(xy 62.50647 -26.214125) (xy 62.475525 -26.149866) (xy 62.451968 -26.082546) (xy 62.436098 -26.013011)
			(xy 62.428112 -25.942137) (xy 61.794144 -25.942137) (xy 61.786158 -26.013011) (xy 61.770288 -26.082546)
			(xy 61.746731 -26.149866) (xy 61.715786 -26.214125) (xy 61.67784 -26.274516) (xy 61.633371 -26.330278)
			(xy 61.582938 -26.380711) (xy 61.527176 -26.42518) (xy 61.466785 -26.463126) (xy 61.402526 -26.494071)
			(xy 61.335206 -26.517628) (xy 61.265671 -26.533498) (xy 61.194797 -26.541484) (xy 61.123475 -26.541484)
			(xy 61.052601 -26.533498) (xy 60.983066 -26.517628) (xy 60.915746 -26.494071) (xy 60.851487 -26.463126)
			(xy 60.791096 -26.42518) (xy 60.735334 -26.380711) (xy 60.684901 -26.330278) (xy 60.640432 -26.274516)
			(xy 60.602486 -26.214125) (xy 60.571541 -26.149866) (xy 60.547984 -26.082546) (xy 60.532114 -26.013011)
			(xy 60.524128 -25.942137) (xy 25.087987 -25.942137) (xy 24.77643 -26.253694) (xy 24.766907 -26.264818)
			(xy 24.75272 -26.290425) (xy 24.744748 -26.318593) (xy 24.743664 -26.333196) (xy 24.743664 -27.493484)
			(xy 29.519874 -27.493484) (xy 29.519874 -27.406584) (xy 29.527892 -27.320055) (xy 29.54386 -27.234635)
			(xy 29.567641 -27.151053) (xy 29.599033 -27.070021) (xy 29.637767 -26.992232) (xy 29.683514 -26.918348)
			(xy 29.735883 -26.849001) (xy 29.794427 -26.784781) (xy 29.858647 -26.726237) (xy 29.927994 -26.673868)
			(xy 30.001878 -26.628121) (xy 30.079667 -26.589387) (xy 30.160699 -26.557995) (xy 30.244281 -26.534214)
			(xy 30.329701 -26.518246) (xy 30.41623 -26.510228) (xy 30.50313 -26.510228) (xy 30.589659 -26.518246)
			(xy 30.675079 -26.534214) (xy 30.758661 -26.557995) (xy 30.839693 -26.589387) (xy 30.917482 -26.628121)
			(xy 30.991366 -26.673868) (xy 31.060713 -26.726237) (xy 31.124933 -26.784781) (xy 31.183477 -26.849001)
			(xy 31.235846 -26.918348) (xy 31.281593 -26.992232) (xy 31.320327 -27.070021) (xy 31.351719 -27.151053)
			(xy 31.3755 -27.234635) (xy 31.391468 -27.320055) (xy 31.399486 -27.406584) (xy 31.399988 -27.450034)
			(xy 31.399486 -27.493484) (xy 34.599874 -27.493484) (xy 34.599874 -27.406584) (xy 34.607892 -27.320055)
			(xy 34.62386 -27.234635) (xy 34.647641 -27.151053) (xy 34.679033 -27.070021) (xy 34.717767 -26.992232)
			(xy 34.763514 -26.918348) (xy 34.815883 -26.849001) (xy 34.874427 -26.784781) (xy 34.938647 -26.726237)
			(xy 35.007994 -26.673868) (xy 35.081878 -26.628121) (xy 35.159667 -26.589387) (xy 35.240699 -26.557995)
			(xy 35.324281 -26.534214) (xy 35.409701 -26.518246) (xy 35.49623 -26.510228) (xy 35.58313 -26.510228)
			(xy 35.669659 -26.518246) (xy 35.755079 -26.534214) (xy 35.838661 -26.557995) (xy 35.919693 -26.589387)
			(xy 35.997482 -26.628121) (xy 36.071366 -26.673868) (xy 36.140713 -26.726237) (xy 36.204933 -26.784781)
			(xy 36.263477 -26.849001) (xy 36.315846 -26.918348) (xy 36.361593 -26.992232) (xy 36.400327 -27.070021)
			(xy 36.431719 -27.151053) (xy 36.4555 -27.234635) (xy 36.471468 -27.320055) (xy 36.479486 -27.406584)
			(xy 36.479988 -27.450034) (xy 36.479486 -27.493484) (xy 36.471468 -27.580013) (xy 36.4555 -27.665433)
			(xy 36.431719 -27.749015) (xy 36.400327 -27.830047) (xy 36.361593 -27.907836) (xy 36.315846 -27.98172)
			(xy 36.263477 -28.051067) (xy 36.204933 -28.115287) (xy 36.140713 -28.173831) (xy 36.071366 -28.2262)
			(xy 35.997482 -28.271947) (xy 35.919693 -28.310681) (xy 35.86198 -28.333039) (xy 41.655992 -28.333039)
			(xy 41.655992 -28.261717) (xy 41.663978 -28.190843) (xy 41.679848 -28.121308) (xy 41.703405 -28.053988)
			(xy 41.73435 -27.989729) (xy 41.772296 -27.929338) (xy 41.816765 -27.873576) (xy 41.867198 -27.823143)
			(xy 41.92296 -27.778674) (xy 41.983351 -27.740728) (xy 42.04761 -27.709783) (xy 42.11493 -27.686226)
			(xy 42.184465 -27.670356) (xy 42.255339 -27.66237) (xy 42.326661 -27.66237) (xy 42.397535 -27.670356)
			(xy 42.46707 -27.686226) (xy 42.53439 -27.709783) (xy 42.598649 -27.740728) (xy 42.65904 -27.778674)
			(xy 42.714802 -27.823143) (xy 42.765235 -27.873576) (xy 42.809704 -27.929338) (xy 42.84765 -27.989729)
			(xy 42.878595 -28.053988) (xy 42.902152 -28.121308) (xy 42.918022 -28.190843) (xy 42.926008 -28.261717)
			(xy 42.926508 -28.297378) (xy 42.926008 -28.333039) (xy 43.542704 -28.333039) (xy 43.542704 -28.261717)
			(xy 43.55069 -28.190843) (xy 43.56656 -28.121308) (xy 43.590117 -28.053988) (xy 43.621062 -27.989729)
			(xy 43.659008 -27.929338) (xy 43.703477 -27.873576) (xy 43.75391 -27.823143) (xy 43.809672 -27.778674)
			(xy 43.870063 -27.740728) (xy 43.934322 -27.709783) (xy 44.001642 -27.686226) (xy 44.071177 -27.670356)
			(xy 44.142051 -27.66237) (xy 44.213373 -27.66237) (xy 44.284247 -27.670356) (xy 44.353782 -27.686226)
			(xy 44.421102 -27.709783) (xy 44.485361 -27.740728) (xy 44.545752 -27.778674) (xy 44.601514 -27.823143)
			(xy 44.651947 -27.873576) (xy 44.696416 -27.929338) (xy 44.734362 -27.989729) (xy 44.765307 -28.053988)
			(xy 44.788864 -28.121308) (xy 44.804734 -28.190843) (xy 44.81272 -28.261717) (xy 44.81322 -28.297378)
			(xy 44.81272 -28.333039) (xy 44.804734 -28.403913) (xy 44.788864 -28.473448) (xy 44.765307 -28.540768)
			(xy 44.734362 -28.605027) (xy 44.696416 -28.665418) (xy 44.651947 -28.72118) (xy 44.601514 -28.771613)
			(xy 44.545752 -28.816082) (xy 44.485361 -28.854028) (xy 44.421102 -28.884973) (xy 44.353782 -28.90853)
			(xy 44.284247 -28.9244) (xy 44.213373 -28.932386) (xy 44.142051 -28.932386) (xy 44.071177 -28.9244)
			(xy 44.001642 -28.90853) (xy 43.934322 -28.884973) (xy 43.870063 -28.854028) (xy 43.809672 -28.816082)
			(xy 43.75391 -28.771613) (xy 43.703477 -28.72118) (xy 43.659008 -28.665418) (xy 43.621062 -28.605027)
			(xy 43.590117 -28.540768) (xy 43.56656 -28.473448) (xy 43.55069 -28.403913) (xy 43.542704 -28.333039)
			(xy 42.926008 -28.333039) (xy 42.918022 -28.403913) (xy 42.902152 -28.473448) (xy 42.878595 -28.540768)
			(xy 42.84765 -28.605027) (xy 42.809704 -28.665418) (xy 42.765235 -28.72118) (xy 42.714802 -28.771613)
			(xy 42.65904 -28.816082) (xy 42.598649 -28.854028) (xy 42.53439 -28.884973) (xy 42.46707 -28.90853)
			(xy 42.397535 -28.9244) (xy 42.326661 -28.932386) (xy 42.255339 -28.932386) (xy 42.184465 -28.9244)
			(xy 42.11493 -28.90853) (xy 42.04761 -28.884973) (xy 41.983351 -28.854028) (xy 41.92296 -28.816082)
			(xy 41.867198 -28.771613) (xy 41.816765 -28.72118) (xy 41.772296 -28.665418) (xy 41.73435 -28.605027)
			(xy 41.703405 -28.540768) (xy 41.679848 -28.473448) (xy 41.663978 -28.403913) (xy 41.655992 -28.333039)
			(xy 35.86198 -28.333039) (xy 35.838661 -28.342073) (xy 35.755079 -28.365854) (xy 35.669659 -28.381822)
			(xy 35.58313 -28.38984) (xy 35.49623 -28.38984) (xy 35.409701 -28.381822) (xy 35.324281 -28.365854)
			(xy 35.240699 -28.342073) (xy 35.159667 -28.310681) (xy 35.081878 -28.271947) (xy 35.007994 -28.2262)
			(xy 34.938647 -28.173831) (xy 34.874427 -28.115287) (xy 34.815883 -28.051067) (xy 34.763514 -27.98172)
			(xy 34.717767 -27.907836) (xy 34.679033 -27.830047) (xy 34.647641 -27.749015) (xy 34.62386 -27.665433)
			(xy 34.607892 -27.580013) (xy 34.599874 -27.493484) (xy 31.399486 -27.493484) (xy 31.391468 -27.580013)
			(xy 31.3755 -27.665433) (xy 31.351719 -27.749015) (xy 31.320327 -27.830047) (xy 31.281593 -27.907836)
			(xy 31.235846 -27.98172) (xy 31.183477 -28.051067) (xy 31.124933 -28.115287) (xy 31.060713 -28.173831)
			(xy 30.991366 -28.2262) (xy 30.917482 -28.271947) (xy 30.839693 -28.310681) (xy 30.758661 -28.342073)
			(xy 30.675079 -28.365854) (xy 30.589659 -28.381822) (xy 30.50313 -28.38984) (xy 30.41623 -28.38984)
			(xy 30.329701 -28.381822) (xy 30.244281 -28.365854) (xy 30.160699 -28.342073) (xy 30.079667 -28.310681)
			(xy 30.001878 -28.271947) (xy 29.927994 -28.2262) (xy 29.858647 -28.173831) (xy 29.794427 -28.115287)
			(xy 29.735883 -28.051067) (xy 29.683514 -27.98172) (xy 29.637767 -27.907836) (xy 29.599033 -27.830047)
			(xy 29.567641 -27.749015) (xy 29.54386 -27.665433) (xy 29.527892 -27.580013) (xy 29.519874 -27.493484)
			(xy 24.743664 -27.493484) (xy 24.743664 -30.033484) (xy 29.519874 -30.033484) (xy 29.519874 -29.946584)
			(xy 29.527892 -29.860055) (xy 29.54386 -29.774635) (xy 29.567641 -29.691053) (xy 29.599033 -29.610021)
			(xy 29.637767 -29.532232) (xy 29.683514 -29.458348) (xy 29.735883 -29.389001) (xy 29.794427 -29.324781)
			(xy 29.858647 -29.266237) (xy 29.927994 -29.213868) (xy 30.001878 -29.168121) (xy 30.079667 -29.129387)
			(xy 30.160699 -29.097995) (xy 30.244281 -29.074214) (xy 30.329701 -29.058246) (xy 30.41623 -29.050228)
			(xy 30.50313 -29.050228) (xy 30.589659 -29.058246) (xy 30.675079 -29.074214) (xy 30.758661 -29.097995)
			(xy 30.839693 -29.129387) (xy 30.917482 -29.168121) (xy 30.991366 -29.213868) (xy 31.060713 -29.266237)
			(xy 31.124933 -29.324781) (xy 31.183477 -29.389001) (xy 31.235846 -29.458348) (xy 31.281593 -29.532232)
			(xy 31.320327 -29.610021) (xy 31.351719 -29.691053) (xy 31.3755 -29.774635) (xy 31.391468 -29.860055)
			(xy 31.399486 -29.946584) (xy 31.399988 -29.990034) (xy 31.399486 -30.033484) (xy 34.599874 -30.033484)
			(xy 34.599874 -29.946584) (xy 34.607892 -29.860055) (xy 34.62386 -29.774635) (xy 34.647641 -29.691053)
			(xy 34.679033 -29.610021) (xy 34.717767 -29.532232) (xy 34.763514 -29.458348) (xy 34.815883 -29.389001)
			(xy 34.874427 -29.324781) (xy 34.938647 -29.266237) (xy 35.007994 -29.213868) (xy 35.081878 -29.168121)
			(xy 35.159667 -29.129387) (xy 35.240699 -29.097995) (xy 35.324281 -29.074214) (xy 35.409701 -29.058246)
			(xy 35.49623 -29.050228) (xy 35.58313 -29.050228) (xy 35.669659 -29.058246) (xy 35.755079 -29.074214)
			(xy 35.838661 -29.097995) (xy 35.919693 -29.129387) (xy 35.997482 -29.168121) (xy 36.071366 -29.213868)
			(xy 36.140713 -29.266237) (xy 36.204933 -29.324781) (xy 36.229734 -29.351986) (xy 64.927732 -29.351986)
			(xy 64.931803 -29.296364) (xy 64.943929 -29.241927) (xy 64.963852 -29.189836) (xy 64.991148 -29.141201)
			(xy 65.025234 -29.097058) (xy 65.065383 -29.058349) (xy 65.110741 -29.025898) (xy 65.160341 -29.000397)
			(xy 65.213125 -28.98239) (xy 65.267968 -28.97226) (xy 65.323702 -28.970223) (xy 65.379139 -28.976323)
			(xy 65.433096 -28.990429) (xy 65.484425 -29.012241) (xy 65.532031 -29.041295) (xy 65.574899 -29.07697)
			(xy 65.612116 -29.118507) (xy 65.642889 -29.16502) (xy 65.666561 -29.215517) (xy 65.682629 -29.268924)
			(xy 65.690749 -29.3241) (xy 65.691258 -29.351986) (xy 67.59524 -29.351986) (xy 67.599311 -29.296364)
			(xy 67.611437 -29.241927) (xy 67.63136 -29.189836) (xy 67.658656 -29.141201) (xy 67.692742 -29.097058)
			(xy 67.732891 -29.058349) (xy 67.778249 -29.025898) (xy 67.827849 -29.000397) (xy 67.880633 -28.98239)
			(xy 67.935476 -28.97226) (xy 67.99121 -28.970223) (xy 68.046647 -28.976323) (xy 68.100604 -28.990429)
			(xy 68.151933 -29.012241) (xy 68.199539 -29.041295) (xy 68.242407 -29.07697) (xy 68.279624 -29.118507)
			(xy 68.310397 -29.16502) (xy 68.334069 -29.215517) (xy 68.350137 -29.268924) (xy 68.358257 -29.3241)
			(xy 68.358766 -29.351986) (xy 68.358257 -29.379872) (xy 68.350137 -29.435048) (xy 68.334069 -29.488455)
			(xy 68.310397 -29.538952) (xy 68.279624 -29.585465) (xy 68.242407 -29.627002) (xy 68.199539 -29.662677)
			(xy 68.151933 -29.691731) (xy 68.100604 -29.713543) (xy 68.046647 -29.727649) (xy 67.99121 -29.733749)
			(xy 67.935476 -29.731712) (xy 67.880633 -29.721582) (xy 67.827849 -29.703575) (xy 67.778249 -29.678074)
			(xy 67.732891 -29.645623) (xy 67.692742 -29.606914) (xy 67.658656 -29.562771) (xy 67.63136 -29.514136)
			(xy 67.611437 -29.462045) (xy 67.599311 -29.407608) (xy 67.59524 -29.351986) (xy 65.691258 -29.351986)
			(xy 65.690749 -29.379872) (xy 65.682629 -29.435048) (xy 65.666561 -29.488455) (xy 65.642889 -29.538952)
			(xy 65.612116 -29.585465) (xy 65.574899 -29.627002) (xy 65.532031 -29.662677) (xy 65.484425 -29.691731)
			(xy 65.433096 -29.713543) (xy 65.379139 -29.727649) (xy 65.323702 -29.733749) (xy 65.267968 -29.731712)
			(xy 65.213125 -29.721582) (xy 65.160341 -29.703575) (xy 65.110741 -29.678074) (xy 65.065383 -29.645623)
			(xy 65.025234 -29.606914) (xy 64.991148 -29.562771) (xy 64.963852 -29.514136) (xy 64.943929 -29.462045)
			(xy 64.931803 -29.407608) (xy 64.927732 -29.351986) (xy 36.229734 -29.351986) (xy 36.263477 -29.389001)
			(xy 36.315846 -29.458348) (xy 36.361593 -29.532232) (xy 36.400327 -29.610021) (xy 36.431719 -29.691053)
			(xy 36.4555 -29.774635) (xy 36.471468 -29.860055) (xy 36.479486 -29.946584) (xy 36.479988 -29.990034)
			(xy 36.479486 -30.033484) (xy 36.471468 -30.120013) (xy 36.462747 -30.166665) (xy 41.655992 -30.166665)
			(xy 41.655992 -30.095343) (xy 41.663978 -30.024469) (xy 41.679848 -29.954934) (xy 41.703405 -29.887614)
			(xy 41.73435 -29.823355) (xy 41.772296 -29.762964) (xy 41.816765 -29.707202) (xy 41.867198 -29.656769)
			(xy 41.92296 -29.6123) (xy 41.983351 -29.574354) (xy 42.04761 -29.543409) (xy 42.11493 -29.519852)
			(xy 42.184465 -29.503982) (xy 42.255339 -29.495996) (xy 42.326661 -29.495996) (xy 42.397535 -29.503982)
			(xy 42.46707 -29.519852) (xy 42.53439 -29.543409) (xy 42.598649 -29.574354) (xy 42.65904 -29.6123)
			(xy 42.714802 -29.656769) (xy 42.765235 -29.707202) (xy 42.809704 -29.762964) (xy 42.84765 -29.823355)
			(xy 42.878595 -29.887614) (xy 42.902152 -29.954934) (xy 42.918022 -30.024469) (xy 42.926008 -30.095343)
			(xy 42.926508 -30.131004) (xy 42.926008 -30.166665) (xy 43.542704 -30.166665) (xy 43.542704 -30.095343)
			(xy 43.55069 -30.024469) (xy 43.56656 -29.954934) (xy 43.590117 -29.887614) (xy 43.621062 -29.823355)
			(xy 43.659008 -29.762964) (xy 43.703477 -29.707202) (xy 43.75391 -29.656769) (xy 43.809672 -29.6123)
			(xy 43.870063 -29.574354) (xy 43.934322 -29.543409) (xy 44.001642 -29.519852) (xy 44.071177 -29.503982)
			(xy 44.142051 -29.495996) (xy 44.213373 -29.495996) (xy 44.284247 -29.503982) (xy 44.353782 -29.519852)
			(xy 44.421102 -29.543409) (xy 44.485361 -29.574354) (xy 44.545752 -29.6123) (xy 44.601514 -29.656769)
			(xy 44.651947 -29.707202) (xy 44.696416 -29.762964) (xy 44.734362 -29.823355) (xy 44.765307 -29.887614)
			(xy 44.788864 -29.954934) (xy 44.804734 -30.024469) (xy 44.81272 -30.095343) (xy 44.81322 -30.131004)
			(xy 44.81272 -30.166665) (xy 44.804734 -30.237539) (xy 44.788864 -30.307074) (xy 44.765307 -30.374394)
			(xy 44.734362 -30.438653) (xy 44.696416 -30.499044) (xy 44.651947 -30.554806) (xy 44.601514 -30.605239)
			(xy 44.545752 -30.649708) (xy 44.485361 -30.687654) (xy 44.421102 -30.718599) (xy 44.353782 -30.742156)
			(xy 44.284247 -30.758026) (xy 44.213373 -30.766012) (xy 44.142051 -30.766012) (xy 44.071177 -30.758026)
			(xy 44.001642 -30.742156) (xy 43.934322 -30.718599) (xy 43.870063 -30.687654) (xy 43.809672 -30.649708)
			(xy 43.75391 -30.605239) (xy 43.703477 -30.554806) (xy 43.659008 -30.499044) (xy 43.621062 -30.438653)
			(xy 43.590117 -30.374394) (xy 43.56656 -30.307074) (xy 43.55069 -30.237539) (xy 43.542704 -30.166665)
			(xy 42.926008 -30.166665) (xy 42.918022 -30.237539) (xy 42.902152 -30.307074) (xy 42.878595 -30.374394)
			(xy 42.84765 -30.438653) (xy 42.809704 -30.499044) (xy 42.765235 -30.554806) (xy 42.714802 -30.605239)
			(xy 42.65904 -30.649708) (xy 42.598649 -30.687654) (xy 42.53439 -30.718599) (xy 42.46707 -30.742156)
			(xy 42.397535 -30.758026) (xy 42.326661 -30.766012) (xy 42.255339 -30.766012) (xy 42.184465 -30.758026)
			(xy 42.11493 -30.742156) (xy 42.04761 -30.718599) (xy 41.983351 -30.687654) (xy 41.92296 -30.649708)
			(xy 41.867198 -30.605239) (xy 41.816765 -30.554806) (xy 41.772296 -30.499044) (xy 41.73435 -30.438653)
			(xy 41.703405 -30.374394) (xy 41.679848 -30.307074) (xy 41.663978 -30.237539) (xy 41.655992 -30.166665)
			(xy 36.462747 -30.166665) (xy 36.4555 -30.205433) (xy 36.431719 -30.289015) (xy 36.400327 -30.370047)
			(xy 36.361593 -30.447836) (xy 36.315846 -30.52172) (xy 36.263477 -30.591067) (xy 36.204933 -30.655287)
			(xy 36.140713 -30.713831) (xy 36.071366 -30.7662) (xy 35.997482 -30.811947) (xy 35.919693 -30.850681)
			(xy 35.838661 -30.882073) (xy 35.755079 -30.905854) (xy 35.669659 -30.921822) (xy 35.58313 -30.92984)
			(xy 35.49623 -30.92984) (xy 35.409701 -30.921822) (xy 35.324281 -30.905854) (xy 35.240699 -30.882073)
			(xy 35.159667 -30.850681) (xy 35.081878 -30.811947) (xy 35.007994 -30.7662) (xy 34.938647 -30.713831)
			(xy 34.874427 -30.655287) (xy 34.815883 -30.591067) (xy 34.763514 -30.52172) (xy 34.717767 -30.447836)
			(xy 34.679033 -30.370047) (xy 34.647641 -30.289015) (xy 34.62386 -30.205433) (xy 34.607892 -30.120013)
			(xy 34.599874 -30.033484) (xy 31.399486 -30.033484) (xy 31.391468 -30.120013) (xy 31.3755 -30.205433)
			(xy 31.351719 -30.289015) (xy 31.320327 -30.370047) (xy 31.281593 -30.447836) (xy 31.235846 -30.52172)
			(xy 31.183477 -30.591067) (xy 31.124933 -30.655287) (xy 31.060713 -30.713831) (xy 30.991366 -30.7662)
			(xy 30.917482 -30.811947) (xy 30.839693 -30.850681) (xy 30.758661 -30.882073) (xy 30.675079 -30.905854)
			(xy 30.589659 -30.921822) (xy 30.50313 -30.92984) (xy 30.41623 -30.92984) (xy 30.329701 -30.921822)
			(xy 30.244281 -30.905854) (xy 30.160699 -30.882073) (xy 30.079667 -30.850681) (xy 30.001878 -30.811947)
			(xy 29.927994 -30.7662) (xy 29.858647 -30.713831) (xy 29.794427 -30.655287) (xy 29.735883 -30.591067)
			(xy 29.683514 -30.52172) (xy 29.637767 -30.447836) (xy 29.599033 -30.370047) (xy 29.567641 -30.289015)
			(xy 29.54386 -30.205433) (xy 29.527892 -30.120013) (xy 29.519874 -30.033484) (xy 24.743664 -30.033484)
			(xy 24.743664 -32.573484) (xy 29.519874 -32.573484) (xy 29.519874 -32.486584) (xy 29.527892 -32.400055)
			(xy 29.54386 -32.314635) (xy 29.567641 -32.231053) (xy 29.599033 -32.150021) (xy 29.637767 -32.072232)
			(xy 29.683514 -31.998348) (xy 29.735883 -31.929001) (xy 29.794427 -31.864781) (xy 29.858647 -31.806237)
			(xy 29.927994 -31.753868) (xy 30.001878 -31.708121) (xy 30.079667 -31.669387) (xy 30.160699 -31.637995)
			(xy 30.244281 -31.614214) (xy 30.329701 -31.598246) (xy 30.41623 -31.590228) (xy 30.50313 -31.590228)
			(xy 30.589659 -31.598246) (xy 30.675079 -31.614214) (xy 30.758661 -31.637995) (xy 30.839693 -31.669387)
			(xy 30.917482 -31.708121) (xy 30.991366 -31.753868) (xy 31.060713 -31.806237) (xy 31.124933 -31.864781)
			(xy 31.183477 -31.929001) (xy 31.235846 -31.998348) (xy 31.281593 -32.072232) (xy 31.320327 -32.150021)
			(xy 31.351719 -32.231053) (xy 31.3755 -32.314635) (xy 31.391468 -32.400055) (xy 31.399486 -32.486584)
			(xy 31.399988 -32.530034) (xy 31.399486 -32.573484) (xy 34.599874 -32.573484) (xy 34.599874 -32.486584)
			(xy 34.607892 -32.400055) (xy 34.62386 -32.314635) (xy 34.647641 -32.231053) (xy 34.679033 -32.150021)
			(xy 34.717767 -32.072232) (xy 34.763514 -31.998348) (xy 34.815883 -31.929001) (xy 34.874427 -31.864781)
			(xy 34.938647 -31.806237) (xy 35.007994 -31.753868) (xy 35.081878 -31.708121) (xy 35.159667 -31.669387)
			(xy 35.240699 -31.637995) (xy 35.324281 -31.614214) (xy 35.409701 -31.598246) (xy 35.49623 -31.590228)
			(xy 35.58313 -31.590228) (xy 35.669659 -31.598246) (xy 35.755079 -31.614214) (xy 35.838661 -31.637995)
			(xy 35.919693 -31.669387) (xy 35.997482 -31.708121) (xy 36.071366 -31.753868) (xy 36.140713 -31.806237)
			(xy 36.204933 -31.864781) (xy 36.263477 -31.929001) (xy 36.315846 -31.998348) (xy 36.358726 -32.067601)
			(xy 41.655992 -32.067601) (xy 41.655992 -31.996279) (xy 41.663978 -31.925405) (xy 41.679848 -31.85587)
			(xy 41.703405 -31.78855) (xy 41.73435 -31.724291) (xy 41.772296 -31.6639) (xy 41.816765 -31.608138)
			(xy 41.867198 -31.557705) (xy 41.92296 -31.513236) (xy 41.983351 -31.47529) (xy 42.04761 -31.444345)
			(xy 42.11493 -31.420788) (xy 42.184465 -31.404918) (xy 42.255339 -31.396932) (xy 42.326661 -31.396932)
			(xy 42.397535 -31.404918) (xy 42.46707 -31.420788) (xy 42.53439 -31.444345) (xy 42.598649 -31.47529)
			(xy 42.65904 -31.513236) (xy 42.714802 -31.557705) (xy 42.765235 -31.608138) (xy 42.809704 -31.6639)
			(xy 42.84765 -31.724291) (xy 42.878595 -31.78855) (xy 42.902152 -31.85587) (xy 42.918022 -31.925405)
			(xy 42.926008 -31.996279) (xy 42.926508 -32.03194) (xy 42.926008 -32.067601) (xy 43.542704 -32.067601)
			(xy 43.542704 -31.996279) (xy 43.55069 -31.925405) (xy 43.56656 -31.85587) (xy 43.590117 -31.78855)
			(xy 43.621062 -31.724291) (xy 43.659008 -31.6639) (xy 43.703477 -31.608138) (xy 43.75391 -31.557705)
			(xy 43.809672 -31.513236) (xy 43.870063 -31.47529) (xy 43.934322 -31.444345) (xy 44.001642 -31.420788)
			(xy 44.071177 -31.404918) (xy 44.142051 -31.396932) (xy 44.213373 -31.396932) (xy 44.284247 -31.404918)
			(xy 44.353782 -31.420788) (xy 44.421102 -31.444345) (xy 44.485361 -31.47529) (xy 44.545752 -31.513236)
			(xy 44.601514 -31.557705) (xy 44.651947 -31.608138) (xy 44.696416 -31.6639) (xy 44.734362 -31.724291)
			(xy 44.765307 -31.78855) (xy 44.788864 -31.85587) (xy 44.804734 -31.925405) (xy 44.81272 -31.996279)
			(xy 44.81322 -32.03194) (xy 44.81272 -32.067601) (xy 44.804734 -32.138475) (xy 44.788864 -32.20801)
			(xy 44.765307 -32.27533) (xy 44.734362 -32.339589) (xy 44.696416 -32.39998) (xy 44.651947 -32.455742)
			(xy 44.601514 -32.506175) (xy 44.545752 -32.550644) (xy 44.495683 -32.582104) (xy 64.88252 -32.582104)
			(xy 64.886591 -32.526482) (xy 64.898717 -32.472045) (xy 64.91864 -32.419954) (xy 64.945936 -32.371319)
			(xy 64.980022 -32.327176) (xy 65.020171 -32.288467) (xy 65.065529 -32.256016) (xy 65.115129 -32.230515)
			(xy 65.167913 -32.212508) (xy 65.222756 -32.202378) (xy 65.27849 -32.200341) (xy 65.333927 -32.206441)
			(xy 65.387884 -32.220547) (xy 65.439213 -32.242359) (xy 65.486819 -32.271413) (xy 65.520757 -32.299656)
			(xy 72.868035 -32.299656) (xy 72.872042 -32.096906) (xy 72.884055 -31.894472) (xy 72.904056 -31.692671)
			(xy 72.932015 -31.491817) (xy 72.967886 -31.292225) (xy 73.011615 -31.094206) (xy 73.063133 -30.898069)
			(xy 73.122359 -30.704121) (xy 73.189201 -30.512663) (xy 73.263555 -30.323996) (xy 73.345304 -30.138414)
			(xy 73.434322 -29.956206) (xy 73.530468 -29.777657) (xy 73.633593 -29.603046) (xy 73.743536 -29.432646)
			(xy 73.860125 -29.266722) (xy 73.983178 -29.105533) (xy 74.112503 -28.949332) (xy 74.247898 -28.798362)
			(xy 74.389151 -28.652858) (xy 74.536043 -28.513049) (xy 74.688343 -28.379152) (xy 74.845814 -28.251377)
			(xy 75.008211 -28.129922) (xy 75.175278 -28.014978) (xy 75.346757 -27.906724) (xy 75.522378 -27.805329)
			(xy 75.701868 -27.710951) (xy 75.884946 -27.623739) (xy 76.071327 -27.543827) (xy 76.26072 -27.47134)
			(xy 76.452828 -27.406393) (xy 76.647352 -27.349085) (xy 76.843988 -27.299508) (xy 77.04243 -27.257737)
			(xy 77.242367 -27.223839) (xy 77.443486 -27.197867) (xy 77.645475 -27.17986) (xy 77.848018 -27.169847)
			(xy 78.050798 -27.167843) (xy 78.253499 -27.173853) (xy 78.455804 -27.187865) (xy 78.657398 -27.20986)
			(xy 78.857965 -27.239801) (xy 79.057193 -27.277642) (xy 79.254771 -27.323325) (xy 79.450389 -27.376778)
			(xy 79.643743 -27.437917) (xy 79.834531 -27.506648) (xy 80.022454 -27.582862) (xy 80.20722 -27.666441)
			(xy 80.388539 -27.757254) (xy 80.56613 -27.855159) (xy 80.739713 -27.960004) (xy 80.909019 -28.071625)
			(xy 81.073784 -28.189847) (xy 81.233749 -28.314487) (xy 81.388665 -28.445348) (xy 81.53829 -28.582228)
			(xy 81.68239 -28.724912) (xy 81.820742 -28.873178) (xy 81.953127 -29.026794) (xy 82.079341 -29.185519)
			(xy 82.199185 -29.349108) (xy 82.312473 -29.517303) (xy 82.419028 -29.689842) (xy 82.518683 -29.866457)
			(xy 82.611283 -30.04687) (xy 82.696683 -30.230801) (xy 82.77475 -30.417962) (xy 82.845362 -30.608062)
			(xy 82.908408 -30.800802) (xy 82.963791 -30.995883) (xy 83.011423 -31.193) (xy 83.051231 -31.391844)
			(xy 83.083153 -31.592106) (xy 83.107137 -31.793472) (xy 83.123148 -31.995629) (xy 83.131159 -32.198261)
			(xy 83.13166 -32.299656) (xy 83.131159 -32.401051) (xy 83.123148 -32.603683) (xy 83.107137 -32.80584)
			(xy 83.083153 -33.007206) (xy 83.051231 -33.207468) (xy 83.011423 -33.406312) (xy 82.963791 -33.603429)
			(xy 82.908408 -33.79851) (xy 82.845362 -33.99125) (xy 82.77475 -34.18135) (xy 82.696683 -34.368511)
			(xy 82.611283 -34.552442) (xy 82.518683 -34.732855) (xy 82.419028 -34.90947) (xy 82.312473 -35.082009)
			(xy 82.199185 -35.250204) (xy 82.079341 -35.413793) (xy 81.953127 -35.572518) (xy 81.820742 -35.726134)
			(xy 81.68239 -35.8744) (xy 81.53829 -36.017084) (xy 81.388665 -36.153964) (xy 81.233749 -36.284825)
			(xy 81.073784 -36.409465) (xy 80.909019 -36.527687) (xy 80.739713 -36.639308) (xy 80.56613 -36.744153)
			(xy 80.388539 -36.842058) (xy 80.20722 -36.932871) (xy 80.022454 -37.01645) (xy 79.834531 -37.092664)
			(xy 79.643743 -37.161395) (xy 79.450389 -37.222534) (xy 79.254771 -37.275987) (xy 79.057193 -37.32167)
			(xy 78.857965 -37.359511) (xy 78.657398 -37.389452) (xy 78.455804 -37.411447) (xy 78.253499 -37.425459)
			(xy 78.050798 -37.431469) (xy 77.848018 -37.429465) (xy 77.645475 -37.419452) (xy 77.443486 -37.401445)
			(xy 77.242367 -37.375473) (xy 77.04243 -37.341575) (xy 76.843988 -37.299804) (xy 76.647352 -37.250227)
			(xy 76.452828 -37.192919) (xy 76.26072 -37.127972) (xy 76.071327 -37.055485) (xy 75.884946 -36.975573)
			(xy 75.701868 -36.888361) (xy 75.522378 -36.793983) (xy 75.346757 -36.692588) (xy 75.175278 -36.584334)
			(xy 75.008211 -36.46939) (xy 74.845814 -36.347935) (xy 74.688343 -36.22016) (xy 74.536043 -36.086263)
			(xy 74.389151 -35.946454) (xy 74.247898 -35.80095) (xy 74.112503 -35.64998) (xy 73.983178 -35.493779)
			(xy 73.860125 -35.33259) (xy 73.743536 -35.166666) (xy 73.633593 -34.996266) (xy 73.530468 -34.821655)
			(xy 73.434322 -34.643106) (xy 73.345304 -34.460898) (xy 73.263555 -34.275316) (xy 73.189201 -34.086649)
			(xy 73.122359 -33.895191) (xy 73.063133 -33.701243) (xy 73.011615 -33.505106) (xy 72.967886 -33.307087)
			(xy 72.932015 -33.107495) (xy 72.904056 -32.906641) (xy 72.884055 -32.70484) (xy 72.872042 -32.502406)
			(xy 72.868035 -32.299656) (xy 65.520757 -32.299656) (xy 65.529687 -32.307088) (xy 65.566904 -32.348625)
			(xy 65.597677 -32.395138) (xy 65.621349 -32.445635) (xy 65.637417 -32.499042) (xy 65.645537 -32.554218)
			(xy 65.646046 -32.582104) (xy 65.645537 -32.60999) (xy 65.637417 -32.665166) (xy 65.621349 -32.718573)
			(xy 65.597677 -32.76907) (xy 65.566904 -32.815583) (xy 65.529687 -32.85712) (xy 65.486819 -32.892795)
			(xy 65.439213 -32.921849) (xy 65.387884 -32.943661) (xy 65.333927 -32.957767) (xy 65.27849 -32.963867)
			(xy 65.222756 -32.96183) (xy 65.167913 -32.9517) (xy 65.115129 -32.933693) (xy 65.065529 -32.908192)
			(xy 65.020171 -32.875741) (xy 64.980022 -32.837032) (xy 64.945936 -32.792889) (xy 64.91864 -32.744254)
			(xy 64.898717 -32.692163) (xy 64.886591 -32.637726) (xy 64.88252 -32.582104) (xy 44.495683 -32.582104)
			(xy 44.485361 -32.58859) (xy 44.421102 -32.619535) (xy 44.353782 -32.643092) (xy 44.284247 -32.658962)
			(xy 44.213373 -32.666948) (xy 44.142051 -32.666948) (xy 44.071177 -32.658962) (xy 44.001642 -32.643092)
			(xy 43.934322 -32.619535) (xy 43.870063 -32.58859) (xy 43.809672 -32.550644) (xy 43.75391 -32.506175)
			(xy 43.703477 -32.455742) (xy 43.659008 -32.39998) (xy 43.621062 -32.339589) (xy 43.590117 -32.27533)
			(xy 43.56656 -32.20801) (xy 43.55069 -32.138475) (xy 43.542704 -32.067601) (xy 42.926008 -32.067601)
			(xy 42.918022 -32.138475) (xy 42.902152 -32.20801) (xy 42.878595 -32.27533) (xy 42.84765 -32.339589)
			(xy 42.809704 -32.39998) (xy 42.765235 -32.455742) (xy 42.714802 -32.506175) (xy 42.65904 -32.550644)
			(xy 42.598649 -32.58859) (xy 42.53439 -32.619535) (xy 42.46707 -32.643092) (xy 42.397535 -32.658962)
			(xy 42.326661 -32.666948) (xy 42.255339 -32.666948) (xy 42.184465 -32.658962) (xy 42.11493 -32.643092)
			(xy 42.04761 -32.619535) (xy 41.983351 -32.58859) (xy 41.92296 -32.550644) (xy 41.867198 -32.506175)
			(xy 41.816765 -32.455742) (xy 41.772296 -32.39998) (xy 41.73435 -32.339589) (xy 41.703405 -32.27533)
			(xy 41.679848 -32.20801) (xy 41.663978 -32.138475) (xy 41.655992 -32.067601) (xy 36.358726 -32.067601)
			(xy 36.361593 -32.072232) (xy 36.400327 -32.150021) (xy 36.431719 -32.231053) (xy 36.4555 -32.314635)
			(xy 36.471468 -32.400055) (xy 36.479486 -32.486584) (xy 36.479988 -32.530034) (xy 36.479486 -32.573484)
			(xy 36.471468 -32.660013) (xy 36.4555 -32.745433) (xy 36.431719 -32.829015) (xy 36.400327 -32.910047)
			(xy 36.361593 -32.987836) (xy 36.315846 -33.06172) (xy 36.263477 -33.131067) (xy 36.204933 -33.195287)
			(xy 36.140713 -33.253831) (xy 36.071366 -33.3062) (xy 35.997482 -33.351947) (xy 35.919693 -33.390681)
			(xy 35.838661 -33.422073) (xy 35.755079 -33.445854) (xy 35.669659 -33.461822) (xy 35.58313 -33.46984)
			(xy 35.49623 -33.46984) (xy 35.409701 -33.461822) (xy 35.324281 -33.445854) (xy 35.240699 -33.422073)
			(xy 35.159667 -33.390681) (xy 35.081878 -33.351947) (xy 35.007994 -33.3062) (xy 34.938647 -33.253831)
			(xy 34.874427 -33.195287) (xy 34.815883 -33.131067) (xy 34.763514 -33.06172) (xy 34.717767 -32.987836)
			(xy 34.679033 -32.910047) (xy 34.647641 -32.829015) (xy 34.62386 -32.745433) (xy 34.607892 -32.660013)
			(xy 34.599874 -32.573484) (xy 31.399486 -32.573484) (xy 31.391468 -32.660013) (xy 31.3755 -32.745433)
			(xy 31.351719 -32.829015) (xy 31.320327 -32.910047) (xy 31.281593 -32.987836) (xy 31.235846 -33.06172)
			(xy 31.183477 -33.131067) (xy 31.124933 -33.195287) (xy 31.060713 -33.253831) (xy 30.991366 -33.3062)
			(xy 30.917482 -33.351947) (xy 30.839693 -33.390681) (xy 30.758661 -33.422073) (xy 30.675079 -33.445854)
			(xy 30.589659 -33.461822) (xy 30.50313 -33.46984) (xy 30.41623 -33.46984) (xy 30.329701 -33.461822)
			(xy 30.244281 -33.445854) (xy 30.160699 -33.422073) (xy 30.079667 -33.390681) (xy 30.001878 -33.351947)
			(xy 29.927994 -33.3062) (xy 29.858647 -33.253831) (xy 29.794427 -33.195287) (xy 29.735883 -33.131067)
			(xy 29.683514 -33.06172) (xy 29.637767 -32.987836) (xy 29.599033 -32.910047) (xy 29.567641 -32.829015)
			(xy 29.54386 -32.745433) (xy 29.527892 -32.660013) (xy 29.519874 -32.573484) (xy 24.743664 -32.573484)
			(xy 24.743664 -33.742731) (xy 41.655992 -33.742731) (xy 41.655992 -33.671409) (xy 41.663978 -33.600535)
			(xy 41.679848 -33.531) (xy 41.703405 -33.46368) (xy 41.73435 -33.399421) (xy 41.772296 -33.33903)
			(xy 41.816765 -33.283268) (xy 41.867198 -33.232835) (xy 41.92296 -33.188366) (xy 41.983351 -33.15042)
			(xy 42.04761 -33.119475) (xy 42.11493 -33.095918) (xy 42.184465 -33.080048) (xy 42.255339 -33.072062)
			(xy 42.326661 -33.072062) (xy 42.397535 -33.080048) (xy 42.46707 -33.095918) (xy 42.53439 -33.119475)
			(xy 42.598649 -33.15042) (xy 42.65904 -33.188366) (xy 42.714802 -33.232835) (xy 42.765235 -33.283268)
			(xy 42.809704 -33.33903) (xy 42.84765 -33.399421) (xy 42.878595 -33.46368) (xy 42.902152 -33.531)
			(xy 42.918022 -33.600535) (xy 42.926008 -33.671409) (xy 42.926508 -33.70707) (xy 42.926008 -33.742731)
			(xy 43.542704 -33.742731) (xy 43.542704 -33.671409) (xy 43.55069 -33.600535) (xy 43.56656 -33.531)
			(xy 43.590117 -33.46368) (xy 43.621062 -33.399421) (xy 43.659008 -33.33903) (xy 43.703477 -33.283268)
			(xy 43.75391 -33.232835) (xy 43.809672 -33.188366) (xy 43.870063 -33.15042) (xy 43.934322 -33.119475)
			(xy 44.001642 -33.095918) (xy 44.071177 -33.080048) (xy 44.142051 -33.072062) (xy 44.213373 -33.072062)
			(xy 44.284247 -33.080048) (xy 44.353782 -33.095918) (xy 44.421102 -33.119475) (xy 44.485361 -33.15042)
			(xy 44.545752 -33.188366) (xy 44.601514 -33.232835) (xy 44.651947 -33.283268) (xy 44.696416 -33.33903)
			(xy 44.734362 -33.399421) (xy 44.765307 -33.46368) (xy 44.788864 -33.531) (xy 44.804734 -33.600535)
			(xy 44.81272 -33.671409) (xy 44.81322 -33.70707) (xy 44.81272 -33.742731) (xy 44.804734 -33.813605)
			(xy 44.788864 -33.88314) (xy 44.765307 -33.95046) (xy 44.734362 -34.014719) (xy 44.696416 -34.07511)
			(xy 44.651947 -34.130872) (xy 44.601514 -34.181305) (xy 44.545752 -34.225774) (xy 44.485361 -34.26372)
			(xy 44.421102 -34.294665) (xy 44.353782 -34.318222) (xy 44.284247 -34.334092) (xy 44.213373 -34.342078)
			(xy 44.142051 -34.342078) (xy 44.071177 -34.334092) (xy 44.001642 -34.318222) (xy 43.934322 -34.294665)
			(xy 43.870063 -34.26372) (xy 43.809672 -34.225774) (xy 43.75391 -34.181305) (xy 43.703477 -34.130872)
			(xy 43.659008 -34.07511) (xy 43.621062 -34.014719) (xy 43.590117 -33.95046) (xy 43.56656 -33.88314)
			(xy 43.55069 -33.813605) (xy 43.542704 -33.742731) (xy 42.926008 -33.742731) (xy 42.918022 -33.813605)
			(xy 42.902152 -33.88314) (xy 42.878595 -33.95046) (xy 42.84765 -34.014719) (xy 42.809704 -34.07511)
			(xy 42.765235 -34.130872) (xy 42.714802 -34.181305) (xy 42.65904 -34.225774) (xy 42.598649 -34.26372)
			(xy 42.53439 -34.294665) (xy 42.46707 -34.318222) (xy 42.397535 -34.334092) (xy 42.326661 -34.342078)
			(xy 42.255339 -34.342078) (xy 42.184465 -34.334092) (xy 42.11493 -34.318222) (xy 42.04761 -34.294665)
			(xy 41.983351 -34.26372) (xy 41.92296 -34.225774) (xy 41.867198 -34.181305) (xy 41.816765 -34.130872)
			(xy 41.772296 -34.07511) (xy 41.73435 -34.014719) (xy 41.703405 -33.95046) (xy 41.679848 -33.88314)
			(xy 41.663978 -33.813605) (xy 41.655992 -33.742731) (xy 24.743664 -33.742731) (xy 24.743664 -35.113484)
			(xy 29.519874 -35.113484) (xy 29.519874 -35.026584) (xy 29.527892 -34.940055) (xy 29.54386 -34.854635)
			(xy 29.567641 -34.771053) (xy 29.599033 -34.690021) (xy 29.637767 -34.612232) (xy 29.683514 -34.538348)
			(xy 29.735883 -34.469001) (xy 29.794427 -34.404781) (xy 29.858647 -34.346237) (xy 29.927994 -34.293868)
			(xy 30.001878 -34.248121) (xy 30.079667 -34.209387) (xy 30.160699 -34.177995) (xy 30.244281 -34.154214)
			(xy 30.329701 -34.138246) (xy 30.41623 -34.130228) (xy 30.50313 -34.130228) (xy 30.589659 -34.138246)
			(xy 30.675079 -34.154214) (xy 30.758661 -34.177995) (xy 30.839693 -34.209387) (xy 30.917482 -34.248121)
			(xy 30.991366 -34.293868) (xy 31.060713 -34.346237) (xy 31.124933 -34.404781) (xy 31.183477 -34.469001)
			(xy 31.235846 -34.538348) (xy 31.281593 -34.612232) (xy 31.320327 -34.690021) (xy 31.351719 -34.771053)
			(xy 31.3755 -34.854635) (xy 31.391468 -34.940055) (xy 31.399486 -35.026584) (xy 31.399988 -35.070034)
			(xy 31.399486 -35.113484) (xy 34.599874 -35.113484) (xy 34.599874 -35.026584) (xy 34.607892 -34.940055)
			(xy 34.62386 -34.854635) (xy 34.647641 -34.771053) (xy 34.679033 -34.690021) (xy 34.717767 -34.612232)
			(xy 34.763514 -34.538348) (xy 34.815883 -34.469001) (xy 34.874427 -34.404781) (xy 34.938647 -34.346237)
			(xy 35.007994 -34.293868) (xy 35.081878 -34.248121) (xy 35.159667 -34.209387) (xy 35.240699 -34.177995)
			(xy 35.324281 -34.154214) (xy 35.409701 -34.138246) (xy 35.49623 -34.130228) (xy 35.58313 -34.130228)
			(xy 35.669659 -34.138246) (xy 35.755079 -34.154214) (xy 35.838661 -34.177995) (xy 35.919693 -34.209387)
			(xy 35.997482 -34.248121) (xy 36.071366 -34.293868) (xy 36.140713 -34.346237) (xy 36.204933 -34.404781)
			(xy 36.263477 -34.469001) (xy 36.315846 -34.538348) (xy 36.361593 -34.612232) (xy 36.400327 -34.690021)
			(xy 36.431719 -34.771053) (xy 36.4555 -34.854635) (xy 36.471468 -34.940055) (xy 36.479486 -35.026584)
			(xy 36.479988 -35.070034) (xy 36.479486 -35.113484) (xy 36.471468 -35.200013) (xy 36.4555 -35.285433)
			(xy 36.431719 -35.369015) (xy 36.400327 -35.450047) (xy 36.361593 -35.527836) (xy 36.315846 -35.60172)
			(xy 36.263477 -35.671067) (xy 36.204933 -35.735287) (xy 36.184512 -35.753903) (xy 41.612558 -35.753903)
			(xy 41.612558 -35.682581) (xy 41.620544 -35.611707) (xy 41.636414 -35.542172) (xy 41.659971 -35.474852)
			(xy 41.690916 -35.410593) (xy 41.728862 -35.350202) (xy 41.773331 -35.29444) (xy 41.823764 -35.244007)
			(xy 41.879526 -35.199538) (xy 41.939917 -35.161592) (xy 42.004176 -35.130647) (xy 42.071496 -35.10709)
			(xy 42.141031 -35.09122) (xy 42.211905 -35.083234) (xy 42.283227 -35.083234) (xy 42.354101 -35.09122)
			(xy 42.423636 -35.10709) (xy 42.490956 -35.130647) (xy 42.555215 -35.161592) (xy 42.615606 -35.199538)
			(xy 42.671368 -35.244007) (xy 42.721801 -35.29444) (xy 42.76627 -35.350202) (xy 42.804216 -35.410593)
			(xy 42.835161 -35.474852) (xy 42.858718 -35.542172) (xy 42.874588 -35.611707) (xy 42.882574 -35.682581)
			(xy 42.883074 -35.718242) (xy 42.882574 -35.753903) (xy 43.49927 -35.753903) (xy 43.49927 -35.682581)
			(xy 43.507256 -35.611707) (xy 43.523126 -35.542172) (xy 43.546683 -35.474852) (xy 43.577628 -35.410593)
			(xy 43.615574 -35.350202) (xy 43.660043 -35.29444) (xy 43.710476 -35.244007) (xy 43.766238 -35.199538)
			(xy 43.826629 -35.161592) (xy 43.890888 -35.130647) (xy 43.958208 -35.10709) (xy 44.027743 -35.09122)
			(xy 44.098617 -35.083234) (xy 44.169939 -35.083234) (xy 44.240813 -35.09122) (xy 44.310348 -35.10709)
			(xy 44.377668 -35.130647) (xy 44.441927 -35.161592) (xy 44.502318 -35.199538) (xy 44.55808 -35.244007)
			(xy 44.608513 -35.29444) (xy 44.652982 -35.350202) (xy 44.690928 -35.410593) (xy 44.721873 -35.474852)
			(xy 44.74543 -35.542172) (xy 44.7613 -35.611707) (xy 44.769286 -35.682581) (xy 44.769786 -35.718242)
			(xy 44.769286 -35.753903) (xy 44.7613 -35.824777) (xy 44.74543 -35.894312) (xy 44.721873 -35.961632)
			(xy 44.690928 -36.025891) (xy 44.652982 -36.086282) (xy 44.608513 -36.142044) (xy 44.55808 -36.192477)
			(xy 44.502318 -36.236946) (xy 44.441927 -36.274892) (xy 44.377668 -36.305837) (xy 44.310348 -36.329394)
			(xy 44.240813 -36.345264) (xy 44.169939 -36.35325) (xy 44.098617 -36.35325) (xy 44.027743 -36.345264)
			(xy 43.958208 -36.329394) (xy 43.890888 -36.305837) (xy 43.826629 -36.274892) (xy 43.766238 -36.236946)
			(xy 43.710476 -36.192477) (xy 43.660043 -36.142044) (xy 43.615574 -36.086282) (xy 43.577628 -36.025891)
			(xy 43.546683 -35.961632) (xy 43.523126 -35.894312) (xy 43.507256 -35.824777) (xy 43.49927 -35.753903)
			(xy 42.882574 -35.753903) (xy 42.874588 -35.824777) (xy 42.858718 -35.894312) (xy 42.835161 -35.961632)
			(xy 42.804216 -36.025891) (xy 42.76627 -36.086282) (xy 42.721801 -36.142044) (xy 42.671368 -36.192477)
			(xy 42.615606 -36.236946) (xy 42.555215 -36.274892) (xy 42.490956 -36.305837) (xy 42.423636 -36.329394)
			(xy 42.354101 -36.345264) (xy 42.283227 -36.35325) (xy 42.211905 -36.35325) (xy 42.141031 -36.345264)
			(xy 42.071496 -36.329394) (xy 42.004176 -36.305837) (xy 41.939917 -36.274892) (xy 41.879526 -36.236946)
			(xy 41.823764 -36.192477) (xy 41.773331 -36.142044) (xy 41.728862 -36.086282) (xy 41.690916 -36.025891)
			(xy 41.659971 -35.961632) (xy 41.636414 -35.894312) (xy 41.620544 -35.824777) (xy 41.612558 -35.753903)
			(xy 36.184512 -35.753903) (xy 36.140713 -35.793831) (xy 36.071366 -35.8462) (xy 35.997482 -35.891947)
			(xy 35.919693 -35.930681) (xy 35.838661 -35.962073) (xy 35.755079 -35.985854) (xy 35.669659 -36.001822)
			(xy 35.58313 -36.00984) (xy 35.49623 -36.00984) (xy 35.409701 -36.001822) (xy 35.324281 -35.985854)
			(xy 35.240699 -35.962073) (xy 35.159667 -35.930681) (xy 35.081878 -35.891947) (xy 35.007994 -35.8462)
			(xy 34.938647 -35.793831) (xy 34.874427 -35.735287) (xy 34.815883 -35.671067) (xy 34.763514 -35.60172)
			(xy 34.717767 -35.527836) (xy 34.679033 -35.450047) (xy 34.647641 -35.369015) (xy 34.62386 -35.285433)
			(xy 34.607892 -35.200013) (xy 34.599874 -35.113484) (xy 31.399486 -35.113484) (xy 31.391468 -35.200013)
			(xy 31.3755 -35.285433) (xy 31.351719 -35.369015) (xy 31.320327 -35.450047) (xy 31.281593 -35.527836)
			(xy 31.235846 -35.60172) (xy 31.183477 -35.671067) (xy 31.124933 -35.735287) (xy 31.060713 -35.793831)
			(xy 30.991366 -35.8462) (xy 30.917482 -35.891947) (xy 30.839693 -35.930681) (xy 30.758661 -35.962073)
			(xy 30.675079 -35.985854) (xy 30.589659 -36.001822) (xy 30.50313 -36.00984) (xy 30.41623 -36.00984)
			(xy 30.329701 -36.001822) (xy 30.244281 -35.985854) (xy 30.160699 -35.962073) (xy 30.079667 -35.930681)
			(xy 30.001878 -35.891947) (xy 29.927994 -35.8462) (xy 29.858647 -35.793831) (xy 29.794427 -35.735287)
			(xy 29.735883 -35.671067) (xy 29.683514 -35.60172) (xy 29.637767 -35.527836) (xy 29.599033 -35.450047)
			(xy 29.567641 -35.369015) (xy 29.54386 -35.285433) (xy 29.527892 -35.200013) (xy 29.519874 -35.113484)
			(xy 24.743664 -35.113484) (xy 24.743664 -37.653484) (xy 29.519874 -37.653484) (xy 29.519874 -37.566584)
			(xy 29.527892 -37.480055) (xy 29.54386 -37.394635) (xy 29.567641 -37.311053) (xy 29.599033 -37.230021)
			(xy 29.637767 -37.152232) (xy 29.683514 -37.078348) (xy 29.735883 -37.009001) (xy 29.794427 -36.944781)
			(xy 29.858647 -36.886237) (xy 29.927994 -36.833868) (xy 30.001878 -36.788121) (xy 30.079667 -36.749387)
			(xy 30.160699 -36.717995) (xy 30.244281 -36.694214) (xy 30.329701 -36.678246) (xy 30.41623 -36.670228)
			(xy 30.50313 -36.670228) (xy 30.589659 -36.678246) (xy 30.675079 -36.694214) (xy 30.758661 -36.717995)
			(xy 30.839693 -36.749387) (xy 30.917482 -36.788121) (xy 30.991366 -36.833868) (xy 31.060713 -36.886237)
			(xy 31.124933 -36.944781) (xy 31.183477 -37.009001) (xy 31.235846 -37.078348) (xy 31.281593 -37.152232)
			(xy 31.320327 -37.230021) (xy 31.351719 -37.311053) (xy 31.3755 -37.394635) (xy 31.391468 -37.480055)
			(xy 31.399486 -37.566584) (xy 31.399988 -37.610034) (xy 31.399486 -37.653484) (xy 34.599874 -37.653484)
			(xy 34.599874 -37.566584) (xy 34.607892 -37.480055) (xy 34.62386 -37.394635) (xy 34.647641 -37.311053)
			(xy 34.679033 -37.230021) (xy 34.717767 -37.152232) (xy 34.763514 -37.078348) (xy 34.815883 -37.009001)
			(xy 34.874427 -36.944781) (xy 34.938647 -36.886237) (xy 35.007994 -36.833868) (xy 35.081878 -36.788121)
			(xy 35.159667 -36.749387) (xy 35.240699 -36.717995) (xy 35.324281 -36.694214) (xy 35.409701 -36.678246)
			(xy 35.49623 -36.670228) (xy 35.58313 -36.670228) (xy 35.669659 -36.678246) (xy 35.755079 -36.694214)
			(xy 35.838661 -36.717995) (xy 35.919693 -36.749387) (xy 35.997482 -36.788121) (xy 36.071366 -36.833868)
			(xy 36.140713 -36.886237) (xy 36.204933 -36.944781) (xy 36.263477 -37.009001) (xy 36.315846 -37.078348)
			(xy 36.361593 -37.152232) (xy 36.400327 -37.230021) (xy 36.431719 -37.311053) (xy 36.4555 -37.394635)
			(xy 36.471468 -37.480055) (xy 36.479486 -37.566584) (xy 36.479988 -37.610034) (xy 36.479591 -37.644425)
			(xy 41.612558 -37.644425) (xy 41.612558 -37.573103) (xy 41.620544 -37.502229) (xy 41.636414 -37.432694)
			(xy 41.659971 -37.365374) (xy 41.690916 -37.301115) (xy 41.728862 -37.240724) (xy 41.773331 -37.184962)
			(xy 41.823764 -37.134529) (xy 41.879526 -37.09006) (xy 41.939917 -37.052114) (xy 42.004176 -37.021169)
			(xy 42.071496 -36.997612) (xy 42.141031 -36.981742) (xy 42.211905 -36.973756) (xy 42.283227 -36.973756)
			(xy 42.354101 -36.981742) (xy 42.423636 -36.997612) (xy 42.490956 -37.021169) (xy 42.555215 -37.052114)
			(xy 42.615606 -37.09006) (xy 42.671368 -37.134529) (xy 42.721801 -37.184962) (xy 42.76627 -37.240724)
			(xy 42.804216 -37.301115) (xy 42.835161 -37.365374) (xy 42.858718 -37.432694) (xy 42.874588 -37.502229)
			(xy 42.882574 -37.573103) (xy 42.883074 -37.608764) (xy 42.882574 -37.644425) (xy 43.49927 -37.644425)
			(xy 43.49927 -37.573103) (xy 43.507256 -37.502229) (xy 43.523126 -37.432694) (xy 43.546683 -37.365374)
			(xy 43.577628 -37.301115) (xy 43.615574 -37.240724) (xy 43.660043 -37.184962) (xy 43.710476 -37.134529)
			(xy 43.766238 -37.09006) (xy 43.826629 -37.052114) (xy 43.890888 -37.021169) (xy 43.958208 -36.997612)
			(xy 44.027743 -36.981742) (xy 44.098617 -36.973756) (xy 44.169939 -36.973756) (xy 44.240813 -36.981742)
			(xy 44.310348 -36.997612) (xy 44.377668 -37.021169) (xy 44.441927 -37.052114) (xy 44.502318 -37.09006)
			(xy 44.55808 -37.134529) (xy 44.608513 -37.184962) (xy 44.652982 -37.240724) (xy 44.690928 -37.301115)
			(xy 44.721873 -37.365374) (xy 44.74543 -37.432694) (xy 44.7613 -37.502229) (xy 44.769286 -37.573103)
			(xy 44.769786 -37.608764) (xy 44.769286 -37.644425) (xy 44.7613 -37.715299) (xy 44.74543 -37.784834)
			(xy 44.721873 -37.852154) (xy 44.690928 -37.916413) (xy 44.652982 -37.976804) (xy 44.608513 -38.032566)
			(xy 44.55808 -38.082999) (xy 44.502318 -38.127468) (xy 44.441927 -38.165414) (xy 44.377668 -38.196359)
			(xy 44.310348 -38.219916) (xy 44.240813 -38.235786) (xy 44.169939 -38.243772) (xy 44.098617 -38.243772)
			(xy 44.027743 -38.235786) (xy 43.958208 -38.219916) (xy 43.890888 -38.196359) (xy 43.826629 -38.165414)
			(xy 43.766238 -38.127468) (xy 43.710476 -38.082999) (xy 43.660043 -38.032566) (xy 43.615574 -37.976804)
			(xy 43.577628 -37.916413) (xy 43.546683 -37.852154) (xy 43.523126 -37.784834) (xy 43.507256 -37.715299)
			(xy 43.49927 -37.644425) (xy 42.882574 -37.644425) (xy 42.874588 -37.715299) (xy 42.858718 -37.784834)
			(xy 42.835161 -37.852154) (xy 42.804216 -37.916413) (xy 42.76627 -37.976804) (xy 42.721801 -38.032566)
			(xy 42.671368 -38.082999) (xy 42.615606 -38.127468) (xy 42.555215 -38.165414) (xy 42.490956 -38.196359)
			(xy 42.423636 -38.219916) (xy 42.354101 -38.235786) (xy 42.283227 -38.243772) (xy 42.211905 -38.243772)
			(xy 42.141031 -38.235786) (xy 42.071496 -38.219916) (xy 42.004176 -38.196359) (xy 41.939917 -38.165414)
			(xy 41.879526 -38.127468) (xy 41.823764 -38.082999) (xy 41.773331 -38.032566) (xy 41.728862 -37.976804)
			(xy 41.690916 -37.916413) (xy 41.659971 -37.852154) (xy 41.636414 -37.784834) (xy 41.620544 -37.715299)
			(xy 41.612558 -37.644425) (xy 36.479591 -37.644425) (xy 36.479486 -37.653484) (xy 36.471468 -37.740013)
			(xy 36.4555 -37.825433) (xy 36.431719 -37.909015) (xy 36.400327 -37.990047) (xy 36.361593 -38.067836)
			(xy 36.315846 -38.14172) (xy 36.263477 -38.211067) (xy 36.204933 -38.275287) (xy 36.140713 -38.333831)
			(xy 36.071366 -38.3862) (xy 35.997482 -38.431947) (xy 35.919693 -38.470681) (xy 35.838661 -38.502073)
			(xy 35.755079 -38.525854) (xy 35.669659 -38.541822) (xy 35.58313 -38.54984) (xy 35.49623 -38.54984)
			(xy 35.409701 -38.541822) (xy 35.324281 -38.525854) (xy 35.240699 -38.502073) (xy 35.159667 -38.470681)
			(xy 35.081878 -38.431947) (xy 35.007994 -38.3862) (xy 34.938647 -38.333831) (xy 34.874427 -38.275287)
			(xy 34.815883 -38.211067) (xy 34.763514 -38.14172) (xy 34.717767 -38.067836) (xy 34.679033 -37.990047)
			(xy 34.647641 -37.909015) (xy 34.62386 -37.825433) (xy 34.607892 -37.740013) (xy 34.599874 -37.653484)
			(xy 31.399486 -37.653484) (xy 31.391468 -37.740013) (xy 31.3755 -37.825433) (xy 31.351719 -37.909015)
			(xy 31.320327 -37.990047) (xy 31.281593 -38.067836) (xy 31.235846 -38.14172) (xy 31.183477 -38.211067)
			(xy 31.124933 -38.275287) (xy 31.060713 -38.333831) (xy 30.991366 -38.3862) (xy 30.917482 -38.431947)
			(xy 30.839693 -38.470681) (xy 30.758661 -38.502073) (xy 30.675079 -38.525854) (xy 30.589659 -38.541822)
			(xy 30.50313 -38.54984) (xy 30.41623 -38.54984) (xy 30.329701 -38.541822) (xy 30.244281 -38.525854)
			(xy 30.160699 -38.502073) (xy 30.079667 -38.470681) (xy 30.001878 -38.431947) (xy 29.927994 -38.3862)
			(xy 29.858647 -38.333831) (xy 29.794427 -38.275287) (xy 29.735883 -38.211067) (xy 29.683514 -38.14172)
			(xy 29.637767 -38.067836) (xy 29.599033 -37.990047) (xy 29.567641 -37.909015) (xy 29.54386 -37.825433)
			(xy 29.527892 -37.740013) (xy 29.519874 -37.653484) (xy 24.743664 -37.653484) (xy 24.743664 -38.661255)
			(xy 47.507896 -38.661255) (xy 47.507896 -38.580145) (xy 47.515846 -38.499426) (xy 47.531669 -38.419875)
			(xy 47.555214 -38.342259) (xy 47.586253 -38.267323) (xy 47.624488 -38.195791) (xy 47.66955 -38.128351)
			(xy 47.721005 -38.065652) (xy 47.778358 -38.008299) (xy 47.841057 -37.956844) (xy 47.908497 -37.911782)
			(xy 47.980029 -37.873547) (xy 48.054965 -37.842508) (xy 48.132581 -37.818963) (xy 48.212132 -37.80314)
			(xy 48.292851 -37.79519) (xy 48.373961 -37.79519) (xy 48.45468 -37.80314) (xy 48.534231 -37.818963)
			(xy 48.611847 -37.842508) (xy 48.686783 -37.873547) (xy 48.758315 -37.911782) (xy 48.825755 -37.956844)
			(xy 48.888454 -38.008299) (xy 48.945807 -38.065652) (xy 48.997262 -38.128351) (xy 49.042324 -38.195791)
			(xy 49.080559 -38.267323) (xy 49.111598 -38.342259) (xy 49.135143 -38.419875) (xy 49.150966 -38.499426)
			(xy 49.158916 -38.580145) (xy 49.159414 -38.6207) (xy 49.158916 -38.661255) (xy 49.150966 -38.741974)
			(xy 49.135143 -38.821525) (xy 49.111598 -38.899141) (xy 49.080559 -38.974077) (xy 49.042324 -39.045609)
			(xy 48.997262 -39.113049) (xy 48.945807 -39.175748) (xy 48.888454 -39.233101) (xy 48.825755 -39.284556)
			(xy 48.758315 -39.329618) (xy 48.686783 -39.367853) (xy 48.611847 -39.398892) (xy 48.534231 -39.422437)
			(xy 48.45468 -39.43826) (xy 48.373961 -39.44621) (xy 48.292851 -39.44621) (xy 48.212132 -39.43826)
			(xy 48.132581 -39.422437) (xy 48.054965 -39.398892) (xy 47.980029 -39.367853) (xy 47.908497 -39.329618)
			(xy 47.841057 -39.284556) (xy 47.778358 -39.233101) (xy 47.721005 -39.175748) (xy 47.66955 -39.113049)
			(xy 47.624488 -39.045609) (xy 47.586253 -38.974077) (xy 47.555214 -38.899141) (xy 47.531669 -38.821525)
			(xy 47.515846 -38.741974) (xy 47.507896 -38.661255) (xy 24.743664 -38.661255) (xy 24.743664 -40.193484)
			(xy 29.519874 -40.193484) (xy 29.519874 -40.106584) (xy 29.527892 -40.020055) (xy 29.54386 -39.934635)
			(xy 29.567641 -39.851053) (xy 29.599033 -39.770021) (xy 29.637767 -39.692232) (xy 29.683514 -39.618348)
			(xy 29.735883 -39.549001) (xy 29.794427 -39.484781) (xy 29.858647 -39.426237) (xy 29.927994 -39.373868)
			(xy 30.001878 -39.328121) (xy 30.079667 -39.289387) (xy 30.160699 -39.257995) (xy 30.244281 -39.234214)
			(xy 30.329701 -39.218246) (xy 30.41623 -39.210228) (xy 30.50313 -39.210228) (xy 30.589659 -39.218246)
			(xy 30.675079 -39.234214) (xy 30.758661 -39.257995) (xy 30.839693 -39.289387) (xy 30.917482 -39.328121)
			(xy 30.991366 -39.373868) (xy 31.060713 -39.426237) (xy 31.124933 -39.484781) (xy 31.183477 -39.549001)
			(xy 31.235846 -39.618348) (xy 31.281593 -39.692232) (xy 31.320327 -39.770021) (xy 31.351719 -39.851053)
			(xy 31.3755 -39.934635) (xy 31.391468 -40.020055) (xy 31.399486 -40.106584) (xy 31.399988 -40.150034)
			(xy 31.399486 -40.193484) (xy 34.599874 -40.193484) (xy 34.599874 -40.106584) (xy 34.607892 -40.020055)
			(xy 34.62386 -39.934635) (xy 34.647641 -39.851053) (xy 34.679033 -39.770021) (xy 34.717767 -39.692232)
			(xy 34.763514 -39.618348) (xy 34.815883 -39.549001) (xy 34.874427 -39.484781) (xy 34.938647 -39.426237)
			(xy 35.007994 -39.373868) (xy 35.081878 -39.328121) (xy 35.159667 -39.289387) (xy 35.240699 -39.257995)
			(xy 35.324281 -39.234214) (xy 35.409701 -39.218246) (xy 35.49623 -39.210228) (xy 35.58313 -39.210228)
			(xy 35.669659 -39.218246) (xy 35.755079 -39.234214) (xy 35.838661 -39.257995) (xy 35.919693 -39.289387)
			(xy 35.997482 -39.328121) (xy 36.071366 -39.373868) (xy 36.140713 -39.426237) (xy 36.204933 -39.484781)
			(xy 36.263477 -39.549001) (xy 36.315846 -39.618348) (xy 36.357467 -39.685569) (xy 41.612558 -39.685569)
			(xy 41.612558 -39.614247) (xy 41.620544 -39.543373) (xy 41.636414 -39.473838) (xy 41.659971 -39.406518)
			(xy 41.690916 -39.342259) (xy 41.728862 -39.281868) (xy 41.773331 -39.226106) (xy 41.823764 -39.175673)
			(xy 41.879526 -39.131204) (xy 41.939917 -39.093258) (xy 42.004176 -39.062313) (xy 42.071496 -39.038756)
			(xy 42.141031 -39.022886) (xy 42.211905 -39.0149) (xy 42.283227 -39.0149) (xy 42.354101 -39.022886)
			(xy 42.423636 -39.038756) (xy 42.490956 -39.062313) (xy 42.555215 -39.093258) (xy 42.615606 -39.131204)
			(xy 42.671368 -39.175673) (xy 42.721801 -39.226106) (xy 42.76627 -39.281868) (xy 42.804216 -39.342259)
			(xy 42.835161 -39.406518) (xy 42.858718 -39.473838) (xy 42.874588 -39.543373) (xy 42.882574 -39.614247)
			(xy 42.883074 -39.649908) (xy 42.882574 -39.685569) (xy 43.49927 -39.685569) (xy 43.49927 -39.614247)
			(xy 43.507256 -39.543373) (xy 43.523126 -39.473838) (xy 43.546683 -39.406518) (xy 43.577628 -39.342259)
			(xy 43.615574 -39.281868) (xy 43.660043 -39.226106) (xy 43.710476 -39.175673) (xy 43.766238 -39.131204)
			(xy 43.826629 -39.093258) (xy 43.890888 -39.062313) (xy 43.958208 -39.038756) (xy 44.027743 -39.022886)
			(xy 44.098617 -39.0149) (xy 44.169939 -39.0149) (xy 44.240813 -39.022886) (xy 44.310348 -39.038756)
			(xy 44.377668 -39.062313) (xy 44.441927 -39.093258) (xy 44.502318 -39.131204) (xy 44.55808 -39.175673)
			(xy 44.608513 -39.226106) (xy 44.652982 -39.281868) (xy 44.690928 -39.342259) (xy 44.721873 -39.406518)
			(xy 44.74543 -39.473838) (xy 44.7613 -39.543373) (xy 44.769286 -39.614247) (xy 44.769786 -39.649908)
			(xy 44.769286 -39.685569) (xy 44.7613 -39.756443) (xy 44.74543 -39.825978) (xy 44.721873 -39.893298)
			(xy 44.690928 -39.957557) (xy 44.652982 -40.017948) (xy 44.608513 -40.07371) (xy 44.55808 -40.124143)
			(xy 44.502318 -40.168612) (xy 44.441927 -40.206558) (xy 44.377668 -40.237503) (xy 44.310348 -40.26106)
			(xy 44.240813 -40.27693) (xy 44.169939 -40.284916) (xy 44.098617 -40.284916) (xy 44.027743 -40.27693)
			(xy 43.958208 -40.26106) (xy 43.890888 -40.237503) (xy 43.826629 -40.206558) (xy 43.766238 -40.168612)
			(xy 43.710476 -40.124143) (xy 43.660043 -40.07371) (xy 43.615574 -40.017948) (xy 43.577628 -39.957557)
			(xy 43.546683 -39.893298) (xy 43.523126 -39.825978) (xy 43.507256 -39.756443) (xy 43.49927 -39.685569)
			(xy 42.882574 -39.685569) (xy 42.874588 -39.756443) (xy 42.858718 -39.825978) (xy 42.835161 -39.893298)
			(xy 42.804216 -39.957557) (xy 42.76627 -40.017948) (xy 42.721801 -40.07371) (xy 42.671368 -40.124143)
			(xy 42.615606 -40.168612) (xy 42.555215 -40.206558) (xy 42.490956 -40.237503) (xy 42.423636 -40.26106)
			(xy 42.354101 -40.27693) (xy 42.283227 -40.284916) (xy 42.211905 -40.284916) (xy 42.141031 -40.27693)
			(xy 42.071496 -40.26106) (xy 42.004176 -40.237503) (xy 41.939917 -40.206558) (xy 41.879526 -40.168612)
			(xy 41.823764 -40.124143) (xy 41.773331 -40.07371) (xy 41.728862 -40.017948) (xy 41.690916 -39.957557)
			(xy 41.659971 -39.893298) (xy 41.636414 -39.825978) (xy 41.620544 -39.756443) (xy 41.612558 -39.685569)
			(xy 36.357467 -39.685569) (xy 36.361593 -39.692232) (xy 36.400327 -39.770021) (xy 36.431719 -39.851053)
			(xy 36.4555 -39.934635) (xy 36.471468 -40.020055) (xy 36.479486 -40.106584) (xy 36.479988 -40.150034)
			(xy 36.479486 -40.193484) (xy 36.471468 -40.280013) (xy 36.4555 -40.365433) (xy 36.431719 -40.449015)
			(xy 36.400327 -40.530047) (xy 36.361593 -40.607836) (xy 36.315846 -40.68172) (xy 36.263477 -40.751067)
			(xy 36.204933 -40.815287) (xy 36.140713 -40.873831) (xy 36.071366 -40.9262) (xy 35.997482 -40.971947)
			(xy 35.919693 -41.010681) (xy 35.838661 -41.042073) (xy 35.755079 -41.065854) (xy 35.669659 -41.081822)
			(xy 35.58313 -41.08984) (xy 35.49623 -41.08984) (xy 35.409701 -41.081822) (xy 35.324281 -41.065854)
			(xy 35.240699 -41.042073) (xy 35.159667 -41.010681) (xy 35.081878 -40.971947) (xy 35.007994 -40.9262)
			(xy 34.938647 -40.873831) (xy 34.874427 -40.815287) (xy 34.815883 -40.751067) (xy 34.763514 -40.68172)
			(xy 34.717767 -40.607836) (xy 34.679033 -40.530047) (xy 34.647641 -40.449015) (xy 34.62386 -40.365433)
			(xy 34.607892 -40.280013) (xy 34.599874 -40.193484) (xy 31.399486 -40.193484) (xy 31.391468 -40.280013)
			(xy 31.3755 -40.365433) (xy 31.351719 -40.449015) (xy 31.320327 -40.530047) (xy 31.281593 -40.607836)
			(xy 31.235846 -40.68172) (xy 31.183477 -40.751067) (xy 31.124933 -40.815287) (xy 31.060713 -40.873831)
			(xy 30.991366 -40.9262) (xy 30.917482 -40.971947) (xy 30.839693 -41.010681) (xy 30.758661 -41.042073)
			(xy 30.675079 -41.065854) (xy 30.589659 -41.081822) (xy 30.50313 -41.08984) (xy 30.41623 -41.08984)
			(xy 30.329701 -41.081822) (xy 30.244281 -41.065854) (xy 30.160699 -41.042073) (xy 30.079667 -41.010681)
			(xy 30.001878 -40.971947) (xy 29.927994 -40.9262) (xy 29.858647 -40.873831) (xy 29.794427 -40.815287)
			(xy 29.735883 -40.751067) (xy 29.683514 -40.68172) (xy 29.637767 -40.607836) (xy 29.599033 -40.530047)
			(xy 29.567641 -40.449015) (xy 29.54386 -40.365433) (xy 29.527892 -40.280013) (xy 29.519874 -40.193484)
			(xy 24.743664 -40.193484) (xy 24.743664 -41.595395) (xy 41.612558 -41.595395) (xy 41.612558 -41.524073)
			(xy 41.620544 -41.453199) (xy 41.636414 -41.383664) (xy 41.659971 -41.316344) (xy 41.690916 -41.252085)
			(xy 41.728862 -41.191694) (xy 41.773331 -41.135932) (xy 41.823764 -41.085499) (xy 41.879526 -41.04103)
			(xy 41.939917 -41.003084) (xy 42.004176 -40.972139) (xy 42.071496 -40.948582) (xy 42.141031 -40.932712)
			(xy 42.211905 -40.924726) (xy 42.283227 -40.924726) (xy 42.354101 -40.932712) (xy 42.423636 -40.948582)
			(xy 42.490956 -40.972139) (xy 42.555215 -41.003084) (xy 42.615606 -41.04103) (xy 42.671368 -41.085499)
			(xy 42.721801 -41.135932) (xy 42.76627 -41.191694) (xy 42.804216 -41.252085) (xy 42.835161 -41.316344)
			(xy 42.858718 -41.383664) (xy 42.874588 -41.453199) (xy 42.882574 -41.524073) (xy 42.883074 -41.559734)
			(xy 42.882574 -41.595395) (xy 43.49927 -41.595395) (xy 43.49927 -41.524073) (xy 43.507256 -41.453199)
			(xy 43.523126 -41.383664) (xy 43.546683 -41.316344) (xy 43.577628 -41.252085) (xy 43.615574 -41.191694)
			(xy 43.660043 -41.135932) (xy 43.710476 -41.085499) (xy 43.766238 -41.04103) (xy 43.826629 -41.003084)
			(xy 43.890888 -40.972139) (xy 43.958208 -40.948582) (xy 44.027743 -40.932712) (xy 44.098617 -40.924726)
			(xy 44.169939 -40.924726) (xy 44.240813 -40.932712) (xy 44.310348 -40.948582) (xy 44.377668 -40.972139)
			(xy 44.441927 -41.003084) (xy 44.502318 -41.04103) (xy 44.55808 -41.085499) (xy 44.608513 -41.135932)
			(xy 44.652982 -41.191694) (xy 44.690928 -41.252085) (xy 44.721873 -41.316344) (xy 44.72296 -41.31945)
			(xy 71.521826 -41.31945) (xy 71.525897 -41.263828) (xy 71.538023 -41.209391) (xy 71.557946 -41.1573)
			(xy 71.585242 -41.108665) (xy 71.619328 -41.064522) (xy 71.659477 -41.025813) (xy 71.704835 -40.993362)
			(xy 71.754435 -40.967861) (xy 71.807219 -40.949854) (xy 71.862062 -40.939724) (xy 71.917796 -40.937687)
			(xy 71.973233 -40.943787) (xy 72.02719 -40.957893) (xy 72.078519 -40.979705) (xy 72.126125 -41.008759)
			(xy 72.168993 -41.044434) (xy 72.20621 -41.085971) (xy 72.236983 -41.132484) (xy 72.260655 -41.182981)
			(xy 72.276723 -41.236388) (xy 72.283901 -41.28516) (xy 72.622662 -41.28516) (xy 72.626733 -41.229538)
			(xy 72.638859 -41.175101) (xy 72.658782 -41.12301) (xy 72.686078 -41.074375) (xy 72.720164 -41.030232)
			(xy 72.760313 -40.991523) (xy 72.805671 -40.959072) (xy 72.855271 -40.933571) (xy 72.908055 -40.915564)
			(xy 72.962898 -40.905434) (xy 73.018632 -40.903397) (xy 73.074069 -40.909497) (xy 73.128026 -40.923603)
			(xy 73.179355 -40.945415) (xy 73.226961 -40.974469) (xy 73.269829 -41.010144) (xy 73.307046 -41.051681)
			(xy 73.337819 -41.098194) (xy 73.361491 -41.148691) (xy 73.377559 -41.202098) (xy 73.385679 -41.257274)
			(xy 73.386188 -41.28516) (xy 73.385771 -41.30802) (xy 73.771504 -41.30802) (xy 73.775575 -41.252398)
			(xy 73.787701 -41.197961) (xy 73.807624 -41.14587) (xy 73.83492 -41.097235) (xy 73.869006 -41.053092)
			(xy 73.909155 -41.014383) (xy 73.954513 -40.981932) (xy 74.004113 -40.956431) (xy 74.056897 -40.938424)
			(xy 74.11174 -40.928294) (xy 74.167474 -40.926257) (xy 74.222911 -40.932357) (xy 74.276868 -40.946463)
			(xy 74.328197 -40.968275) (xy 74.375803 -40.997329) (xy 74.418671 -41.033004) (xy 74.455888 -41.074541)
			(xy 74.486661 -41.121054) (xy 74.510333 -41.171551) (xy 74.526401 -41.224958) (xy 74.534521 -41.280134)
			(xy 74.534821 -41.29659) (xy 74.934824 -41.29659) (xy 74.938895 -41.240968) (xy 74.951021 -41.186531)
			(xy 74.970944 -41.13444) (xy 74.99824 -41.085805) (xy 75.032326 -41.041662) (xy 75.072475 -41.002953)
			(xy 75.117833 -40.970502) (xy 75.167433 -40.945001) (xy 75.220217 -40.926994) (xy 75.27506 -40.916864)
			(xy 75.330794 -40.914827) (xy 75.386231 -40.920927) (xy 75.440188 -40.935033) (xy 75.491517 -40.956845)
			(xy 75.539123 -40.985899) (xy 75.581991 -41.021574) (xy 75.619208 -41.063111) (xy 75.649981 -41.109624)
			(xy 75.673653 -41.160121) (xy 75.689721 -41.213528) (xy 75.697841 -41.268704) (xy 75.69835 -41.29659)
			(xy 75.697841 -41.324476) (xy 75.689721 -41.379652) (xy 75.673653 -41.433059) (xy 75.649981 -41.483556)
			(xy 75.619208 -41.530069) (xy 75.581991 -41.571606) (xy 75.539123 -41.607281) (xy 75.491517 -41.636335)
			(xy 75.440188 -41.658147) (xy 75.386231 -41.672253) (xy 75.330794 -41.678353) (xy 75.27506 -41.676316)
			(xy 75.220217 -41.666186) (xy 75.167433 -41.648179) (xy 75.117833 -41.622678) (xy 75.072475 -41.590227)
			(xy 75.032326 -41.551518) (xy 74.99824 -41.507375) (xy 74.970944 -41.45874) (xy 74.951021 -41.406649)
			(xy 74.938895 -41.352212) (xy 74.934824 -41.29659) (xy 74.534821 -41.29659) (xy 74.53503 -41.30802)
			(xy 74.534521 -41.335906) (xy 74.526401 -41.391082) (xy 74.510333 -41.444489) (xy 74.486661 -41.494986)
			(xy 74.455888 -41.541499) (xy 74.418671 -41.583036) (xy 74.375803 -41.618711) (xy 74.328197 -41.647765)
			(xy 74.276868 -41.669577) (xy 74.222911 -41.683683) (xy 74.167474 -41.689783) (xy 74.11174 -41.687746)
			(xy 74.056897 -41.677616) (xy 74.004113 -41.659609) (xy 73.954513 -41.634108) (xy 73.909155 -41.601657)
			(xy 73.869006 -41.562948) (xy 73.83492 -41.518805) (xy 73.807624 -41.47017) (xy 73.787701 -41.418079)
			(xy 73.775575 -41.363642) (xy 73.771504 -41.30802) (xy 73.385771 -41.30802) (xy 73.385679 -41.313046)
			(xy 73.377559 -41.368222) (xy 73.361491 -41.421629) (xy 73.337819 -41.472126) (xy 73.307046 -41.518639)
			(xy 73.269829 -41.560176) (xy 73.226961 -41.595851) (xy 73.179355 -41.624905) (xy 73.128026 -41.646717)
			(xy 73.074069 -41.660823) (xy 73.018632 -41.666923) (xy 72.962898 -41.664886) (xy 72.908055 -41.654756)
			(xy 72.855271 -41.636749) (xy 72.805671 -41.611248) (xy 72.760313 -41.578797) (xy 72.720164 -41.540088)
			(xy 72.686078 -41.495945) (xy 72.658782 -41.44731) (xy 72.638859 -41.395219) (xy 72.626733 -41.340782)
			(xy 72.622662 -41.28516) (xy 72.283901 -41.28516) (xy 72.284843 -41.291564) (xy 72.285352 -41.31945)
			(xy 72.284843 -41.347336) (xy 72.276723 -41.402512) (xy 72.260655 -41.455919) (xy 72.236983 -41.506416)
			(xy 72.20621 -41.552929) (xy 72.168993 -41.594466) (xy 72.126125 -41.630141) (xy 72.078519 -41.659195)
			(xy 72.02719 -41.681007) (xy 71.973233 -41.695113) (xy 71.917796 -41.701213) (xy 71.862062 -41.699176)
			(xy 71.807219 -41.689046) (xy 71.754435 -41.671039) (xy 71.704835 -41.645538) (xy 71.659477 -41.613087)
			(xy 71.619328 -41.574378) (xy 71.585242 -41.530235) (xy 71.557946 -41.4816) (xy 71.538023 -41.429509)
			(xy 71.525897 -41.375072) (xy 71.521826 -41.31945) (xy 44.72296 -41.31945) (xy 44.74543 -41.383664)
			(xy 44.7613 -41.453199) (xy 44.769286 -41.524073) (xy 44.769786 -41.559734) (xy 44.769286 -41.595395)
			(xy 44.7613 -41.666269) (xy 44.74543 -41.735804) (xy 44.721873 -41.803124) (xy 44.690928 -41.867383)
			(xy 44.652982 -41.927774) (xy 44.608513 -41.983536) (xy 44.55808 -42.033969) (xy 44.502318 -42.078438)
			(xy 44.441927 -42.116384) (xy 44.377668 -42.147329) (xy 44.310348 -42.170886) (xy 44.240813 -42.186756)
			(xy 44.169939 -42.194742) (xy 44.098617 -42.194742) (xy 44.027743 -42.186756) (xy 43.958208 -42.170886)
			(xy 43.890888 -42.147329) (xy 43.826629 -42.116384) (xy 43.766238 -42.078438) (xy 43.710476 -42.033969)
			(xy 43.660043 -41.983536) (xy 43.615574 -41.927774) (xy 43.577628 -41.867383) (xy 43.546683 -41.803124)
			(xy 43.523126 -41.735804) (xy 43.507256 -41.666269) (xy 43.49927 -41.595395) (xy 42.882574 -41.595395)
			(xy 42.874588 -41.666269) (xy 42.858718 -41.735804) (xy 42.835161 -41.803124) (xy 42.804216 -41.867383)
			(xy 42.76627 -41.927774) (xy 42.721801 -41.983536) (xy 42.671368 -42.033969) (xy 42.615606 -42.078438)
			(xy 42.555215 -42.116384) (xy 42.490956 -42.147329) (xy 42.423636 -42.170886) (xy 42.354101 -42.186756)
			(xy 42.283227 -42.194742) (xy 42.211905 -42.194742) (xy 42.141031 -42.186756) (xy 42.071496 -42.170886)
			(xy 42.004176 -42.147329) (xy 41.939917 -42.116384) (xy 41.879526 -42.078438) (xy 41.823764 -42.033969)
			(xy 41.773331 -41.983536) (xy 41.728862 -41.927774) (xy 41.690916 -41.867383) (xy 41.659971 -41.803124)
			(xy 41.636414 -41.735804) (xy 41.620544 -41.666269) (xy 41.612558 -41.595395) (xy 24.743664 -41.595395)
			(xy 24.743664 -42.733484) (xy 29.519874 -42.733484) (xy 29.519874 -42.646584) (xy 29.527892 -42.560055)
			(xy 29.54386 -42.474635) (xy 29.567641 -42.391053) (xy 29.599033 -42.310021) (xy 29.637767 -42.232232)
			(xy 29.683514 -42.158348) (xy 29.735883 -42.089001) (xy 29.794427 -42.024781) (xy 29.858647 -41.966237)
			(xy 29.927994 -41.913868) (xy 30.001878 -41.868121) (xy 30.079667 -41.829387) (xy 30.160699 -41.797995)
			(xy 30.244281 -41.774214) (xy 30.329701 -41.758246) (xy 30.41623 -41.750228) (xy 30.50313 -41.750228)
			(xy 30.589659 -41.758246) (xy 30.675079 -41.774214) (xy 30.758661 -41.797995) (xy 30.839693 -41.829387)
			(xy 30.917482 -41.868121) (xy 30.991366 -41.913868) (xy 31.060713 -41.966237) (xy 31.124933 -42.024781)
			(xy 31.183477 -42.089001) (xy 31.235846 -42.158348) (xy 31.281593 -42.232232) (xy 31.320327 -42.310021)
			(xy 31.351719 -42.391053) (xy 31.3755 -42.474635) (xy 31.391468 -42.560055) (xy 31.399486 -42.646584)
			(xy 31.399988 -42.690034) (xy 31.399486 -42.733484) (xy 34.599874 -42.733484) (xy 34.599874 -42.646584)
			(xy 34.607892 -42.560055) (xy 34.62386 -42.474635) (xy 34.647641 -42.391053) (xy 34.679033 -42.310021)
			(xy 34.717767 -42.232232) (xy 34.763514 -42.158348) (xy 34.815883 -42.089001) (xy 34.874427 -42.024781)
			(xy 34.938647 -41.966237) (xy 35.007994 -41.913868) (xy 35.081878 -41.868121) (xy 35.159667 -41.829387)
			(xy 35.240699 -41.797995) (xy 35.324281 -41.774214) (xy 35.409701 -41.758246) (xy 35.49623 -41.750228)
			(xy 35.58313 -41.750228) (xy 35.669659 -41.758246) (xy 35.755079 -41.774214) (xy 35.838661 -41.797995)
			(xy 35.919693 -41.829387) (xy 35.997482 -41.868121) (xy 36.071366 -41.913868) (xy 36.140713 -41.966237)
			(xy 36.204933 -42.024781) (xy 36.263477 -42.089001) (xy 36.315846 -42.158348) (xy 36.361593 -42.232232)
			(xy 36.400327 -42.310021) (xy 36.431719 -42.391053) (xy 36.4555 -42.474635) (xy 36.471468 -42.560055)
			(xy 36.479486 -42.646584) (xy 36.479988 -42.690034) (xy 36.479486 -42.733484) (xy 36.471468 -42.820013)
			(xy 36.4555 -42.905433) (xy 36.431719 -42.989015) (xy 36.400327 -43.070047) (xy 36.361593 -43.147836)
			(xy 36.315846 -43.22172) (xy 36.263477 -43.291067) (xy 36.204933 -43.355287) (xy 36.140713 -43.413831)
			(xy 36.071366 -43.4662) (xy 35.997482 -43.511947) (xy 35.919693 -43.550681) (xy 35.838661 -43.582073)
			(xy 35.755079 -43.605854) (xy 35.669659 -43.621822) (xy 35.58313 -43.62984) (xy 35.49623 -43.62984)
			(xy 35.409701 -43.621822) (xy 35.324281 -43.605854) (xy 35.240699 -43.582073) (xy 35.159667 -43.550681)
			(xy 35.081878 -43.511947) (xy 35.007994 -43.4662) (xy 34.938647 -43.413831) (xy 34.874427 -43.355287)
			(xy 34.815883 -43.291067) (xy 34.763514 -43.22172) (xy 34.717767 -43.147836) (xy 34.679033 -43.070047)
			(xy 34.647641 -42.989015) (xy 34.62386 -42.905433) (xy 34.607892 -42.820013) (xy 34.599874 -42.733484)
			(xy 31.399486 -42.733484) (xy 31.391468 -42.820013) (xy 31.3755 -42.905433) (xy 31.351719 -42.989015)
			(xy 31.320327 -43.070047) (xy 31.281593 -43.147836) (xy 31.235846 -43.22172) (xy 31.183477 -43.291067)
			(xy 31.124933 -43.355287) (xy 31.060713 -43.413831) (xy 30.991366 -43.4662) (xy 30.917482 -43.511947)
			(xy 30.839693 -43.550681) (xy 30.758661 -43.582073) (xy 30.675079 -43.605854) (xy 30.589659 -43.621822)
			(xy 30.50313 -43.62984) (xy 30.41623 -43.62984) (xy 30.329701 -43.621822) (xy 30.244281 -43.605854)
			(xy 30.160699 -43.582073) (xy 30.079667 -43.550681) (xy 30.001878 -43.511947) (xy 29.927994 -43.4662)
			(xy 29.858647 -43.413831) (xy 29.794427 -43.355287) (xy 29.735883 -43.291067) (xy 29.683514 -43.22172)
			(xy 29.637767 -43.147836) (xy 29.599033 -43.070047) (xy 29.567641 -42.989015) (xy 29.54386 -42.905433)
			(xy 29.527892 -42.820013) (xy 29.519874 -42.733484) (xy 24.743664 -42.733484) (xy 24.743664 -45.273484)
			(xy 29.519874 -45.273484) (xy 29.519874 -45.186584) (xy 29.527892 -45.100055) (xy 29.54386 -45.014635)
			(xy 29.567641 -44.931053) (xy 29.599033 -44.850021) (xy 29.637767 -44.772232) (xy 29.683514 -44.698348)
			(xy 29.735883 -44.629001) (xy 29.794427 -44.564781) (xy 29.858647 -44.506237) (xy 29.927994 -44.453868)
			(xy 30.001878 -44.408121) (xy 30.079667 -44.369387) (xy 30.160699 -44.337995) (xy 30.244281 -44.314214)
			(xy 30.329701 -44.298246) (xy 30.41623 -44.290228) (xy 30.50313 -44.290228) (xy 30.589659 -44.298246)
			(xy 30.675079 -44.314214) (xy 30.758661 -44.337995) (xy 30.839693 -44.369387) (xy 30.917482 -44.408121)
			(xy 30.991366 -44.453868) (xy 31.060713 -44.506237) (xy 31.124933 -44.564781) (xy 31.183477 -44.629001)
			(xy 31.235846 -44.698348) (xy 31.281593 -44.772232) (xy 31.320327 -44.850021) (xy 31.351719 -44.931053)
			(xy 31.3755 -45.014635) (xy 31.391468 -45.100055) (xy 31.399486 -45.186584) (xy 31.399988 -45.230034)
			(xy 31.399486 -45.273484) (xy 34.599874 -45.273484) (xy 34.599874 -45.186584) (xy 34.607892 -45.100055)
			(xy 34.62386 -45.014635) (xy 34.647641 -44.931053) (xy 34.679033 -44.850021) (xy 34.717767 -44.772232)
			(xy 34.763514 -44.698348) (xy 34.815883 -44.629001) (xy 34.874427 -44.564781) (xy 34.938647 -44.506237)
			(xy 35.007994 -44.453868) (xy 35.081878 -44.408121) (xy 35.159667 -44.369387) (xy 35.240699 -44.337995)
			(xy 35.324281 -44.314214) (xy 35.409701 -44.298246) (xy 35.49623 -44.290228) (xy 35.58313 -44.290228)
			(xy 35.669659 -44.298246) (xy 35.755079 -44.314214) (xy 35.838661 -44.337995) (xy 35.919693 -44.369387)
			(xy 35.997482 -44.408121) (xy 36.071366 -44.453868) (xy 36.140713 -44.506237) (xy 36.204933 -44.564781)
			(xy 36.263477 -44.629001) (xy 36.315846 -44.698348) (xy 36.361593 -44.772232) (xy 36.400327 -44.850021)
			(xy 36.431719 -44.931053) (xy 36.4555 -45.014635) (xy 36.471468 -45.100055) (xy 36.479486 -45.186584)
			(xy 36.479988 -45.230034) (xy 36.479486 -45.273484) (xy 36.471468 -45.360013) (xy 36.4555 -45.445433)
			(xy 36.431719 -45.529015) (xy 36.400327 -45.610047) (xy 36.361593 -45.687836) (xy 36.315846 -45.76172)
			(xy 36.263477 -45.831067) (xy 36.204933 -45.895287) (xy 36.140713 -45.953831) (xy 36.071366 -46.0062)
			(xy 35.997482 -46.051947) (xy 35.919693 -46.090681) (xy 35.838661 -46.122073) (xy 35.755079 -46.145854)
			(xy 35.669659 -46.161822) (xy 35.58313 -46.16984) (xy 35.49623 -46.16984) (xy 35.409701 -46.161822)
			(xy 35.324281 -46.145854) (xy 35.240699 -46.122073) (xy 35.159667 -46.090681) (xy 35.081878 -46.051947)
			(xy 35.007994 -46.0062) (xy 34.938647 -45.953831) (xy 34.874427 -45.895287) (xy 34.815883 -45.831067)
			(xy 34.763514 -45.76172) (xy 34.717767 -45.687836) (xy 34.679033 -45.610047) (xy 34.647641 -45.529015)
			(xy 34.62386 -45.445433) (xy 34.607892 -45.360013) (xy 34.599874 -45.273484) (xy 31.399486 -45.273484)
			(xy 31.391468 -45.360013) (xy 31.3755 -45.445433) (xy 31.351719 -45.529015) (xy 31.320327 -45.610047)
			(xy 31.281593 -45.687836) (xy 31.235846 -45.76172) (xy 31.183477 -45.831067) (xy 31.124933 -45.895287)
			(xy 31.060713 -45.953831) (xy 30.991366 -46.0062) (xy 30.917482 -46.051947) (xy 30.839693 -46.090681)
			(xy 30.758661 -46.122073) (xy 30.675079 -46.145854) (xy 30.589659 -46.161822) (xy 30.50313 -46.16984)
			(xy 30.41623 -46.16984) (xy 30.329701 -46.161822) (xy 30.244281 -46.145854) (xy 30.160699 -46.122073)
			(xy 30.079667 -46.090681) (xy 30.001878 -46.051947) (xy 29.927994 -46.0062) (xy 29.858647 -45.953831)
			(xy 29.794427 -45.895287) (xy 29.735883 -45.831067) (xy 29.683514 -45.76172) (xy 29.637767 -45.687836)
			(xy 29.599033 -45.610047) (xy 29.567641 -45.529015) (xy 29.54386 -45.445433) (xy 29.527892 -45.360013)
			(xy 29.519874 -45.273484) (xy 24.743664 -45.273484) (xy 24.743664 -47.813484) (xy 29.519874 -47.813484)
			(xy 29.519874 -47.726584) (xy 29.527892 -47.640055) (xy 29.54386 -47.554635) (xy 29.567641 -47.471053)
			(xy 29.599033 -47.390021) (xy 29.637767 -47.312232) (xy 29.683514 -47.238348) (xy 29.735883 -47.169001)
			(xy 29.794427 -47.104781) (xy 29.858647 -47.046237) (xy 29.927994 -46.993868) (xy 30.001878 -46.948121)
			(xy 30.079667 -46.909387) (xy 30.160699 -46.877995) (xy 30.244281 -46.854214) (xy 30.329701 -46.838246)
			(xy 30.41623 -46.830228) (xy 30.50313 -46.830228) (xy 30.589659 -46.838246) (xy 30.675079 -46.854214)
			(xy 30.758661 -46.877995) (xy 30.839693 -46.909387) (xy 30.917482 -46.948121) (xy 30.991366 -46.993868)
			(xy 31.060713 -47.046237) (xy 31.124933 -47.104781) (xy 31.183477 -47.169001) (xy 31.235846 -47.238348)
			(xy 31.281593 -47.312232) (xy 31.320327 -47.390021) (xy 31.351719 -47.471053) (xy 31.3755 -47.554635)
			(xy 31.391468 -47.640055) (xy 31.399486 -47.726584) (xy 31.399988 -47.770034) (xy 31.399486 -47.813484)
			(xy 34.599874 -47.813484) (xy 34.599874 -47.726584) (xy 34.607892 -47.640055) (xy 34.62386 -47.554635)
			(xy 34.647641 -47.471053) (xy 34.679033 -47.390021) (xy 34.717767 -47.312232) (xy 34.763514 -47.238348)
			(xy 34.815883 -47.169001) (xy 34.874427 -47.104781) (xy 34.938647 -47.046237) (xy 35.007994 -46.993868)
			(xy 35.081878 -46.948121) (xy 35.159667 -46.909387) (xy 35.240699 -46.877995) (xy 35.324281 -46.854214)
			(xy 35.409701 -46.838246) (xy 35.49623 -46.830228) (xy 35.58313 -46.830228) (xy 35.669659 -46.838246)
			(xy 35.755079 -46.854214) (xy 35.838661 -46.877995) (xy 35.919693 -46.909387) (xy 35.997482 -46.948121)
			(xy 36.071366 -46.993868) (xy 36.140713 -47.046237) (xy 36.204933 -47.104781) (xy 36.263477 -47.169001)
			(xy 36.315846 -47.238348) (xy 36.361593 -47.312232) (xy 36.400327 -47.390021) (xy 36.431719 -47.471053)
			(xy 36.4555 -47.554635) (xy 36.471468 -47.640055) (xy 36.479486 -47.726584) (xy 36.479988 -47.770034)
			(xy 36.479486 -47.813484) (xy 36.471468 -47.900013) (xy 36.4555 -47.985433) (xy 36.431719 -48.069015)
			(xy 36.400327 -48.150047) (xy 36.361593 -48.227836) (xy 36.315846 -48.30172) (xy 36.263477 -48.371067)
			(xy 36.204933 -48.435287) (xy 36.140713 -48.493831) (xy 36.071366 -48.5462) (xy 35.997482 -48.591947)
			(xy 35.919693 -48.630681) (xy 35.838661 -48.662073) (xy 35.755079 -48.685854) (xy 35.669659 -48.701822)
			(xy 35.58313 -48.70984) (xy 35.49623 -48.70984) (xy 35.409701 -48.701822) (xy 35.324281 -48.685854)
			(xy 35.240699 -48.662073) (xy 35.159667 -48.630681) (xy 35.081878 -48.591947) (xy 35.007994 -48.5462)
			(xy 34.938647 -48.493831) (xy 34.874427 -48.435287) (xy 34.815883 -48.371067) (xy 34.763514 -48.30172)
			(xy 34.717767 -48.227836) (xy 34.679033 -48.150047) (xy 34.647641 -48.069015) (xy 34.62386 -47.985433)
			(xy 34.607892 -47.900013) (xy 34.599874 -47.813484) (xy 31.399486 -47.813484) (xy 31.391468 -47.900013)
			(xy 31.3755 -47.985433) (xy 31.351719 -48.069015) (xy 31.320327 -48.150047) (xy 31.281593 -48.227836)
			(xy 31.235846 -48.30172) (xy 31.183477 -48.371067) (xy 31.124933 -48.435287) (xy 31.060713 -48.493831)
			(xy 30.991366 -48.5462) (xy 30.917482 -48.591947) (xy 30.839693 -48.630681) (xy 30.758661 -48.662073)
			(xy 30.675079 -48.685854) (xy 30.589659 -48.701822) (xy 30.50313 -48.70984) (xy 30.41623 -48.70984)
			(xy 30.329701 -48.701822) (xy 30.244281 -48.685854) (xy 30.160699 -48.662073) (xy 30.079667 -48.630681)
			(xy 30.001878 -48.591947) (xy 29.927994 -48.5462) (xy 29.858647 -48.493831) (xy 29.794427 -48.435287)
			(xy 29.735883 -48.371067) (xy 29.683514 -48.30172) (xy 29.637767 -48.227836) (xy 29.599033 -48.150047)
			(xy 29.567641 -48.069015) (xy 29.54386 -47.985433) (xy 29.527892 -47.900013) (xy 29.519874 -47.813484)
			(xy 24.743664 -47.813484) (xy 24.743664 -50.353484) (xy 29.519874 -50.353484) (xy 29.519874 -50.266584)
			(xy 29.527892 -50.180055) (xy 29.54386 -50.094635) (xy 29.567641 -50.011053) (xy 29.599033 -49.930021)
			(xy 29.637767 -49.852232) (xy 29.683514 -49.778348) (xy 29.735883 -49.709001) (xy 29.794427 -49.644781)
			(xy 29.858647 -49.586237) (xy 29.927994 -49.533868) (xy 30.001878 -49.488121) (xy 30.079667 -49.449387)
			(xy 30.160699 -49.417995) (xy 30.244281 -49.394214) (xy 30.329701 -49.378246) (xy 30.41623 -49.370228)
			(xy 30.50313 -49.370228) (xy 30.589659 -49.378246) (xy 30.675079 -49.394214) (xy 30.758661 -49.417995)
			(xy 30.839693 -49.449387) (xy 30.917482 -49.488121) (xy 30.991366 -49.533868) (xy 31.060713 -49.586237)
			(xy 31.124933 -49.644781) (xy 31.183477 -49.709001) (xy 31.235846 -49.778348) (xy 31.281593 -49.852232)
			(xy 31.320327 -49.930021) (xy 31.351719 -50.011053) (xy 31.3755 -50.094635) (xy 31.391468 -50.180055)
			(xy 31.399486 -50.266584) (xy 31.399988 -50.310034) (xy 31.399486 -50.353484) (xy 34.599874 -50.353484)
			(xy 34.599874 -50.266584) (xy 34.607892 -50.180055) (xy 34.62386 -50.094635) (xy 34.647641 -50.011053)
			(xy 34.679033 -49.930021) (xy 34.717767 -49.852232) (xy 34.763514 -49.778348) (xy 34.815883 -49.709001)
			(xy 34.874427 -49.644781) (xy 34.938647 -49.586237) (xy 35.007994 -49.533868) (xy 35.081878 -49.488121)
			(xy 35.159667 -49.449387) (xy 35.240699 -49.417995) (xy 35.324281 -49.394214) (xy 35.409701 -49.378246)
			(xy 35.49623 -49.370228) (xy 35.58313 -49.370228) (xy 35.669659 -49.378246) (xy 35.755079 -49.394214)
			(xy 35.838661 -49.417995) (xy 35.919693 -49.449387) (xy 35.997482 -49.488121) (xy 36.071366 -49.533868)
			(xy 36.140713 -49.586237) (xy 36.204933 -49.644781) (xy 36.263477 -49.709001) (xy 36.315846 -49.778348)
			(xy 36.361593 -49.852232) (xy 36.400327 -49.930021) (xy 36.431719 -50.011053) (xy 36.4555 -50.094635)
			(xy 36.471468 -50.180055) (xy 36.479486 -50.266584) (xy 36.479988 -50.310034) (xy 36.479486 -50.353484)
			(xy 36.471468 -50.440013) (xy 36.4555 -50.525433) (xy 36.431719 -50.609015) (xy 36.400327 -50.690047)
			(xy 36.361593 -50.767836) (xy 36.315846 -50.84172) (xy 36.263477 -50.911067) (xy 36.204933 -50.975287)
			(xy 36.140713 -51.033831) (xy 36.071366 -51.0862) (xy 35.997482 -51.131947) (xy 35.919693 -51.170681)
			(xy 35.838661 -51.202073) (xy 35.755079 -51.225854) (xy 35.669659 -51.241822) (xy 35.58313 -51.24984)
			(xy 35.49623 -51.24984) (xy 35.409701 -51.241822) (xy 35.324281 -51.225854) (xy 35.240699 -51.202073)
			(xy 35.159667 -51.170681) (xy 35.081878 -51.131947) (xy 35.007994 -51.0862) (xy 34.938647 -51.033831)
			(xy 34.874427 -50.975287) (xy 34.815883 -50.911067) (xy 34.763514 -50.84172) (xy 34.717767 -50.767836)
			(xy 34.679033 -50.690047) (xy 34.647641 -50.609015) (xy 34.62386 -50.525433) (xy 34.607892 -50.440013)
			(xy 34.599874 -50.353484) (xy 31.399486 -50.353484) (xy 31.391468 -50.440013) (xy 31.3755 -50.525433)
			(xy 31.351719 -50.609015) (xy 31.320327 -50.690047) (xy 31.281593 -50.767836) (xy 31.235846 -50.84172)
			(xy 31.183477 -50.911067) (xy 31.124933 -50.975287) (xy 31.060713 -51.033831) (xy 30.991366 -51.0862)
			(xy 30.917482 -51.131947) (xy 30.839693 -51.170681) (xy 30.758661 -51.202073) (xy 30.675079 -51.225854)
			(xy 30.589659 -51.241822) (xy 30.50313 -51.24984) (xy 30.41623 -51.24984) (xy 30.329701 -51.241822)
			(xy 30.244281 -51.225854) (xy 30.160699 -51.202073) (xy 30.079667 -51.170681) (xy 30.001878 -51.131947)
			(xy 29.927994 -51.0862) (xy 29.858647 -51.033831) (xy 29.794427 -50.975287) (xy 29.735883 -50.911067)
			(xy 29.683514 -50.84172) (xy 29.637767 -50.767836) (xy 29.599033 -50.690047) (xy 29.567641 -50.609015)
			(xy 29.54386 -50.525433) (xy 29.527892 -50.440013) (xy 29.519874 -50.353484) (xy 24.743664 -50.353484)
			(xy 24.743664 -51.36007) (xy 39.818063 -51.36007) (xy 39.82207 -51.244046) (xy 39.834072 -51.128574)
			(xy 39.854012 -51.014206) (xy 39.881795 -50.901486) (xy 39.917289 -50.790952) (xy 39.960324 -50.683129)
			(xy 40.010695 -50.578532) (xy 40.068162 -50.47766) (xy 40.132452 -50.380993) (xy 40.203257 -50.288992)
			(xy 40.280241 -50.202095) (xy 40.363037 -50.120716) (xy 40.45125 -50.045243) (xy 40.54446 -49.976036)
			(xy 40.642223 -49.913424) (xy 40.744072 -49.857707) (xy 40.849522 -49.809149) (xy 40.958071 -49.767981)
			(xy 41.069202 -49.734401) (xy 41.182385 -49.708568) (xy 41.29708 -49.690605) (xy 41.412742 -49.680597)
			(xy 41.528818 -49.678594) (xy 41.644756 -49.684603) (xy 41.760003 -49.698596) (xy 41.874009 -49.720507)
			(xy 41.986233 -49.750232) (xy 42.096139 -49.787628) (xy 42.203202 -49.832517) (xy 42.306914 -49.884686)
			(xy 42.406779 -49.943886) (xy 42.502322 -50.009835) (xy 42.502604 -50.01006) (xy 43.327577 -50.01006)
			(xy 43.331612 -49.934356) (xy 43.343671 -49.859511) (xy 43.363617 -49.78637) (xy 43.391224 -49.715765)
			(xy 43.42618 -49.648494) (xy 43.468088 -49.585319) (xy 43.516474 -49.526957) (xy 43.57079 -49.474069)
			(xy 43.630419 -49.427254) (xy 43.694687 -49.387042) (xy 43.762864 -49.35389) (xy 43.83418 -49.328172)
			(xy 43.907825 -49.31018) (xy 43.982965 -49.300118) (xy 44.058749 -49.298099) (xy 44.134319 -49.304148)
			(xy 44.208817 -49.318195) (xy 44.2814 -49.340081) (xy 44.351246 -49.369558) (xy 44.417563 -49.406293)
			(xy 44.479599 -49.449868) (xy 44.536652 -49.49979) (xy 44.588076 -49.555494) (xy 44.633287 -49.616349)
			(xy 44.671774 -49.681664) (xy 44.7031 -49.7507) (xy 44.72691 -49.822675) (xy 44.742935 -49.896773)
			(xy 44.750994 -49.972154) (xy 44.751498 -50.01006) (xy 45.867577 -50.01006) (xy 45.871612 -49.934356)
			(xy 45.883671 -49.859511) (xy 45.903617 -49.78637) (xy 45.931224 -49.715765) (xy 45.96618 -49.648494)
			(xy 46.008088 -49.585319) (xy 46.056474 -49.526957) (xy 46.11079 -49.474069) (xy 46.170419 -49.427254)
			(xy 46.234687 -49.387042) (xy 46.302864 -49.35389) (xy 46.37418 -49.328172) (xy 46.447825 -49.31018)
			(xy 46.522965 -49.300118) (xy 46.598749 -49.298099) (xy 46.674319 -49.304148) (xy 46.748817 -49.318195)
			(xy 46.8214 -49.340081) (xy 46.891246 -49.369558) (xy 46.957563 -49.406293) (xy 47.019599 -49.449868)
			(xy 47.076652 -49.49979) (xy 47.128076 -49.555494) (xy 47.173287 -49.616349) (xy 47.211774 -49.681664)
			(xy 47.2431 -49.7507) (xy 47.26691 -49.822675) (xy 47.282935 -49.896773) (xy 47.290994 -49.972154)
			(xy 47.291498 -50.01006) (xy 48.407577 -50.01006) (xy 48.411612 -49.934356) (xy 48.423671 -49.859511)
			(xy 48.443617 -49.78637) (xy 48.471224 -49.715765) (xy 48.50618 -49.648494) (xy 48.548088 -49.585319)
			(xy 48.596474 -49.526957) (xy 48.65079 -49.474069) (xy 48.710419 -49.427254) (xy 48.774687 -49.387042)
			(xy 48.842864 -49.35389) (xy 48.91418 -49.328172) (xy 48.987825 -49.31018) (xy 49.062965 -49.300118)
			(xy 49.138749 -49.298099) (xy 49.214319 -49.304148) (xy 49.288817 -49.318195) (xy 49.3614 -49.340081)
			(xy 49.431246 -49.369558) (xy 49.497563 -49.406293) (xy 49.559599 -49.449868) (xy 49.616652 -49.49979)
			(xy 49.668076 -49.555494) (xy 49.713287 -49.616349) (xy 49.751774 -49.681664) (xy 49.7831 -49.7507)
			(xy 49.80691 -49.822675) (xy 49.822935 -49.896773) (xy 49.830994 -49.972154) (xy 49.831498 -50.01006)
			(xy 50.947577 -50.01006) (xy 50.951612 -49.934356) (xy 50.963671 -49.859511) (xy 50.983617 -49.78637)
			(xy 51.011224 -49.715765) (xy 51.04618 -49.648494) (xy 51.088088 -49.585319) (xy 51.136474 -49.526957)
			(xy 51.19079 -49.474069) (xy 51.250419 -49.427254) (xy 51.314687 -49.387042) (xy 51.382864 -49.35389)
			(xy 51.45418 -49.328172) (xy 51.527825 -49.31018) (xy 51.602965 -49.300118) (xy 51.678749 -49.298099)
			(xy 51.754319 -49.304148) (xy 51.828817 -49.318195) (xy 51.9014 -49.340081) (xy 51.971246 -49.369558)
			(xy 52.037563 -49.406293) (xy 52.099599 -49.449868) (xy 52.156652 -49.49979) (xy 52.208076 -49.555494)
			(xy 52.253287 -49.616349) (xy 52.291774 -49.681664) (xy 52.3231 -49.7507) (xy 52.34691 -49.822675)
			(xy 52.362935 -49.896773) (xy 52.370994 -49.972154) (xy 52.371498 -50.01006) (xy 53.487577 -50.01006)
			(xy 53.491612 -49.934356) (xy 53.503671 -49.859511) (xy 53.523617 -49.78637) (xy 53.551224 -49.715765)
			(xy 53.58618 -49.648494) (xy 53.628088 -49.585319) (xy 53.676474 -49.526957) (xy 53.73079 -49.474069)
			(xy 53.790419 -49.427254) (xy 53.854687 -49.387042) (xy 53.922864 -49.35389) (xy 53.99418 -49.328172)
			(xy 54.067825 -49.31018) (xy 54.142965 -49.300118) (xy 54.218749 -49.298099) (xy 54.294319 -49.304148)
			(xy 54.368817 -49.318195) (xy 54.4414 -49.340081) (xy 54.511246 -49.369558) (xy 54.577563 -49.406293)
			(xy 54.639599 -49.449868) (xy 54.696652 -49.49979) (xy 54.748076 -49.555494) (xy 54.793287 -49.616349)
			(xy 54.831774 -49.681664) (xy 54.8631 -49.7507) (xy 54.88691 -49.822675) (xy 54.902935 -49.896773)
			(xy 54.910994 -49.972154) (xy 54.911498 -50.01006) (xy 56.027577 -50.01006) (xy 56.031612 -49.934356)
			(xy 56.043671 -49.859511) (xy 56.063617 -49.78637) (xy 56.091224 -49.715765) (xy 56.12618 -49.648494)
			(xy 56.168088 -49.585319) (xy 56.216474 -49.526957) (xy 56.27079 -49.474069) (xy 56.330419 -49.427254)
			(xy 56.394687 -49.387042) (xy 56.462864 -49.35389) (xy 56.53418 -49.328172) (xy 56.607825 -49.31018)
			(xy 56.682965 -49.300118) (xy 56.758749 -49.298099) (xy 56.834319 -49.304148) (xy 56.908817 -49.318195)
			(xy 56.9814 -49.340081) (xy 57.051246 -49.369558) (xy 57.117563 -49.406293) (xy 57.179599 -49.449868)
			(xy 57.236652 -49.49979) (xy 57.288076 -49.555494) (xy 57.333287 -49.616349) (xy 57.371774 -49.681664)
			(xy 57.4031 -49.7507) (xy 57.42691 -49.822675) (xy 57.442935 -49.896773) (xy 57.450994 -49.972154)
			(xy 57.451498 -50.01006) (xy 58.567577 -50.01006) (xy 58.571612 -49.934356) (xy 58.583671 -49.859511)
			(xy 58.603617 -49.78637) (xy 58.631224 -49.715765) (xy 58.66618 -49.648494) (xy 58.708088 -49.585319)
			(xy 58.756474 -49.526957) (xy 58.81079 -49.474069) (xy 58.870419 -49.427254) (xy 58.934687 -49.387042)
			(xy 59.002864 -49.35389) (xy 59.07418 -49.328172) (xy 59.147825 -49.31018) (xy 59.222965 -49.300118)
			(xy 59.298749 -49.298099) (xy 59.374319 -49.304148) (xy 59.448817 -49.318195) (xy 59.5214 -49.340081)
			(xy 59.591246 -49.369558) (xy 59.657563 -49.406293) (xy 59.719599 -49.449868) (xy 59.776652 -49.49979)
			(xy 59.828076 -49.555494) (xy 59.873287 -49.616349) (xy 59.911774 -49.681664) (xy 59.9431 -49.7507)
			(xy 59.96691 -49.822675) (xy 59.982935 -49.896773) (xy 59.990994 -49.972154) (xy 59.991498 -50.01006)
			(xy 61.107577 -50.01006) (xy 61.111612 -49.934356) (xy 61.123671 -49.859511) (xy 61.143617 -49.78637)
			(xy 61.171224 -49.715765) (xy 61.20618 -49.648494) (xy 61.248088 -49.585319) (xy 61.296474 -49.526957)
			(xy 61.35079 -49.474069) (xy 61.410419 -49.427254) (xy 61.474687 -49.387042) (xy 61.542864 -49.35389)
			(xy 61.61418 -49.328172) (xy 61.687825 -49.31018) (xy 61.762965 -49.300118) (xy 61.838749 -49.298099)
			(xy 61.914319 -49.304148) (xy 61.988817 -49.318195) (xy 62.0614 -49.340081) (xy 62.131246 -49.369558)
			(xy 62.197563 -49.406293) (xy 62.259599 -49.449868) (xy 62.316652 -49.49979) (xy 62.368076 -49.555494)
			(xy 62.413287 -49.616349) (xy 62.451774 -49.681664) (xy 62.4831 -49.7507) (xy 62.50691 -49.822675)
			(xy 62.522935 -49.896773) (xy 62.530994 -49.972154) (xy 62.531498 -50.01006) (xy 62.530994 -50.047966)
			(xy 62.522935 -50.123347) (xy 62.50691 -50.197445) (xy 62.4831 -50.26942) (xy 62.451774 -50.338456)
			(xy 62.413287 -50.403771) (xy 62.368076 -50.464626) (xy 62.316652 -50.52033) (xy 62.259599 -50.570252)
			(xy 62.197563 -50.613827) (xy 62.131246 -50.650562) (xy 62.0614 -50.680039) (xy 61.988817 -50.701925)
			(xy 61.914319 -50.715972) (xy 61.838749 -50.722021) (xy 61.762965 -50.720002) (xy 61.687825 -50.70994)
			(xy 61.61418 -50.691948) (xy 61.542864 -50.66623) (xy 61.474687 -50.633078) (xy 61.410419 -50.592866)
			(xy 61.35079 -50.546051) (xy 61.296474 -50.493163) (xy 61.248088 -50.434801) (xy 61.20618 -50.371626)
			(xy 61.171224 -50.304355) (xy 61.143617 -50.23375) (xy 61.123671 -50.160609) (xy 61.111612 -50.085764)
			(xy 61.107577 -50.01006) (xy 59.991498 -50.01006) (xy 59.990994 -50.047966) (xy 59.982935 -50.123347)
			(xy 59.96691 -50.197445) (xy 59.9431 -50.26942) (xy 59.911774 -50.338456) (xy 59.873287 -50.403771)
			(xy 59.828076 -50.464626) (xy 59.776652 -50.52033) (xy 59.719599 -50.570252) (xy 59.657563 -50.613827)
			(xy 59.591246 -50.650562) (xy 59.5214 -50.680039) (xy 59.448817 -50.701925) (xy 59.374319 -50.715972)
			(xy 59.298749 -50.722021) (xy 59.222965 -50.720002) (xy 59.147825 -50.70994) (xy 59.07418 -50.691948)
			(xy 59.002864 -50.66623) (xy 58.934687 -50.633078) (xy 58.870419 -50.592866) (xy 58.81079 -50.546051)
			(xy 58.756474 -50.493163) (xy 58.708088 -50.434801) (xy 58.66618 -50.371626) (xy 58.631224 -50.304355)
			(xy 58.603617 -50.23375) (xy 58.583671 -50.160609) (xy 58.571612 -50.085764) (xy 58.567577 -50.01006)
			(xy 57.451498 -50.01006) (xy 57.450994 -50.047966) (xy 57.442935 -50.123347) (xy 57.42691 -50.197445)
			(xy 57.4031 -50.26942) (xy 57.371774 -50.338456) (xy 57.333287 -50.403771) (xy 57.288076 -50.464626)
			(xy 57.236652 -50.52033) (xy 57.179599 -50.570252) (xy 57.117563 -50.613827) (xy 57.051246 -50.650562)
			(xy 56.9814 -50.680039) (xy 56.908817 -50.701925) (xy 56.834319 -50.715972) (xy 56.758749 -50.722021)
			(xy 56.682965 -50.720002) (xy 56.607825 -50.70994) (xy 56.53418 -50.691948) (xy 56.462864 -50.66623)
			(xy 56.394687 -50.633078) (xy 56.330419 -50.592866) (xy 56.27079 -50.546051) (xy 56.216474 -50.493163)
			(xy 56.168088 -50.434801) (xy 56.12618 -50.371626) (xy 56.091224 -50.304355) (xy 56.063617 -50.23375)
			(xy 56.043671 -50.160609) (xy 56.031612 -50.085764) (xy 56.027577 -50.01006) (xy 54.911498 -50.01006)
			(xy 54.910994 -50.047966) (xy 54.902935 -50.123347) (xy 54.88691 -50.197445) (xy 54.8631 -50.26942)
			(xy 54.831774 -50.338456) (xy 54.793287 -50.403771) (xy 54.748076 -50.464626) (xy 54.696652 -50.52033)
			(xy 54.639599 -50.570252) (xy 54.577563 -50.613827) (xy 54.511246 -50.650562) (xy 54.4414 -50.680039)
			(xy 54.368817 -50.701925) (xy 54.294319 -50.715972) (xy 54.218749 -50.722021) (xy 54.142965 -50.720002)
			(xy 54.067825 -50.70994) (xy 53.99418 -50.691948) (xy 53.922864 -50.66623) (xy 53.854687 -50.633078)
			(xy 53.790419 -50.592866) (xy 53.73079 -50.546051) (xy 53.676474 -50.493163) (xy 53.628088 -50.434801)
			(xy 53.58618 -50.371626) (xy 53.551224 -50.304355) (xy 53.523617 -50.23375) (xy 53.503671 -50.160609)
			(xy 53.491612 -50.085764) (xy 53.487577 -50.01006) (xy 52.371498 -50.01006) (xy 52.370994 -50.047966)
			(xy 52.362935 -50.123347) (xy 52.34691 -50.197445) (xy 52.3231 -50.26942) (xy 52.291774 -50.338456)
			(xy 52.253287 -50.403771) (xy 52.208076 -50.464626) (xy 52.156652 -50.52033) (xy 52.099599 -50.570252)
			(xy 52.037563 -50.613827) (xy 51.971246 -50.650562) (xy 51.9014 -50.680039) (xy 51.828817 -50.701925)
			(xy 51.754319 -50.715972) (xy 51.678749 -50.722021) (xy 51.602965 -50.720002) (xy 51.527825 -50.70994)
			(xy 51.45418 -50.691948) (xy 51.382864 -50.66623) (xy 51.314687 -50.633078) (xy 51.250419 -50.592866)
			(xy 51.19079 -50.546051) (xy 51.136474 -50.493163) (xy 51.088088 -50.434801) (xy 51.04618 -50.371626)
			(xy 51.011224 -50.304355) (xy 50.983617 -50.23375) (xy 50.963671 -50.160609) (xy 50.951612 -50.085764)
			(xy 50.947577 -50.01006) (xy 49.831498 -50.01006) (xy 49.830994 -50.047966) (xy 49.822935 -50.123347)
			(xy 49.80691 -50.197445) (xy 49.7831 -50.26942) (xy 49.751774 -50.338456) (xy 49.713287 -50.403771)
			(xy 49.668076 -50.464626) (xy 49.616652 -50.52033) (xy 49.559599 -50.570252) (xy 49.497563 -50.613827)
			(xy 49.431246 -50.650562) (xy 49.3614 -50.680039) (xy 49.288817 -50.701925) (xy 49.214319 -50.715972)
			(xy 49.138749 -50.722021) (xy 49.062965 -50.720002) (xy 48.987825 -50.70994) (xy 48.91418 -50.691948)
			(xy 48.842864 -50.66623) (xy 48.774687 -50.633078) (xy 48.710419 -50.592866) (xy 48.65079 -50.546051)
			(xy 48.596474 -50.493163) (xy 48.548088 -50.434801) (xy 48.50618 -50.371626) (xy 48.471224 -50.304355)
			(xy 48.443617 -50.23375) (xy 48.423671 -50.160609) (xy 48.411612 -50.085764) (xy 48.407577 -50.01006)
			(xy 47.291498 -50.01006) (xy 47.290994 -50.047966) (xy 47.282935 -50.123347) (xy 47.26691 -50.197445)
			(xy 47.2431 -50.26942) (xy 47.211774 -50.338456) (xy 47.173287 -50.403771) (xy 47.128076 -50.464626)
			(xy 47.076652 -50.52033) (xy 47.019599 -50.570252) (xy 46.957563 -50.613827) (xy 46.891246 -50.650562)
			(xy 46.8214 -50.680039) (xy 46.748817 -50.701925) (xy 46.674319 -50.715972) (xy 46.598749 -50.722021)
			(xy 46.522965 -50.720002) (xy 46.447825 -50.70994) (xy 46.37418 -50.691948) (xy 46.302864 -50.66623)
			(xy 46.234687 -50.633078) (xy 46.170419 -50.592866) (xy 46.11079 -50.546051) (xy 46.056474 -50.493163)
			(xy 46.008088 -50.434801) (xy 45.96618 -50.371626) (xy 45.931224 -50.304355) (xy 45.903617 -50.23375)
			(xy 45.883671 -50.160609) (xy 45.871612 -50.085764) (xy 45.867577 -50.01006) (xy 44.751498 -50.01006)
			(xy 44.750994 -50.047966) (xy 44.742935 -50.123347) (xy 44.72691 -50.197445) (xy 44.7031 -50.26942)
			(xy 44.671774 -50.338456) (xy 44.633287 -50.403771) (xy 44.588076 -50.464626) (xy 44.536652 -50.52033)
			(xy 44.479599 -50.570252) (xy 44.417563 -50.613827) (xy 44.351246 -50.650562) (xy 44.2814 -50.680039)
			(xy 44.208817 -50.701925) (xy 44.134319 -50.715972) (xy 44.058749 -50.722021) (xy 43.982965 -50.720002)
			(xy 43.907825 -50.70994) (xy 43.83418 -50.691948) (xy 43.762864 -50.66623) (xy 43.694687 -50.633078)
			(xy 43.630419 -50.592866) (xy 43.57079 -50.546051) (xy 43.516474 -50.493163) (xy 43.468088 -50.434801)
			(xy 43.42618 -50.371626) (xy 43.391224 -50.304355) (xy 43.363617 -50.23375) (xy 43.343671 -50.160609)
			(xy 43.331612 -50.085764) (xy 43.327577 -50.01006) (xy 42.502604 -50.01006) (xy 42.593088 -50.082218)
			(xy 42.678643 -50.160691) (xy 42.758581 -50.244879) (xy 42.83252 -50.334381) (xy 42.900108 -50.428772)
			(xy 42.961022 -50.5276) (xy 43.014974 -50.630396) (xy 43.061704 -50.736669) (xy 43.100992 -50.845913)
			(xy 43.132649 -50.957606) (xy 43.156525 -51.071218) (xy 43.172506 -51.186206) (xy 43.180515 -51.302023)
			(xy 43.181016 -51.36007) (xy 43.180515 -51.418117) (xy 43.172506 -51.533934) (xy 43.156525 -51.648922)
			(xy 43.132649 -51.762534) (xy 43.100992 -51.874227) (xy 43.061704 -51.983471) (xy 43.014974 -52.089744)
			(xy 42.961022 -52.19254) (xy 42.900108 -52.291368) (xy 42.83252 -52.385759) (xy 42.758581 -52.475261)
			(xy 42.678643 -52.559449) (xy 42.593088 -52.637922) (xy 42.502604 -52.71008) (xy 43.327577 -52.71008)
			(xy 43.331612 -52.634376) (xy 43.343671 -52.559531) (xy 43.363617 -52.48639) (xy 43.391224 -52.415785)
			(xy 43.42618 -52.348514) (xy 43.468088 -52.285339) (xy 43.516474 -52.226977) (xy 43.57079 -52.174089)
			(xy 43.630419 -52.127274) (xy 43.694687 -52.087062) (xy 43.762864 -52.05391) (xy 43.83418 -52.028192)
			(xy 43.907825 -52.0102) (xy 43.982965 -52.000138) (xy 44.058749 -51.998119) (xy 44.134319 -52.004168)
			(xy 44.208817 -52.018215) (xy 44.2814 -52.040101) (xy 44.351246 -52.069578) (xy 44.417563 -52.106313)
			(xy 44.479599 -52.149888) (xy 44.536652 -52.19981) (xy 44.588076 -52.255514) (xy 44.633287 -52.316369)
			(xy 44.671774 -52.381684) (xy 44.7031 -52.45072) (xy 44.72691 -52.522695) (xy 44.742935 -52.596793)
			(xy 44.750994 -52.672174) (xy 44.751498 -52.71008) (xy 45.867577 -52.71008) (xy 45.871612 -52.634376)
			(xy 45.883671 -52.559531) (xy 45.903617 -52.48639) (xy 45.931224 -52.415785) (xy 45.96618 -52.348514)
			(xy 46.008088 -52.285339) (xy 46.056474 -52.226977) (xy 46.11079 -52.174089) (xy 46.170419 -52.127274)
			(xy 46.234687 -52.087062) (xy 46.302864 -52.05391) (xy 46.37418 -52.028192) (xy 46.447825 -52.0102)
			(xy 46.522965 -52.000138) (xy 46.598749 -51.998119) (xy 46.674319 -52.004168) (xy 46.748817 -52.018215)
			(xy 46.8214 -52.040101) (xy 46.891246 -52.069578) (xy 46.957563 -52.106313) (xy 47.019599 -52.149888)
			(xy 47.076652 -52.19981) (xy 47.128076 -52.255514) (xy 47.173287 -52.316369) (xy 47.211774 -52.381684)
			(xy 47.2431 -52.45072) (xy 47.26691 -52.522695) (xy 47.282935 -52.596793) (xy 47.290994 -52.672174)
			(xy 47.291498 -52.71008) (xy 48.407577 -52.71008) (xy 48.411612 -52.634376) (xy 48.423671 -52.559531)
			(xy 48.443617 -52.48639) (xy 48.471224 -52.415785) (xy 48.50618 -52.348514) (xy 48.548088 -52.285339)
			(xy 48.596474 -52.226977) (xy 48.65079 -52.174089) (xy 48.710419 -52.127274) (xy 48.774687 -52.087062)
			(xy 48.842864 -52.05391) (xy 48.91418 -52.028192) (xy 48.987825 -52.0102) (xy 49.062965 -52.000138)
			(xy 49.138749 -51.998119) (xy 49.214319 -52.004168) (xy 49.288817 -52.018215) (xy 49.3614 -52.040101)
			(xy 49.431246 -52.069578) (xy 49.497563 -52.106313) (xy 49.559599 -52.149888) (xy 49.616652 -52.19981)
			(xy 49.668076 -52.255514) (xy 49.713287 -52.316369) (xy 49.751774 -52.381684) (xy 49.7831 -52.45072)
			(xy 49.80691 -52.522695) (xy 49.822935 -52.596793) (xy 49.830994 -52.672174) (xy 49.831498 -52.71008)
			(xy 50.947577 -52.71008) (xy 50.951612 -52.634376) (xy 50.963671 -52.559531) (xy 50.983617 -52.48639)
			(xy 51.011224 -52.415785) (xy 51.04618 -52.348514) (xy 51.088088 -52.285339) (xy 51.136474 -52.226977)
			(xy 51.19079 -52.174089) (xy 51.250419 -52.127274) (xy 51.314687 -52.087062) (xy 51.382864 -52.05391)
			(xy 51.45418 -52.028192) (xy 51.527825 -52.0102) (xy 51.602965 -52.000138) (xy 51.678749 -51.998119)
			(xy 51.754319 -52.004168) (xy 51.828817 -52.018215) (xy 51.9014 -52.040101) (xy 51.971246 -52.069578)
			(xy 52.037563 -52.106313) (xy 52.099599 -52.149888) (xy 52.156652 -52.19981) (xy 52.208076 -52.255514)
			(xy 52.253287 -52.316369) (xy 52.291774 -52.381684) (xy 52.3231 -52.45072) (xy 52.34691 -52.522695)
			(xy 52.362935 -52.596793) (xy 52.370994 -52.672174) (xy 52.371498 -52.71008) (xy 53.487577 -52.71008)
			(xy 53.491612 -52.634376) (xy 53.503671 -52.559531) (xy 53.523617 -52.48639) (xy 53.551224 -52.415785)
			(xy 53.58618 -52.348514) (xy 53.628088 -52.285339) (xy 53.676474 -52.226977) (xy 53.73079 -52.174089)
			(xy 53.790419 -52.127274) (xy 53.854687 -52.087062) (xy 53.922864 -52.05391) (xy 53.99418 -52.028192)
			(xy 54.067825 -52.0102) (xy 54.142965 -52.000138) (xy 54.218749 -51.998119) (xy 54.294319 -52.004168)
			(xy 54.368817 -52.018215) (xy 54.4414 -52.040101) (xy 54.511246 -52.069578) (xy 54.577563 -52.106313)
			(xy 54.639599 -52.149888) (xy 54.696652 -52.19981) (xy 54.748076 -52.255514) (xy 54.793287 -52.316369)
			(xy 54.831774 -52.381684) (xy 54.8631 -52.45072) (xy 54.88691 -52.522695) (xy 54.902935 -52.596793)
			(xy 54.910994 -52.672174) (xy 54.911498 -52.71008) (xy 56.027577 -52.71008) (xy 56.031612 -52.634376)
			(xy 56.043671 -52.559531) (xy 56.063617 -52.48639) (xy 56.091224 -52.415785) (xy 56.12618 -52.348514)
			(xy 56.168088 -52.285339) (xy 56.216474 -52.226977) (xy 56.27079 -52.174089) (xy 56.330419 -52.127274)
			(xy 56.394687 -52.087062) (xy 56.462864 -52.05391) (xy 56.53418 -52.028192) (xy 56.607825 -52.0102)
			(xy 56.682965 -52.000138) (xy 56.758749 -51.998119) (xy 56.834319 -52.004168) (xy 56.908817 -52.018215)
			(xy 56.9814 -52.040101) (xy 57.051246 -52.069578) (xy 57.117563 -52.106313) (xy 57.179599 -52.149888)
			(xy 57.236652 -52.19981) (xy 57.288076 -52.255514) (xy 57.333287 -52.316369) (xy 57.371774 -52.381684)
			(xy 57.4031 -52.45072) (xy 57.42691 -52.522695) (xy 57.442935 -52.596793) (xy 57.450994 -52.672174)
			(xy 57.451498 -52.71008) (xy 58.567577 -52.71008) (xy 58.571612 -52.634376) (xy 58.583671 -52.559531)
			(xy 58.603617 -52.48639) (xy 58.631224 -52.415785) (xy 58.66618 -52.348514) (xy 58.708088 -52.285339)
			(xy 58.756474 -52.226977) (xy 58.81079 -52.174089) (xy 58.870419 -52.127274) (xy 58.934687 -52.087062)
			(xy 59.002864 -52.05391) (xy 59.07418 -52.028192) (xy 59.147825 -52.0102) (xy 59.222965 -52.000138)
			(xy 59.298749 -51.998119) (xy 59.374319 -52.004168) (xy 59.448817 -52.018215) (xy 59.5214 -52.040101)
			(xy 59.591246 -52.069578) (xy 59.657563 -52.106313) (xy 59.719599 -52.149888) (xy 59.776652 -52.19981)
			(xy 59.828076 -52.255514) (xy 59.873287 -52.316369) (xy 59.911774 -52.381684) (xy 59.9431 -52.45072)
			(xy 59.96691 -52.522695) (xy 59.982935 -52.596793) (xy 59.990994 -52.672174) (xy 59.991498 -52.71008)
			(xy 61.107577 -52.71008) (xy 61.111612 -52.634376) (xy 61.123671 -52.559531) (xy 61.143617 -52.48639)
			(xy 61.171224 -52.415785) (xy 61.20618 -52.348514) (xy 61.248088 -52.285339) (xy 61.296474 -52.226977)
			(xy 61.35079 -52.174089) (xy 61.410419 -52.127274) (xy 61.474687 -52.087062) (xy 61.542864 -52.05391)
			(xy 61.61418 -52.028192) (xy 61.687825 -52.0102) (xy 61.762965 -52.000138) (xy 61.838749 -51.998119)
			(xy 61.914319 -52.004168) (xy 61.988817 -52.018215) (xy 62.0614 -52.040101) (xy 62.131246 -52.069578)
			(xy 62.197563 -52.106313) (xy 62.259599 -52.149888) (xy 62.316652 -52.19981) (xy 62.368076 -52.255514)
			(xy 62.413287 -52.316369) (xy 62.451774 -52.381684) (xy 62.4831 -52.45072) (xy 62.50691 -52.522695)
			(xy 62.522935 -52.596793) (xy 62.530994 -52.672174) (xy 62.531498 -52.71008) (xy 62.530994 -52.747986)
			(xy 62.522935 -52.823367) (xy 62.50691 -52.897465) (xy 62.4831 -52.96944) (xy 62.451774 -53.038476)
			(xy 62.413287 -53.103791) (xy 62.368076 -53.164646) (xy 62.316652 -53.22035) (xy 62.259599 -53.270272)
			(xy 62.197563 -53.313847) (xy 62.131246 -53.350582) (xy 62.0614 -53.380059) (xy 61.988817 -53.401945)
			(xy 61.914319 -53.415992) (xy 61.838749 -53.422041) (xy 61.762965 -53.420022) (xy 61.687825 -53.40996)
			(xy 61.61418 -53.391968) (xy 61.542864 -53.36625) (xy 61.474687 -53.333098) (xy 61.410419 -53.292886)
			(xy 61.35079 -53.246071) (xy 61.296474 -53.193183) (xy 61.248088 -53.134821) (xy 61.20618 -53.071646)
			(xy 61.171224 -53.004375) (xy 61.143617 -52.93377) (xy 61.123671 -52.860629) (xy 61.111612 -52.785784)
			(xy 61.107577 -52.71008) (xy 59.991498 -52.71008) (xy 59.990994 -52.747986) (xy 59.982935 -52.823367)
			(xy 59.96691 -52.897465) (xy 59.9431 -52.96944) (xy 59.911774 -53.038476) (xy 59.873287 -53.103791)
			(xy 59.828076 -53.164646) (xy 59.776652 -53.22035) (xy 59.719599 -53.270272) (xy 59.657563 -53.313847)
			(xy 59.591246 -53.350582) (xy 59.5214 -53.380059) (xy 59.448817 -53.401945) (xy 59.374319 -53.415992)
			(xy 59.298749 -53.422041) (xy 59.222965 -53.420022) (xy 59.147825 -53.40996) (xy 59.07418 -53.391968)
			(xy 59.002864 -53.36625) (xy 58.934687 -53.333098) (xy 58.870419 -53.292886) (xy 58.81079 -53.246071)
			(xy 58.756474 -53.193183) (xy 58.708088 -53.134821) (xy 58.66618 -53.071646) (xy 58.631224 -53.004375)
			(xy 58.603617 -52.93377) (xy 58.583671 -52.860629) (xy 58.571612 -52.785784) (xy 58.567577 -52.71008)
			(xy 57.451498 -52.71008) (xy 57.450994 -52.747986) (xy 57.442935 -52.823367) (xy 57.42691 -52.897465)
			(xy 57.4031 -52.96944) (xy 57.371774 -53.038476) (xy 57.333287 -53.103791) (xy 57.288076 -53.164646)
			(xy 57.236652 -53.22035) (xy 57.179599 -53.270272) (xy 57.117563 -53.313847) (xy 57.051246 -53.350582)
			(xy 56.9814 -53.380059) (xy 56.908817 -53.401945) (xy 56.834319 -53.415992) (xy 56.758749 -53.422041)
			(xy 56.682965 -53.420022) (xy 56.607825 -53.40996) (xy 56.53418 -53.391968) (xy 56.462864 -53.36625)
			(xy 56.394687 -53.333098) (xy 56.330419 -53.292886) (xy 56.27079 -53.246071) (xy 56.216474 -53.193183)
			(xy 56.168088 -53.134821) (xy 56.12618 -53.071646) (xy 56.091224 -53.004375) (xy 56.063617 -52.93377)
			(xy 56.043671 -52.860629) (xy 56.031612 -52.785784) (xy 56.027577 -52.71008) (xy 54.911498 -52.71008)
			(xy 54.910994 -52.747986) (xy 54.902935 -52.823367) (xy 54.88691 -52.897465) (xy 54.8631 -52.96944)
			(xy 54.831774 -53.038476) (xy 54.793287 -53.103791) (xy 54.748076 -53.164646) (xy 54.696652 -53.22035)
			(xy 54.639599 -53.270272) (xy 54.577563 -53.313847) (xy 54.511246 -53.350582) (xy 54.4414 -53.380059)
			(xy 54.368817 -53.401945) (xy 54.294319 -53.415992) (xy 54.218749 -53.422041) (xy 54.142965 -53.420022)
			(xy 54.067825 -53.40996) (xy 53.99418 -53.391968) (xy 53.922864 -53.36625) (xy 53.854687 -53.333098)
			(xy 53.790419 -53.292886) (xy 53.73079 -53.246071) (xy 53.676474 -53.193183) (xy 53.628088 -53.134821)
			(xy 53.58618 -53.071646) (xy 53.551224 -53.004375) (xy 53.523617 -52.93377) (xy 53.503671 -52.860629)
			(xy 53.491612 -52.785784) (xy 53.487577 -52.71008) (xy 52.371498 -52.71008) (xy 52.370994 -52.747986)
			(xy 52.362935 -52.823367) (xy 52.34691 -52.897465) (xy 52.3231 -52.96944) (xy 52.291774 -53.038476)
			(xy 52.253287 -53.103791) (xy 52.208076 -53.164646) (xy 52.156652 -53.22035) (xy 52.099599 -53.270272)
			(xy 52.037563 -53.313847) (xy 51.971246 -53.350582) (xy 51.9014 -53.380059) (xy 51.828817 -53.401945)
			(xy 51.754319 -53.415992) (xy 51.678749 -53.422041) (xy 51.602965 -53.420022) (xy 51.527825 -53.40996)
			(xy 51.45418 -53.391968) (xy 51.382864 -53.36625) (xy 51.314687 -53.333098) (xy 51.250419 -53.292886)
			(xy 51.19079 -53.246071) (xy 51.136474 -53.193183) (xy 51.088088 -53.134821) (xy 51.04618 -53.071646)
			(xy 51.011224 -53.004375) (xy 50.983617 -52.93377) (xy 50.963671 -52.860629) (xy 50.951612 -52.785784)
			(xy 50.947577 -52.71008) (xy 49.831498 -52.71008) (xy 49.830994 -52.747986) (xy 49.822935 -52.823367)
			(xy 49.80691 -52.897465) (xy 49.7831 -52.96944) (xy 49.751774 -53.038476) (xy 49.713287 -53.103791)
			(xy 49.668076 -53.164646) (xy 49.616652 -53.22035) (xy 49.559599 -53.270272) (xy 49.497563 -53.313847)
			(xy 49.431246 -53.350582) (xy 49.3614 -53.380059) (xy 49.288817 -53.401945) (xy 49.214319 -53.415992)
			(xy 49.138749 -53.422041) (xy 49.062965 -53.420022) (xy 48.987825 -53.40996) (xy 48.91418 -53.391968)
			(xy 48.842864 -53.36625) (xy 48.774687 -53.333098) (xy 48.710419 -53.292886) (xy 48.65079 -53.246071)
			(xy 48.596474 -53.193183) (xy 48.548088 -53.134821) (xy 48.50618 -53.071646) (xy 48.471224 -53.004375)
			(xy 48.443617 -52.93377) (xy 48.423671 -52.860629) (xy 48.411612 -52.785784) (xy 48.407577 -52.71008)
			(xy 47.291498 -52.71008) (xy 47.290994 -52.747986) (xy 47.282935 -52.823367) (xy 47.26691 -52.897465)
			(xy 47.2431 -52.96944) (xy 47.211774 -53.038476) (xy 47.173287 -53.103791) (xy 47.128076 -53.164646)
			(xy 47.076652 -53.22035) (xy 47.019599 -53.270272) (xy 46.957563 -53.313847) (xy 46.891246 -53.350582)
			(xy 46.8214 -53.380059) (xy 46.748817 -53.401945) (xy 46.674319 -53.415992) (xy 46.598749 -53.422041)
			(xy 46.522965 -53.420022) (xy 46.447825 -53.40996) (xy 46.37418 -53.391968) (xy 46.302864 -53.36625)
			(xy 46.234687 -53.333098) (xy 46.170419 -53.292886) (xy 46.11079 -53.246071) (xy 46.056474 -53.193183)
			(xy 46.008088 -53.134821) (xy 45.96618 -53.071646) (xy 45.931224 -53.004375) (xy 45.903617 -52.93377)
			(xy 45.883671 -52.860629) (xy 45.871612 -52.785784) (xy 45.867577 -52.71008) (xy 44.751498 -52.71008)
			(xy 44.750994 -52.747986) (xy 44.742935 -52.823367) (xy 44.72691 -52.897465) (xy 44.7031 -52.96944)
			(xy 44.671774 -53.038476) (xy 44.633287 -53.103791) (xy 44.588076 -53.164646) (xy 44.536652 -53.22035)
			(xy 44.479599 -53.270272) (xy 44.417563 -53.313847) (xy 44.351246 -53.350582) (xy 44.2814 -53.380059)
			(xy 44.208817 -53.401945) (xy 44.134319 -53.415992) (xy 44.058749 -53.422041) (xy 43.982965 -53.420022)
			(xy 43.907825 -53.40996) (xy 43.83418 -53.391968) (xy 43.762864 -53.36625) (xy 43.694687 -53.333098)
			(xy 43.630419 -53.292886) (xy 43.57079 -53.246071) (xy 43.516474 -53.193183) (xy 43.468088 -53.134821)
			(xy 43.42618 -53.071646) (xy 43.391224 -53.004375) (xy 43.363617 -52.93377) (xy 43.343671 -52.860629)
			(xy 43.331612 -52.785784) (xy 43.327577 -52.71008) (xy 42.502604 -52.71008) (xy 42.502322 -52.710305)
			(xy 42.406779 -52.776254) (xy 42.306914 -52.835454) (xy 42.203202 -52.887623) (xy 42.096139 -52.932512)
			(xy 41.986233 -52.969908) (xy 41.874009 -52.999633) (xy 41.760003 -53.021544) (xy 41.644756 -53.035537)
			(xy 41.528818 -53.041546) (xy 41.412742 -53.039543) (xy 41.29708 -53.029535) (xy 41.182385 -53.011572)
			(xy 41.069202 -52.985739) (xy 40.958071 -52.952159) (xy 40.849522 -52.910991) (xy 40.744072 -52.862433)
			(xy 40.642223 -52.806716) (xy 40.54446 -52.744104) (xy 40.45125 -52.674897) (xy 40.363037 -52.599424)
			(xy 40.280241 -52.518045) (xy 40.203257 -52.431148) (xy 40.132452 -52.339147) (xy 40.068162 -52.24248)
			(xy 40.010695 -52.141608) (xy 39.960324 -52.037011) (xy 39.917289 -51.929188) (xy 39.881795 -51.818654)
			(xy 39.854012 -51.705934) (xy 39.834072 -51.591566) (xy 39.82207 -51.476094) (xy 39.818063 -51.36007)
			(xy 24.743664 -51.36007) (xy 24.743664 -52.893484) (xy 29.519874 -52.893484) (xy 29.519874 -52.806584)
			(xy 29.527892 -52.720055) (xy 29.54386 -52.634635) (xy 29.567641 -52.551053) (xy 29.599033 -52.470021)
			(xy 29.637767 -52.392232) (xy 29.683514 -52.318348) (xy 29.735883 -52.249001) (xy 29.794427 -52.184781)
			(xy 29.858647 -52.126237) (xy 29.927994 -52.073868) (xy 30.001878 -52.028121) (xy 30.079667 -51.989387)
			(xy 30.160699 -51.957995) (xy 30.244281 -51.934214) (xy 30.329701 -51.918246) (xy 30.41623 -51.910228)
			(xy 30.50313 -51.910228) (xy 30.589659 -51.918246) (xy 30.675079 -51.934214) (xy 30.758661 -51.957995)
			(xy 30.839693 -51.989387) (xy 30.917482 -52.028121) (xy 30.991366 -52.073868) (xy 31.060713 -52.126237)
			(xy 31.124933 -52.184781) (xy 31.183477 -52.249001) (xy 31.235846 -52.318348) (xy 31.281593 -52.392232)
			(xy 31.320327 -52.470021) (xy 31.351719 -52.551053) (xy 31.3755 -52.634635) (xy 31.391468 -52.720055)
			(xy 31.399486 -52.806584) (xy 31.399988 -52.850034) (xy 31.399486 -52.893484) (xy 34.599874 -52.893484)
			(xy 34.599874 -52.806584) (xy 34.607892 -52.720055) (xy 34.62386 -52.634635) (xy 34.647641 -52.551053)
			(xy 34.679033 -52.470021) (xy 34.717767 -52.392232) (xy 34.763514 -52.318348) (xy 34.815883 -52.249001)
			(xy 34.874427 -52.184781) (xy 34.938647 -52.126237) (xy 35.007994 -52.073868) (xy 35.081878 -52.028121)
			(xy 35.159667 -51.989387) (xy 35.240699 -51.957995) (xy 35.324281 -51.934214) (xy 35.409701 -51.918246)
			(xy 35.49623 -51.910228) (xy 35.58313 -51.910228) (xy 35.669659 -51.918246) (xy 35.755079 -51.934214)
			(xy 35.838661 -51.957995) (xy 35.919693 -51.989387) (xy 35.997482 -52.028121) (xy 36.071366 -52.073868)
			(xy 36.140713 -52.126237) (xy 36.204933 -52.184781) (xy 36.263477 -52.249001) (xy 36.315846 -52.318348)
			(xy 36.361593 -52.392232) (xy 36.400327 -52.470021) (xy 36.431719 -52.551053) (xy 36.4555 -52.634635)
			(xy 36.471468 -52.720055) (xy 36.479486 -52.806584) (xy 36.479988 -52.850034) (xy 36.479486 -52.893484)
			(xy 36.471468 -52.980013) (xy 36.4555 -53.065433) (xy 36.431719 -53.149015) (xy 36.400327 -53.230047)
			(xy 36.361593 -53.307836) (xy 36.315846 -53.38172) (xy 36.263477 -53.451067) (xy 36.204933 -53.515287)
			(xy 36.140713 -53.573831) (xy 36.071366 -53.6262) (xy 35.997482 -53.671947) (xy 35.919693 -53.710681)
			(xy 35.838661 -53.742073) (xy 35.755079 -53.765854) (xy 35.669659 -53.781822) (xy 35.58313 -53.78984)
			(xy 35.49623 -53.78984) (xy 35.409701 -53.781822) (xy 35.324281 -53.765854) (xy 35.240699 -53.742073)
			(xy 35.159667 -53.710681) (xy 35.081878 -53.671947) (xy 35.007994 -53.6262) (xy 34.938647 -53.573831)
			(xy 34.874427 -53.515287) (xy 34.815883 -53.451067) (xy 34.763514 -53.38172) (xy 34.717767 -53.307836)
			(xy 34.679033 -53.230047) (xy 34.647641 -53.149015) (xy 34.62386 -53.065433) (xy 34.607892 -52.980013)
			(xy 34.599874 -52.893484) (xy 31.399486 -52.893484) (xy 31.391468 -52.980013) (xy 31.3755 -53.065433)
			(xy 31.351719 -53.149015) (xy 31.320327 -53.230047) (xy 31.281593 -53.307836) (xy 31.235846 -53.38172)
			(xy 31.183477 -53.451067) (xy 31.124933 -53.515287) (xy 31.060713 -53.573831) (xy 30.991366 -53.6262)
			(xy 30.917482 -53.671947) (xy 30.839693 -53.710681) (xy 30.758661 -53.742073) (xy 30.675079 -53.765854)
			(xy 30.589659 -53.781822) (xy 30.50313 -53.78984) (xy 30.41623 -53.78984) (xy 30.329701 -53.781822)
			(xy 30.244281 -53.765854) (xy 30.160699 -53.742073) (xy 30.079667 -53.710681) (xy 30.001878 -53.671947)
			(xy 29.927994 -53.6262) (xy 29.858647 -53.573831) (xy 29.794427 -53.515287) (xy 29.735883 -53.451067)
			(xy 29.683514 -53.38172) (xy 29.637767 -53.307836) (xy 29.599033 -53.230047) (xy 29.567641 -53.149015)
			(xy 29.54386 -53.065433) (xy 29.527892 -52.980013) (xy 29.519874 -52.893484) (xy 24.743664 -52.893484)
			(xy 24.743664 -57.492392) (xy 24.743688 -60.430765) (xy 57.204348 -60.430765) (xy 57.204348 -60.359443)
			(xy 57.212334 -60.288569) (xy 57.228204 -60.219034) (xy 57.251761 -60.151714) (xy 57.282706 -60.087455)
			(xy 57.320652 -60.027064) (xy 57.365121 -59.971302) (xy 57.415554 -59.920869) (xy 57.471316 -59.8764)
			(xy 57.531707 -59.838454) (xy 57.595966 -59.807509) (xy 57.663286 -59.783952) (xy 57.732821 -59.768082)
			(xy 57.803695 -59.760096) (xy 57.875017 -59.760096) (xy 57.945891 -59.768082) (xy 58.015426 -59.783952)
			(xy 58.082746 -59.807509) (xy 58.147005 -59.838454) (xy 58.207396 -59.8764) (xy 58.263158 -59.920869)
			(xy 58.313591 -59.971302) (xy 58.35806 -60.027064) (xy 58.396006 -60.087455) (xy 58.426951 -60.151714)
			(xy 58.450508 -60.219034) (xy 58.466378 -60.288569) (xy 58.474364 -60.359443) (xy 58.474864 -60.395104)
			(xy 58.474364 -60.430765) (xy 58.466378 -60.501639) (xy 58.450508 -60.571174) (xy 58.426951 -60.638494)
			(xy 58.396006 -60.702753) (xy 58.35806 -60.763144) (xy 58.313591 -60.818906) (xy 58.263158 -60.869339)
			(xy 58.207396 -60.913808) (xy 58.147005 -60.951754) (xy 58.082746 -60.982699) (xy 58.015426 -61.006256)
			(xy 57.945891 -61.022126) (xy 57.875017 -61.030112) (xy 57.803695 -61.030112) (xy 57.732821 -61.022126)
			(xy 57.663286 -61.006256) (xy 57.595966 -60.982699) (xy 57.531707 -60.951754) (xy 57.471316 -60.913808)
			(xy 57.415554 -60.869339) (xy 57.365121 -60.818906) (xy 57.320652 -60.763144) (xy 57.282706 -60.702753)
			(xy 57.251761 -60.638494) (xy 57.228204 -60.571174) (xy 57.212334 -60.501639) (xy 57.204348 -60.430765)
			(xy 24.743688 -60.430765) (xy 24.743695 -61.3156) (xy 69.8787 -61.3156) (xy 69.882771 -61.259978)
			(xy 69.894897 -61.205541) (xy 69.91482 -61.15345) (xy 69.942116 -61.104815) (xy 69.976202 -61.060672)
			(xy 70.016351 -61.021963) (xy 70.061709 -60.989512) (xy 70.111309 -60.964011) (xy 70.164093 -60.946004)
			(xy 70.218936 -60.935874) (xy 70.27467 -60.933837) (xy 70.330107 -60.939937) (xy 70.384064 -60.954043)
			(xy 70.435393 -60.975855) (xy 70.482999 -61.004909) (xy 70.525867 -61.040584) (xy 70.563084 -61.082121)
			(xy 70.593857 -61.128634) (xy 70.617529 -61.179131) (xy 70.633597 -61.232538) (xy 70.641717 -61.287714)
			(xy 70.642226 -61.3156) (xy 70.641717 -61.343486) (xy 70.637448 -61.372496) (xy 71.041004 -61.372496)
			(xy 71.045075 -61.316874) (xy 71.057201 -61.262437) (xy 71.077124 -61.210346) (xy 71.10442 -61.161711)
			(xy 71.138506 -61.117568) (xy 71.178655 -61.078859) (xy 71.224013 -61.046408) (xy 71.273613 -61.020907)
			(xy 71.326397 -61.0029) (xy 71.38124 -60.99277) (xy 71.436974 -60.990733) (xy 71.492411 -60.996833)
			(xy 71.546368 -61.010939) (xy 71.597697 -61.032751) (xy 71.645303 -61.061805) (xy 71.688171 -61.09748)
			(xy 71.725388 -61.139017) (xy 71.756161 -61.18553) (xy 71.779833 -61.236027) (xy 71.795901 -61.289434)
			(xy 71.804021 -61.34461) (xy 71.80453 -61.372496) (xy 71.804021 -61.400382) (xy 71.795901 -61.455558)
			(xy 71.779833 -61.508965) (xy 71.756161 -61.559462) (xy 71.725388 -61.605975) (xy 71.688171 -61.647512)
			(xy 71.645303 -61.683187) (xy 71.597697 -61.712241) (xy 71.546368 -61.734053) (xy 71.492411 -61.748159)
			(xy 71.436974 -61.754259) (xy 71.38124 -61.752222) (xy 71.326397 -61.742092) (xy 71.273613 -61.724085)
			(xy 71.224013 -61.698584) (xy 71.178655 -61.666133) (xy 71.138506 -61.627424) (xy 71.10442 -61.583281)
			(xy 71.077124 -61.534646) (xy 71.057201 -61.482555) (xy 71.045075 -61.428118) (xy 71.041004 -61.372496)
			(xy 70.637448 -61.372496) (xy 70.633597 -61.398662) (xy 70.617529 -61.452069) (xy 70.593857 -61.502566)
			(xy 70.563084 -61.549079) (xy 70.525867 -61.590616) (xy 70.482999 -61.626291) (xy 70.435393 -61.655345)
			(xy 70.384064 -61.677157) (xy 70.330107 -61.691263) (xy 70.27467 -61.697363) (xy 70.218936 -61.695326)
			(xy 70.164093 -61.685196) (xy 70.111309 -61.667189) (xy 70.061709 -61.641688) (xy 70.016351 -61.609237)
			(xy 69.976202 -61.570528) (xy 69.942116 -61.526385) (xy 69.91482 -61.47775) (xy 69.894897 -61.425659)
			(xy 69.882771 -61.371222) (xy 69.8787 -61.3156) (xy 24.743695 -61.3156) (xy 24.743708 -62.922827)
			(xy 47.525168 -62.922827) (xy 47.525168 -62.841717) (xy 47.533118 -62.760998) (xy 47.548941 -62.681447)
			(xy 47.572486 -62.603831) (xy 47.603525 -62.528895) (xy 47.64176 -62.457363) (xy 47.686822 -62.389923)
			(xy 47.738277 -62.327224) (xy 47.79563 -62.269871) (xy 47.858329 -62.218416) (xy 47.925769 -62.173354)
			(xy 47.997301 -62.135119) (xy 48.072237 -62.10408) (xy 48.149853 -62.080535) (xy 48.229404 -62.064712)
			(xy 48.310123 -62.056762) (xy 48.391233 -62.056762) (xy 48.471952 -62.064712) (xy 48.551503 -62.080535)
			(xy 48.629119 -62.10408) (xy 48.704055 -62.135119) (xy 48.775587 -62.173354) (xy 48.843027 -62.218416)
			(xy 48.899049 -62.264391) (xy 57.204348 -62.264391) (xy 57.204348 -62.193069) (xy 57.212334 -62.122195)
			(xy 57.228204 -62.05266) (xy 57.251761 -61.98534) (xy 57.282706 -61.921081) (xy 57.320652 -61.86069)
			(xy 57.365121 -61.804928) (xy 57.415554 -61.754495) (xy 57.471316 -61.710026) (xy 57.531707 -61.67208)
			(xy 57.595966 -61.641135) (xy 57.663286 -61.617578) (xy 57.732821 -61.601708) (xy 57.803695 -61.593722)
			(xy 57.875017 -61.593722) (xy 57.945891 -61.601708) (xy 58.015426 -61.617578) (xy 58.082746 -61.641135)
			(xy 58.147005 -61.67208) (xy 58.207396 -61.710026) (xy 58.263158 -61.754495) (xy 58.313591 -61.804928)
			(xy 58.35806 -61.86069) (xy 58.396006 -61.921081) (xy 58.426951 -61.98534) (xy 58.450508 -62.05266)
			(xy 58.466378 -62.122195) (xy 58.474364 -62.193069) (xy 58.474864 -62.22873) (xy 58.474364 -62.264391)
			(xy 59.44539 -62.264391) (xy 59.44539 -62.193069) (xy 59.453376 -62.122195) (xy 59.469246 -62.05266)
			(xy 59.492803 -61.98534) (xy 59.523748 -61.921081) (xy 59.561694 -61.86069) (xy 59.606163 -61.804928)
			(xy 59.656596 -61.754495) (xy 59.712358 -61.710026) (xy 59.772749 -61.67208) (xy 59.837008 -61.641135)
			(xy 59.904328 -61.617578) (xy 59.973863 -61.601708) (xy 60.044737 -61.593722) (xy 60.116059 -61.593722)
			(xy 60.186933 -61.601708) (xy 60.256468 -61.617578) (xy 60.323788 -61.641135) (xy 60.388047 -61.67208)
			(xy 60.448438 -61.710026) (xy 60.5042 -61.754495) (xy 60.554633 -61.804928) (xy 60.599102 -61.86069)
			(xy 60.637048 -61.921081) (xy 60.667993 -61.98534) (xy 60.69155 -62.05266) (xy 60.70742 -62.122195)
			(xy 60.715406 -62.193069) (xy 60.715906 -62.22873) (xy 60.715406 -62.264391) (xy 61.349374 -62.264391)
			(xy 61.349374 -62.193069) (xy 61.35736 -62.122195) (xy 61.37323 -62.05266) (xy 61.396787 -61.98534)
			(xy 61.427732 -61.921081) (xy 61.465678 -61.86069) (xy 61.510147 -61.804928) (xy 61.56058 -61.754495)
			(xy 61.616342 -61.710026) (xy 61.676733 -61.67208) (xy 61.740992 -61.641135) (xy 61.808312 -61.617578)
			(xy 61.877847 -61.601708) (xy 61.948721 -61.593722) (xy 62.020043 -61.593722) (xy 62.090917 -61.601708)
			(xy 62.160452 -61.617578) (xy 62.227772 -61.641135) (xy 62.292031 -61.67208) (xy 62.352422 -61.710026)
			(xy 62.408184 -61.754495) (xy 62.458617 -61.804928) (xy 62.503086 -61.86069) (xy 62.541032 -61.921081)
			(xy 62.571977 -61.98534) (xy 62.595534 -62.05266) (xy 62.611404 -62.122195) (xy 62.61939 -62.193069)
			(xy 62.61989 -62.22873) (xy 62.61939 -62.264391) (xy 62.613162 -62.319662) (xy 68.59092 -62.319662)
			(xy 68.594991 -62.26404) (xy 68.607117 -62.209603) (xy 68.62704 -62.157512) (xy 68.654336 -62.108877)
			(xy 68.688422 -62.064734) (xy 68.728571 -62.026025) (xy 68.773929 -61.993574) (xy 68.823529 -61.968073)
			(xy 68.876313 -61.950066) (xy 68.931156 -61.939936) (xy 68.98689 -61.937899) (xy 69.042327 -61.943999)
			(xy 69.096284 -61.958105) (xy 69.147613 -61.979917) (xy 69.195219 -62.008971) (xy 69.238087 -62.044646)
			(xy 69.275304 -62.086183) (xy 69.306077 -62.132696) (xy 69.329749 -62.183193) (xy 69.345817 -62.2366)
			(xy 69.353937 -62.291776) (xy 69.354446 -62.319662) (xy 69.353937 -62.347548) (xy 69.345817 -62.402724)
			(xy 69.329749 -62.456131) (xy 69.306077 -62.506628) (xy 69.275304 -62.553141) (xy 69.238087 -62.594678)
			(xy 69.195219 -62.630353) (xy 69.147613 -62.659407) (xy 69.096284 -62.681219) (xy 69.042327 -62.695325)
			(xy 68.98689 -62.701425) (xy 68.931156 -62.699388) (xy 68.876313 -62.689258) (xy 68.823529 -62.671251)
			(xy 68.773929 -62.64575) (xy 68.728571 -62.613299) (xy 68.688422 -62.57459) (xy 68.654336 -62.530447)
			(xy 68.62704 -62.481812) (xy 68.607117 -62.429721) (xy 68.594991 -62.375284) (xy 68.59092 -62.319662)
			(xy 62.613162 -62.319662) (xy 62.611404 -62.335265) (xy 62.595534 -62.4048) (xy 62.571977 -62.47212)
			(xy 62.541032 -62.536379) (xy 62.503086 -62.59677) (xy 62.458617 -62.652532) (xy 62.408184 -62.702965)
			(xy 62.352422 -62.747434) (xy 62.292031 -62.78538) (xy 62.227772 -62.816325) (xy 62.160452 -62.839882)
			(xy 62.090917 -62.855752) (xy 62.020043 -62.863738) (xy 61.948721 -62.863738) (xy 61.877847 -62.855752)
			(xy 61.808312 -62.839882) (xy 61.740992 -62.816325) (xy 61.676733 -62.78538) (xy 61.616342 -62.747434)
			(xy 61.56058 -62.702965) (xy 61.510147 -62.652532) (xy 61.465678 -62.59677) (xy 61.427732 -62.536379)
			(xy 61.396787 -62.47212) (xy 61.37323 -62.4048) (xy 61.35736 -62.335265) (xy 61.349374 -62.264391)
			(xy 60.715406 -62.264391) (xy 60.70742 -62.335265) (xy 60.69155 -62.4048) (xy 60.667993 -62.47212)
			(xy 60.637048 -62.536379) (xy 60.599102 -62.59677) (xy 60.554633 -62.652532) (xy 60.5042 -62.702965)
			(xy 60.448438 -62.747434) (xy 60.388047 -62.78538) (xy 60.323788 -62.816325) (xy 60.256468 -62.839882)
			(xy 60.186933 -62.855752) (xy 60.116059 -62.863738) (xy 60.044737 -62.863738) (xy 59.973863 -62.855752)
			(xy 59.904328 -62.839882) (xy 59.837008 -62.816325) (xy 59.772749 -62.78538) (xy 59.712358 -62.747434)
			(xy 59.656596 -62.702965) (xy 59.606163 -62.652532) (xy 59.561694 -62.59677) (xy 59.523748 -62.536379)
			(xy 59.492803 -62.47212) (xy 59.469246 -62.4048) (xy 59.453376 -62.335265) (xy 59.44539 -62.264391)
			(xy 58.474364 -62.264391) (xy 58.466378 -62.335265) (xy 58.450508 -62.4048) (xy 58.426951 -62.47212)
			(xy 58.396006 -62.536379) (xy 58.35806 -62.59677) (xy 58.313591 -62.652532) (xy 58.263158 -62.702965)
			(xy 58.207396 -62.747434) (xy 58.147005 -62.78538) (xy 58.082746 -62.816325) (xy 58.015426 -62.839882)
			(xy 57.945891 -62.855752) (xy 57.875017 -62.863738) (xy 57.803695 -62.863738) (xy 57.732821 -62.855752)
			(xy 57.663286 -62.839882) (xy 57.595966 -62.816325) (xy 57.531707 -62.78538) (xy 57.471316 -62.747434)
			(xy 57.415554 -62.702965) (xy 57.365121 -62.652532) (xy 57.320652 -62.59677) (xy 57.282706 -62.536379)
			(xy 57.251761 -62.47212) (xy 57.228204 -62.4048) (xy 57.212334 -62.335265) (xy 57.204348 -62.264391)
			(xy 48.899049 -62.264391) (xy 48.905726 -62.269871) (xy 48.963079 -62.327224) (xy 49.014534 -62.389923)
			(xy 49.059596 -62.457363) (xy 49.097831 -62.528895) (xy 49.12887 -62.603831) (xy 49.152415 -62.681447)
			(xy 49.168238 -62.760998) (xy 49.176188 -62.841717) (xy 49.176686 -62.882272) (xy 49.176188 -62.922827)
			(xy 49.168238 -63.003546) (xy 49.152415 -63.083097) (xy 49.12887 -63.160713) (xy 49.097831 -63.235649)
			(xy 49.059596 -63.307181) (xy 49.014534 -63.374621) (xy 48.963079 -63.43732) (xy 48.905726 -63.494673)
			(xy 48.843027 -63.546128) (xy 48.775587 -63.59119) (xy 48.704055 -63.629425) (xy 48.629119 -63.660464)
			(xy 48.551503 -63.684009) (xy 48.471952 -63.699832) (xy 48.391233 -63.707782) (xy 48.310123 -63.707782)
			(xy 48.229404 -63.699832) (xy 48.149853 -63.684009) (xy 48.072237 -63.660464) (xy 47.997301 -63.629425)
			(xy 47.925769 -63.59119) (xy 47.858329 -63.546128) (xy 47.79563 -63.494673) (xy 47.738277 -63.43732)
			(xy 47.686822 -63.374621) (xy 47.64176 -63.307181) (xy 47.603525 -63.235649) (xy 47.572486 -63.160713)
			(xy 47.548941 -63.083097) (xy 47.533118 -63.003546) (xy 47.525168 -62.922827) (xy 24.743708 -62.922827)
			(xy 24.743718 -64.165327) (xy 57.204348 -64.165327) (xy 57.204348 -64.094005) (xy 57.212334 -64.023131)
			(xy 57.228204 -63.953596) (xy 57.251761 -63.886276) (xy 57.282706 -63.822017) (xy 57.320652 -63.761626)
			(xy 57.365121 -63.705864) (xy 57.415554 -63.655431) (xy 57.471316 -63.610962) (xy 57.531707 -63.573016)
			(xy 57.595966 -63.542071) (xy 57.663286 -63.518514) (xy 57.732821 -63.502644) (xy 57.803695 -63.494658)
			(xy 57.875017 -63.494658) (xy 57.945891 -63.502644) (xy 58.015426 -63.518514) (xy 58.082746 -63.542071)
			(xy 58.147005 -63.573016) (xy 58.207396 -63.610962) (xy 58.263158 -63.655431) (xy 58.313591 -63.705864)
			(xy 58.35806 -63.761626) (xy 58.396006 -63.822017) (xy 58.426951 -63.886276) (xy 58.450508 -63.953596)
			(xy 58.466378 -64.023131) (xy 58.474364 -64.094005) (xy 58.474864 -64.129666) (xy 58.474364 -64.165327)
			(xy 59.44539 -64.165327) (xy 59.44539 -64.094005) (xy 59.453376 -64.023131) (xy 59.469246 -63.953596)
			(xy 59.492803 -63.886276) (xy 59.523748 -63.822017) (xy 59.561694 -63.761626) (xy 59.606163 -63.705864)
			(xy 59.656596 -63.655431) (xy 59.712358 -63.610962) (xy 59.772749 -63.573016) (xy 59.837008 -63.542071)
			(xy 59.904328 -63.518514) (xy 59.973863 -63.502644) (xy 60.044737 -63.494658) (xy 60.116059 -63.494658)
			(xy 60.186933 -63.502644) (xy 60.256468 -63.518514) (xy 60.323788 -63.542071) (xy 60.388047 -63.573016)
			(xy 60.448438 -63.610962) (xy 60.5042 -63.655431) (xy 60.554633 -63.705864) (xy 60.599102 -63.761626)
			(xy 60.637048 -63.822017) (xy 60.667993 -63.886276) (xy 60.69155 -63.953596) (xy 60.70742 -64.023131)
			(xy 60.715406 -64.094005) (xy 60.715906 -64.129666) (xy 60.715406 -64.165327) (xy 61.349374 -64.165327)
			(xy 61.349374 -64.094005) (xy 61.35736 -64.023131) (xy 61.37323 -63.953596) (xy 61.396787 -63.886276)
			(xy 61.427732 -63.822017) (xy 61.465678 -63.761626) (xy 61.510147 -63.705864) (xy 61.56058 -63.655431)
			(xy 61.616342 -63.610962) (xy 61.676733 -63.573016) (xy 61.740992 -63.542071) (xy 61.808312 -63.518514)
			(xy 61.877847 -63.502644) (xy 61.948721 -63.494658) (xy 62.020043 -63.494658) (xy 62.090917 -63.502644)
			(xy 62.160452 -63.518514) (xy 62.227772 -63.542071) (xy 62.292031 -63.573016) (xy 62.352422 -63.610962)
			(xy 62.408184 -63.655431) (xy 62.458617 -63.705864) (xy 62.503086 -63.761626) (xy 62.541032 -63.822017)
			(xy 62.571977 -63.886276) (xy 62.595534 -63.953596) (xy 62.611404 -64.023131) (xy 62.61939 -64.094005)
			(xy 62.61989 -64.129666) (xy 62.61939 -64.165327) (xy 62.611404 -64.236201) (xy 62.595534 -64.305736)
			(xy 62.571977 -64.373056) (xy 62.541032 -64.437315) (xy 62.503086 -64.497706) (xy 62.458617 -64.553468)
			(xy 62.408184 -64.603901) (xy 62.352422 -64.64837) (xy 62.292031 -64.686316) (xy 62.227772 -64.717261)
			(xy 62.160452 -64.740818) (xy 62.090917 -64.756688) (xy 62.020043 -64.764674) (xy 61.948721 -64.764674)
			(xy 61.877847 -64.756688) (xy 61.808312 -64.740818) (xy 61.740992 -64.717261) (xy 61.676733 -64.686316)
			(xy 61.616342 -64.64837) (xy 61.56058 -64.603901) (xy 61.510147 -64.553468) (xy 61.465678 -64.497706)
			(xy 61.427732 -64.437315) (xy 61.396787 -64.373056) (xy 61.37323 -64.305736) (xy 61.35736 -64.236201)
			(xy 61.349374 -64.165327) (xy 60.715406 -64.165327) (xy 60.70742 -64.236201) (xy 60.69155 -64.305736)
			(xy 60.667993 -64.373056) (xy 60.637048 -64.437315) (xy 60.599102 -64.497706) (xy 60.554633 -64.553468)
			(xy 60.5042 -64.603901) (xy 60.448438 -64.64837) (xy 60.388047 -64.686316) (xy 60.323788 -64.717261)
			(xy 60.256468 -64.740818) (xy 60.186933 -64.756688) (xy 60.116059 -64.764674) (xy 60.044737 -64.764674)
			(xy 59.973863 -64.756688) (xy 59.904328 -64.740818) (xy 59.837008 -64.717261) (xy 59.772749 -64.686316)
			(xy 59.712358 -64.64837) (xy 59.656596 -64.603901) (xy 59.606163 -64.553468) (xy 59.561694 -64.497706)
			(xy 59.523748 -64.437315) (xy 59.492803 -64.373056) (xy 59.469246 -64.305736) (xy 59.453376 -64.236201)
			(xy 59.44539 -64.165327) (xy 58.474364 -64.165327) (xy 58.466378 -64.236201) (xy 58.450508 -64.305736)
			(xy 58.426951 -64.373056) (xy 58.396006 -64.437315) (xy 58.35806 -64.497706) (xy 58.313591 -64.553468)
			(xy 58.263158 -64.603901) (xy 58.207396 -64.64837) (xy 58.147005 -64.686316) (xy 58.082746 -64.717261)
			(xy 58.015426 -64.740818) (xy 57.945891 -64.756688) (xy 57.875017 -64.764674) (xy 57.803695 -64.764674)
			(xy 57.732821 -64.756688) (xy 57.663286 -64.740818) (xy 57.595966 -64.717261) (xy 57.531707 -64.686316)
			(xy 57.471316 -64.64837) (xy 57.415554 -64.603901) (xy 57.365121 -64.553468) (xy 57.320652 -64.497706)
			(xy 57.282706 -64.437315) (xy 57.251761 -64.373056) (xy 57.228204 -64.305736) (xy 57.212334 -64.236201)
			(xy 57.204348 -64.165327) (xy 24.743718 -64.165327) (xy 24.743737 -66.480537) (xy 43.823374 -66.480537)
			(xy 43.823374 -66.409215) (xy 43.83136 -66.338341) (xy 43.84723 -66.268806) (xy 43.870787 -66.201486)
			(xy 43.901732 -66.137227) (xy 43.939678 -66.076836) (xy 43.984147 -66.021074) (xy 44.03458 -65.970641)
			(xy 44.090342 -65.926172) (xy 44.150733 -65.888226) (xy 44.214992 -65.857281) (xy 44.282312 -65.833724)
			(xy 44.351847 -65.817854) (xy 44.422721 -65.809868) (xy 44.494043 -65.809868) (xy 44.564917 -65.817854)
			(xy 44.634452 -65.833724) (xy 44.653693 -65.840457) (xy 57.204348 -65.840457) (xy 57.204348 -65.769135)
			(xy 57.212334 -65.698261) (xy 57.228204 -65.628726) (xy 57.251761 -65.561406) (xy 57.282706 -65.497147)
			(xy 57.320652 -65.436756) (xy 57.365121 -65.380994) (xy 57.415554 -65.330561) (xy 57.471316 -65.286092)
			(xy 57.531707 -65.248146) (xy 57.595966 -65.217201) (xy 57.663286 -65.193644) (xy 57.732821 -65.177774)
			(xy 57.803695 -65.169788) (xy 57.875017 -65.169788) (xy 57.945891 -65.177774) (xy 58.015426 -65.193644)
			(xy 58.082746 -65.217201) (xy 58.147005 -65.248146) (xy 58.207396 -65.286092) (xy 58.263158 -65.330561)
			(xy 58.313591 -65.380994) (xy 58.35806 -65.436756) (xy 58.396006 -65.497147) (xy 58.426951 -65.561406)
			(xy 58.450508 -65.628726) (xy 58.466378 -65.698261) (xy 58.474364 -65.769135) (xy 58.474864 -65.804796)
			(xy 58.474364 -65.840457) (xy 59.44539 -65.840457) (xy 59.44539 -65.769135) (xy 59.453376 -65.698261)
			(xy 59.469246 -65.628726) (xy 59.492803 -65.561406) (xy 59.523748 -65.497147) (xy 59.561694 -65.436756)
			(xy 59.606163 -65.380994) (xy 59.656596 -65.330561) (xy 59.712358 -65.286092) (xy 59.772749 -65.248146)
			(xy 59.837008 -65.217201) (xy 59.904328 -65.193644) (xy 59.973863 -65.177774) (xy 60.044737 -65.169788)
			(xy 60.116059 -65.169788) (xy 60.186933 -65.177774) (xy 60.256468 -65.193644) (xy 60.323788 -65.217201)
			(xy 60.388047 -65.248146) (xy 60.448438 -65.286092) (xy 60.5042 -65.330561) (xy 60.554633 -65.380994)
			(xy 60.599102 -65.436756) (xy 60.637048 -65.497147) (xy 60.667993 -65.561406) (xy 60.69155 -65.628726)
			(xy 60.70742 -65.698261) (xy 60.715406 -65.769135) (xy 60.715906 -65.804796) (xy 60.715406 -65.840457)
			(xy 61.349374 -65.840457) (xy 61.349374 -65.769135) (xy 61.35736 -65.698261) (xy 61.37323 -65.628726)
			(xy 61.396787 -65.561406) (xy 61.427732 -65.497147) (xy 61.465678 -65.436756) (xy 61.510147 -65.380994)
			(xy 61.56058 -65.330561) (xy 61.616342 -65.286092) (xy 61.676733 -65.248146) (xy 61.740992 -65.217201)
			(xy 61.808312 -65.193644) (xy 61.877847 -65.177774) (xy 61.948721 -65.169788) (xy 62.020043 -65.169788)
			(xy 62.090917 -65.177774) (xy 62.160452 -65.193644) (xy 62.227772 -65.217201) (xy 62.292031 -65.248146)
			(xy 62.352422 -65.286092) (xy 62.408184 -65.330561) (xy 62.458617 -65.380994) (xy 62.503086 -65.436756)
			(xy 62.541032 -65.497147) (xy 62.571977 -65.561406) (xy 62.595534 -65.628726) (xy 62.611404 -65.698261)
			(xy 62.61939 -65.769135) (xy 62.61989 -65.804796) (xy 62.61939 -65.840457) (xy 62.611404 -65.911331)
			(xy 62.595534 -65.980866) (xy 62.571977 -66.048186) (xy 62.541032 -66.112445) (xy 62.503086 -66.172836)
			(xy 62.458617 -66.228598) (xy 62.408184 -66.279031) (xy 62.352422 -66.3235) (xy 62.292031 -66.361446)
			(xy 62.227772 -66.392391) (xy 62.160452 -66.415948) (xy 62.090917 -66.431818) (xy 62.020043 -66.439804)
			(xy 61.948721 -66.439804) (xy 61.877847 -66.431818) (xy 61.808312 -66.415948) (xy 61.740992 -66.392391)
			(xy 61.676733 -66.361446) (xy 61.616342 -66.3235) (xy 61.56058 -66.279031) (xy 61.510147 -66.228598)
			(xy 61.465678 -66.172836) (xy 61.427732 -66.112445) (xy 61.396787 -66.048186) (xy 61.37323 -65.980866)
			(xy 61.35736 -65.911331) (xy 61.349374 -65.840457) (xy 60.715406 -65.840457) (xy 60.70742 -65.911331)
			(xy 60.69155 -65.980866) (xy 60.667993 -66.048186) (xy 60.637048 -66.112445) (xy 60.599102 -66.172836)
			(xy 60.554633 -66.228598) (xy 60.5042 -66.279031) (xy 60.448438 -66.3235) (xy 60.388047 -66.361446)
			(xy 60.323788 -66.392391) (xy 60.256468 -66.415948) (xy 60.186933 -66.431818) (xy 60.116059 -66.439804)
			(xy 60.044737 -66.439804) (xy 59.973863 -66.431818) (xy 59.904328 -66.415948) (xy 59.837008 -66.392391)
			(xy 59.772749 -66.361446) (xy 59.712358 -66.3235) (xy 59.656596 -66.279031) (xy 59.606163 -66.228598)
			(xy 59.561694 -66.172836) (xy 59.523748 -66.112445) (xy 59.492803 -66.048186) (xy 59.469246 -65.980866)
			(xy 59.453376 -65.911331) (xy 59.44539 -65.840457) (xy 58.474364 -65.840457) (xy 58.466378 -65.911331)
			(xy 58.450508 -65.980866) (xy 58.426951 -66.048186) (xy 58.396006 -66.112445) (xy 58.35806 -66.172836)
			(xy 58.313591 -66.228598) (xy 58.263158 -66.279031) (xy 58.207396 -66.3235) (xy 58.147005 -66.361446)
			(xy 58.082746 -66.392391) (xy 58.015426 -66.415948) (xy 57.945891 -66.431818) (xy 57.875017 -66.439804)
			(xy 57.803695 -66.439804) (xy 57.732821 -66.431818) (xy 57.663286 -66.415948) (xy 57.595966 -66.392391)
			(xy 57.531707 -66.361446) (xy 57.471316 -66.3235) (xy 57.415554 -66.279031) (xy 57.365121 -66.228598)
			(xy 57.320652 -66.172836) (xy 57.282706 -66.112445) (xy 57.251761 -66.048186) (xy 57.228204 -65.980866)
			(xy 57.212334 -65.911331) (xy 57.204348 -65.840457) (xy 44.653693 -65.840457) (xy 44.701772 -65.857281)
			(xy 44.766031 -65.888226) (xy 44.826422 -65.926172) (xy 44.882184 -65.970641) (xy 44.932617 -66.021074)
			(xy 44.977086 -66.076836) (xy 45.015032 -66.137227) (xy 45.045977 -66.201486) (xy 45.069534 -66.268806)
			(xy 45.085404 -66.338341) (xy 45.09339 -66.409215) (xy 45.09389 -66.444876) (xy 45.09339 -66.480537)
			(xy 45.085404 -66.551411) (xy 45.069534 -66.620946) (xy 45.045977 -66.688266) (xy 45.015032 -66.752525)
			(xy 44.977086 -66.812916) (xy 44.932617 -66.868678) (xy 44.882184 -66.919111) (xy 44.826422 -66.96358)
			(xy 44.766031 -67.001526) (xy 44.701772 -67.032471) (xy 44.634452 -67.056028) (xy 44.564917 -67.071898)
			(xy 44.494043 -67.079884) (xy 44.422721 -67.079884) (xy 44.351847 -67.071898) (xy 44.282312 -67.056028)
			(xy 44.214992 -67.032471) (xy 44.150733 -67.001526) (xy 44.090342 -66.96358) (xy 44.03458 -66.919111)
			(xy 43.984147 -66.868678) (xy 43.939678 -66.812916) (xy 43.901732 -66.752525) (xy 43.870787 -66.688266)
			(xy 43.84723 -66.620946) (xy 43.83136 -66.551411) (xy 43.823374 -66.480537) (xy 24.743737 -66.480537)
			(xy 24.743752 -68.314163) (xy 43.823374 -68.314163) (xy 43.823374 -68.242841) (xy 43.83136 -68.171967)
			(xy 43.84723 -68.102432) (xy 43.870787 -68.035112) (xy 43.901732 -67.970853) (xy 43.939678 -67.910462)
			(xy 43.984147 -67.8547) (xy 44.03458 -67.804267) (xy 44.090342 -67.759798) (xy 44.150733 -67.721852)
			(xy 44.214992 -67.690907) (xy 44.282312 -67.66735) (xy 44.351847 -67.65148) (xy 44.422721 -67.643494)
			(xy 44.494043 -67.643494) (xy 44.564917 -67.65148) (xy 44.634452 -67.66735) (xy 44.701772 -67.690907)
			(xy 44.766031 -67.721852) (xy 44.826422 -67.759798) (xy 44.882184 -67.804267) (xy 44.929546 -67.851629)
			(xy 57.160914 -67.851629) (xy 57.160914 -67.780307) (xy 57.1689 -67.709433) (xy 57.18477 -67.639898)
			(xy 57.208327 -67.572578) (xy 57.239272 -67.508319) (xy 57.277218 -67.447928) (xy 57.321687 -67.392166)
			(xy 57.37212 -67.341733) (xy 57.427882 -67.297264) (xy 57.488273 -67.259318) (xy 57.552532 -67.228373)
			(xy 57.619852 -67.204816) (xy 57.689387 -67.188946) (xy 57.760261 -67.18096) (xy 57.831583 -67.18096)
			(xy 57.902457 -67.188946) (xy 57.971992 -67.204816) (xy 58.039312 -67.228373) (xy 58.103571 -67.259318)
			(xy 58.163962 -67.297264) (xy 58.219724 -67.341733) (xy 58.270157 -67.392166) (xy 58.314626 -67.447928)
			(xy 58.352572 -67.508319) (xy 58.383517 -67.572578) (xy 58.407074 -67.639898) (xy 58.422944 -67.709433)
			(xy 58.43093 -67.780307) (xy 58.43143 -67.815968) (xy 58.43093 -67.851629) (xy 59.401956 -67.851629)
			(xy 59.401956 -67.780307) (xy 59.409942 -67.709433) (xy 59.425812 -67.639898) (xy 59.449369 -67.572578)
			(xy 59.480314 -67.508319) (xy 59.51826 -67.447928) (xy 59.562729 -67.392166) (xy 59.613162 -67.341733)
			(xy 59.668924 -67.297264) (xy 59.729315 -67.259318) (xy 59.793574 -67.228373) (xy 59.860894 -67.204816)
			(xy 59.930429 -67.188946) (xy 60.001303 -67.18096) (xy 60.072625 -67.18096) (xy 60.143499 -67.188946)
			(xy 60.213034 -67.204816) (xy 60.280354 -67.228373) (xy 60.344613 -67.259318) (xy 60.405004 -67.297264)
			(xy 60.460766 -67.341733) (xy 60.511199 -67.392166) (xy 60.555668 -67.447928) (xy 60.593614 -67.508319)
			(xy 60.624559 -67.572578) (xy 60.648116 -67.639898) (xy 60.663986 -67.709433) (xy 60.671972 -67.780307)
			(xy 60.672472 -67.815968) (xy 60.671972 -67.851629) (xy 61.30594 -67.851629) (xy 61.30594 -67.780307)
			(xy 61.313926 -67.709433) (xy 61.329796 -67.639898) (xy 61.353353 -67.572578) (xy 61.384298 -67.508319)
			(xy 61.422244 -67.447928) (xy 61.466713 -67.392166) (xy 61.517146 -67.341733) (xy 61.572908 -67.297264)
			(xy 61.633299 -67.259318) (xy 61.697558 -67.228373) (xy 61.764878 -67.204816) (xy 61.834413 -67.188946)
			(xy 61.905287 -67.18096) (xy 61.976609 -67.18096) (xy 62.047483 -67.188946) (xy 62.117018 -67.204816)
			(xy 62.184338 -67.228373) (xy 62.248597 -67.259318) (xy 62.308988 -67.297264) (xy 62.36475 -67.341733)
			(xy 62.415183 -67.392166) (xy 62.459652 -67.447928) (xy 62.497598 -67.508319) (xy 62.528543 -67.572578)
			(xy 62.5521 -67.639898) (xy 62.56797 -67.709433) (xy 62.575956 -67.780307) (xy 62.576456 -67.815968)
			(xy 62.575956 -67.851629) (xy 62.56797 -67.922503) (xy 62.5521 -67.992038) (xy 62.528543 -68.059358)
			(xy 62.497598 -68.123617) (xy 62.459652 -68.184008) (xy 62.415183 -68.23977) (xy 62.36475 -68.290203)
			(xy 62.308988 -68.334672) (xy 62.248597 -68.372618) (xy 62.184338 -68.403563) (xy 62.117018 -68.42712)
			(xy 62.047483 -68.44299) (xy 61.976609 -68.450976) (xy 61.905287 -68.450976) (xy 61.834413 -68.44299)
			(xy 61.764878 -68.42712) (xy 61.697558 -68.403563) (xy 61.633299 -68.372618) (xy 61.572908 -68.334672)
			(xy 61.517146 -68.290203) (xy 61.466713 -68.23977) (xy 61.422244 -68.184008) (xy 61.384298 -68.123617)
			(xy 61.353353 -68.059358) (xy 61.329796 -67.992038) (xy 61.313926 -67.922503) (xy 61.30594 -67.851629)
			(xy 60.671972 -67.851629) (xy 60.663986 -67.922503) (xy 60.648116 -67.992038) (xy 60.624559 -68.059358)
			(xy 60.593614 -68.123617) (xy 60.555668 -68.184008) (xy 60.511199 -68.23977) (xy 60.460766 -68.290203)
			(xy 60.405004 -68.334672) (xy 60.344613 -68.372618) (xy 60.280354 -68.403563) (xy 60.213034 -68.42712)
			(xy 60.143499 -68.44299) (xy 60.072625 -68.450976) (xy 60.001303 -68.450976) (xy 59.930429 -68.44299)
			(xy 59.860894 -68.42712) (xy 59.793574 -68.403563) (xy 59.729315 -68.372618) (xy 59.668924 -68.334672)
			(xy 59.613162 -68.290203) (xy 59.562729 -68.23977) (xy 59.51826 -68.184008) (xy 59.480314 -68.123617)
			(xy 59.449369 -68.059358) (xy 59.425812 -67.992038) (xy 59.409942 -67.922503) (xy 59.401956 -67.851629)
			(xy 58.43093 -67.851629) (xy 58.422944 -67.922503) (xy 58.407074 -67.992038) (xy 58.383517 -68.059358)
			(xy 58.352572 -68.123617) (xy 58.314626 -68.184008) (xy 58.270157 -68.23977) (xy 58.219724 -68.290203)
			(xy 58.163962 -68.334672) (xy 58.103571 -68.372618) (xy 58.039312 -68.403563) (xy 57.971992 -68.42712)
			(xy 57.902457 -68.44299) (xy 57.831583 -68.450976) (xy 57.760261 -68.450976) (xy 57.689387 -68.44299)
			(xy 57.619852 -68.42712) (xy 57.552532 -68.403563) (xy 57.488273 -68.372618) (xy 57.427882 -68.334672)
			(xy 57.37212 -68.290203) (xy 57.321687 -68.23977) (xy 57.277218 -68.184008) (xy 57.239272 -68.123617)
			(xy 57.208327 -68.059358) (xy 57.18477 -67.992038) (xy 57.1689 -67.922503) (xy 57.160914 -67.851629)
			(xy 44.929546 -67.851629) (xy 44.932617 -67.8547) (xy 44.977086 -67.910462) (xy 45.015032 -67.970853)
			(xy 45.045977 -68.035112) (xy 45.069534 -68.102432) (xy 45.085404 -68.171967) (xy 45.09339 -68.242841)
			(xy 45.09389 -68.278502) (xy 45.09339 -68.314163) (xy 45.085404 -68.385037) (xy 45.069534 -68.454572)
			(xy 45.045977 -68.521892) (xy 45.015032 -68.586151) (xy 44.977086 -68.646542) (xy 44.932617 -68.702304)
			(xy 44.882184 -68.752737) (xy 44.826422 -68.797206) (xy 44.766031 -68.835152) (xy 44.701772 -68.866097)
			(xy 44.634452 -68.889654) (xy 44.564917 -68.905524) (xy 44.494043 -68.91351) (xy 44.422721 -68.91351)
			(xy 44.351847 -68.905524) (xy 44.282312 -68.889654) (xy 44.214992 -68.866097) (xy 44.150733 -68.835152)
			(xy 44.090342 -68.797206) (xy 44.03458 -68.752737) (xy 43.984147 -68.702304) (xy 43.939678 -68.646542)
			(xy 43.901732 -68.586151) (xy 43.870787 -68.521892) (xy 43.84723 -68.454572) (xy 43.83136 -68.385037)
			(xy 43.823374 -68.314163) (xy 24.743752 -68.314163) (xy 24.743767 -70.215099) (xy 43.823374 -70.215099)
			(xy 43.823374 -70.143777) (xy 43.83136 -70.072903) (xy 43.84723 -70.003368) (xy 43.870787 -69.936048)
			(xy 43.901732 -69.871789) (xy 43.939678 -69.811398) (xy 43.984147 -69.755636) (xy 44.03458 -69.705203)
			(xy 44.090342 -69.660734) (xy 44.150733 -69.622788) (xy 44.214992 -69.591843) (xy 44.282312 -69.568286)
			(xy 44.351847 -69.552416) (xy 44.422721 -69.54443) (xy 44.494043 -69.54443) (xy 44.564917 -69.552416)
			(xy 44.634452 -69.568286) (xy 44.701772 -69.591843) (xy 44.766031 -69.622788) (xy 44.826422 -69.660734)
			(xy 44.882184 -69.705203) (xy 44.919132 -69.742151) (xy 57.160914 -69.742151) (xy 57.160914 -69.670829)
			(xy 57.1689 -69.599955) (xy 57.18477 -69.53042) (xy 57.208327 -69.4631) (xy 57.239272 -69.398841)
			(xy 57.277218 -69.33845) (xy 57.321687 -69.282688) (xy 57.37212 -69.232255) (xy 57.427882 -69.187786)
			(xy 57.488273 -69.14984) (xy 57.552532 -69.118895) (xy 57.619852 -69.095338) (xy 57.689387 -69.079468)
			(xy 57.760261 -69.071482) (xy 57.831583 -69.071482) (xy 57.902457 -69.079468) (xy 57.971992 -69.095338)
			(xy 58.039312 -69.118895) (xy 58.103571 -69.14984) (xy 58.163962 -69.187786) (xy 58.219724 -69.232255)
			(xy 58.270157 -69.282688) (xy 58.314626 -69.33845) (xy 58.352572 -69.398841) (xy 58.383517 -69.4631)
			(xy 58.407074 -69.53042) (xy 58.422944 -69.599955) (xy 58.43093 -69.670829) (xy 58.43143 -69.70649)
			(xy 58.43093 -69.742151) (xy 59.401956 -69.742151) (xy 59.401956 -69.670829) (xy 59.409942 -69.599955)
			(xy 59.425812 -69.53042) (xy 59.449369 -69.4631) (xy 59.480314 -69.398841) (xy 59.51826 -69.33845)
			(xy 59.562729 -69.282688) (xy 59.613162 -69.232255) (xy 59.668924 -69.187786) (xy 59.729315 -69.14984)
			(xy 59.793574 -69.118895) (xy 59.860894 -69.095338) (xy 59.930429 -69.079468) (xy 60.001303 -69.071482)
			(xy 60.072625 -69.071482) (xy 60.143499 -69.079468) (xy 60.213034 -69.095338) (xy 60.280354 -69.118895)
			(xy 60.344613 -69.14984) (xy 60.405004 -69.187786) (xy 60.460766 -69.232255) (xy 60.511199 -69.282688)
			(xy 60.555668 -69.33845) (xy 60.593614 -69.398841) (xy 60.624559 -69.4631) (xy 60.648116 -69.53042)
			(xy 60.663986 -69.599955) (xy 60.671972 -69.670829) (xy 60.672472 -69.70649) (xy 60.671972 -69.742151)
			(xy 61.30594 -69.742151) (xy 61.30594 -69.670829) (xy 61.313926 -69.599955) (xy 61.329796 -69.53042)
			(xy 61.353353 -69.4631) (xy 61.384298 -69.398841) (xy 61.422244 -69.33845) (xy 61.466713 -69.282688)
			(xy 61.517146 -69.232255) (xy 61.572908 -69.187786) (xy 61.633299 -69.14984) (xy 61.697558 -69.118895)
			(xy 61.764878 -69.095338) (xy 61.834413 -69.079468) (xy 61.905287 -69.071482) (xy 61.976609 -69.071482)
			(xy 62.047483 -69.079468) (xy 62.117018 -69.095338) (xy 62.184338 -69.118895) (xy 62.248597 -69.14984)
			(xy 62.308988 -69.187786) (xy 62.36475 -69.232255) (xy 62.415183 -69.282688) (xy 62.459652 -69.33845)
			(xy 62.497598 -69.398841) (xy 62.528543 -69.4631) (xy 62.5521 -69.53042) (xy 62.56797 -69.599955)
			(xy 62.575956 -69.670829) (xy 62.576456 -69.70649) (xy 62.575956 -69.742151) (xy 62.56797 -69.813025)
			(xy 62.5521 -69.88256) (xy 62.528543 -69.94988) (xy 62.497598 -70.014139) (xy 62.459652 -70.07453)
			(xy 62.415183 -70.130292) (xy 62.36475 -70.180725) (xy 62.308988 -70.225194) (xy 62.248597 -70.26314)
			(xy 62.184338 -70.294085) (xy 62.117018 -70.317642) (xy 62.047483 -70.333512) (xy 61.976609 -70.341498)
			(xy 61.905287 -70.341498) (xy 61.834413 -70.333512) (xy 61.764878 -70.317642) (xy 61.697558 -70.294085)
			(xy 61.633299 -70.26314) (xy 61.572908 -70.225194) (xy 61.517146 -70.180725) (xy 61.466713 -70.130292)
			(xy 61.422244 -70.07453) (xy 61.384298 -70.014139) (xy 61.353353 -69.94988) (xy 61.329796 -69.88256)
			(xy 61.313926 -69.813025) (xy 61.30594 -69.742151) (xy 60.671972 -69.742151) (xy 60.663986 -69.813025)
			(xy 60.648116 -69.88256) (xy 60.624559 -69.94988) (xy 60.593614 -70.014139) (xy 60.555668 -70.07453)
			(xy 60.511199 -70.130292) (xy 60.460766 -70.180725) (xy 60.405004 -70.225194) (xy 60.344613 -70.26314)
			(xy 60.280354 -70.294085) (xy 60.213034 -70.317642) (xy 60.143499 -70.333512) (xy 60.072625 -70.341498)
			(xy 60.001303 -70.341498) (xy 59.930429 -70.333512) (xy 59.860894 -70.317642) (xy 59.793574 -70.294085)
			(xy 59.729315 -70.26314) (xy 59.668924 -70.225194) (xy 59.613162 -70.180725) (xy 59.562729 -70.130292)
			(xy 59.51826 -70.07453) (xy 59.480314 -70.014139) (xy 59.449369 -69.94988) (xy 59.425812 -69.88256)
			(xy 59.409942 -69.813025) (xy 59.401956 -69.742151) (xy 58.43093 -69.742151) (xy 58.422944 -69.813025)
			(xy 58.407074 -69.88256) (xy 58.383517 -69.94988) (xy 58.352572 -70.014139) (xy 58.314626 -70.07453)
			(xy 58.270157 -70.130292) (xy 58.219724 -70.180725) (xy 58.163962 -70.225194) (xy 58.103571 -70.26314)
			(xy 58.039312 -70.294085) (xy 57.971992 -70.317642) (xy 57.902457 -70.333512) (xy 57.831583 -70.341498)
			(xy 57.760261 -70.341498) (xy 57.689387 -70.333512) (xy 57.619852 -70.317642) (xy 57.552532 -70.294085)
			(xy 57.488273 -70.26314) (xy 57.427882 -70.225194) (xy 57.37212 -70.180725) (xy 57.321687 -70.130292)
			(xy 57.277218 -70.07453) (xy 57.239272 -70.014139) (xy 57.208327 -69.94988) (xy 57.18477 -69.88256)
			(xy 57.1689 -69.813025) (xy 57.160914 -69.742151) (xy 44.919132 -69.742151) (xy 44.932617 -69.755636)
			(xy 44.977086 -69.811398) (xy 45.015032 -69.871789) (xy 45.045977 -69.936048) (xy 45.069534 -70.003368)
			(xy 45.085404 -70.072903) (xy 45.09339 -70.143777) (xy 45.09389 -70.179438) (xy 45.09339 -70.215099)
			(xy 45.085404 -70.285973) (xy 45.069534 -70.355508) (xy 45.045977 -70.422828) (xy 45.015032 -70.487087)
			(xy 44.977086 -70.547478) (xy 44.932617 -70.60324) (xy 44.882184 -70.653673) (xy 44.826422 -70.698142)
			(xy 44.766031 -70.736088) (xy 44.701772 -70.767033) (xy 44.634452 -70.79059) (xy 44.564917 -70.80646)
			(xy 44.494043 -70.814446) (xy 44.422721 -70.814446) (xy 44.351847 -70.80646) (xy 44.282312 -70.79059)
			(xy 44.214992 -70.767033) (xy 44.150733 -70.736088) (xy 44.090342 -70.698142) (xy 44.03458 -70.653673)
			(xy 43.984147 -70.60324) (xy 43.939678 -70.547478) (xy 43.901732 -70.487087) (xy 43.870787 -70.422828)
			(xy 43.84723 -70.355508) (xy 43.83136 -70.285973) (xy 43.823374 -70.215099) (xy 24.743767 -70.215099)
			(xy 24.743781 -71.890229) (xy 43.823374 -71.890229) (xy 43.823374 -71.818907) (xy 43.83136 -71.748033)
			(xy 43.84723 -71.678498) (xy 43.870787 -71.611178) (xy 43.901732 -71.546919) (xy 43.939678 -71.486528)
			(xy 43.984147 -71.430766) (xy 44.03458 -71.380333) (xy 44.090342 -71.335864) (xy 44.150733 -71.297918)
			(xy 44.214992 -71.266973) (xy 44.282312 -71.243416) (xy 44.351847 -71.227546) (xy 44.422721 -71.21956)
			(xy 44.494043 -71.21956) (xy 44.564917 -71.227546) (xy 44.634452 -71.243416) (xy 44.701772 -71.266973)
			(xy 44.766031 -71.297918) (xy 44.826422 -71.335864) (xy 44.882184 -71.380333) (xy 44.932617 -71.430766)
			(xy 44.977086 -71.486528) (xy 45.015032 -71.546919) (xy 45.045977 -71.611178) (xy 45.069534 -71.678498)
			(xy 45.085404 -71.748033) (xy 45.089377 -71.783295) (xy 57.160914 -71.783295) (xy 57.160914 -71.711973)
			(xy 57.1689 -71.641099) (xy 57.18477 -71.571564) (xy 57.208327 -71.504244) (xy 57.239272 -71.439985)
			(xy 57.277218 -71.379594) (xy 57.321687 -71.323832) (xy 57.37212 -71.273399) (xy 57.427882 -71.22893)
			(xy 57.488273 -71.190984) (xy 57.552532 -71.160039) (xy 57.619852 -71.136482) (xy 57.689387 -71.120612)
			(xy 57.760261 -71.112626) (xy 57.831583 -71.112626) (xy 57.902457 -71.120612) (xy 57.971992 -71.136482)
			(xy 58.039312 -71.160039) (xy 58.103571 -71.190984) (xy 58.163962 -71.22893) (xy 58.219724 -71.273399)
			(xy 58.270157 -71.323832) (xy 58.314626 -71.379594) (xy 58.352572 -71.439985) (xy 58.383517 -71.504244)
			(xy 58.407074 -71.571564) (xy 58.422944 -71.641099) (xy 58.43093 -71.711973) (xy 58.43143 -71.747634)
			(xy 58.43093 -71.783295) (xy 59.401956 -71.783295) (xy 59.401956 -71.711973) (xy 59.409942 -71.641099)
			(xy 59.425812 -71.571564) (xy 59.449369 -71.504244) (xy 59.480314 -71.439985) (xy 59.51826 -71.379594)
			(xy 59.562729 -71.323832) (xy 59.613162 -71.273399) (xy 59.668924 -71.22893) (xy 59.729315 -71.190984)
			(xy 59.793574 -71.160039) (xy 59.860894 -71.136482) (xy 59.930429 -71.120612) (xy 60.001303 -71.112626)
			(xy 60.072625 -71.112626) (xy 60.143499 -71.120612) (xy 60.213034 -71.136482) (xy 60.280354 -71.160039)
			(xy 60.344613 -71.190984) (xy 60.405004 -71.22893) (xy 60.460766 -71.273399) (xy 60.511199 -71.323832)
			(xy 60.555668 -71.379594) (xy 60.593614 -71.439985) (xy 60.624559 -71.504244) (xy 60.648116 -71.571564)
			(xy 60.663986 -71.641099) (xy 60.671972 -71.711973) (xy 60.672472 -71.747634) (xy 60.671972 -71.783295)
			(xy 61.30594 -71.783295) (xy 61.30594 -71.711973) (xy 61.313926 -71.641099) (xy 61.329796 -71.571564)
			(xy 61.353353 -71.504244) (xy 61.384298 -71.439985) (xy 61.422244 -71.379594) (xy 61.466713 -71.323832)
			(xy 61.517146 -71.273399) (xy 61.572908 -71.22893) (xy 61.633299 -71.190984) (xy 61.697558 -71.160039)
			(xy 61.764878 -71.136482) (xy 61.834413 -71.120612) (xy 61.905287 -71.112626) (xy 61.976609 -71.112626)
			(xy 62.047483 -71.120612) (xy 62.117018 -71.136482) (xy 62.184338 -71.160039) (xy 62.248597 -71.190984)
			(xy 62.308988 -71.22893) (xy 62.36475 -71.273399) (xy 62.415183 -71.323832) (xy 62.459652 -71.379594)
			(xy 62.497598 -71.439985) (xy 62.528543 -71.504244) (xy 62.5521 -71.571564) (xy 62.56797 -71.641099)
			(xy 62.575956 -71.711973) (xy 62.576456 -71.747634) (xy 62.575956 -71.783295) (xy 62.56797 -71.854169)
			(xy 62.5521 -71.923704) (xy 62.528543 -71.991024) (xy 62.497598 -72.055283) (xy 62.459652 -72.115674)
			(xy 62.415183 -72.171436) (xy 62.36475 -72.221869) (xy 62.308988 -72.266338) (xy 62.248597 -72.304284)
			(xy 62.184338 -72.335229) (xy 62.117018 -72.358786) (xy 62.047483 -72.374656) (xy 61.976609 -72.382642)
			(xy 61.905287 -72.382642) (xy 61.834413 -72.374656) (xy 61.764878 -72.358786) (xy 61.697558 -72.335229)
			(xy 61.633299 -72.304284) (xy 61.572908 -72.266338) (xy 61.517146 -72.221869) (xy 61.466713 -72.171436)
			(xy 61.422244 -72.115674) (xy 61.384298 -72.055283) (xy 61.353353 -71.991024) (xy 61.329796 -71.923704)
			(xy 61.313926 -71.854169) (xy 61.30594 -71.783295) (xy 60.671972 -71.783295) (xy 60.663986 -71.854169)
			(xy 60.648116 -71.923704) (xy 60.624559 -71.991024) (xy 60.593614 -72.055283) (xy 60.555668 -72.115674)
			(xy 60.511199 -72.171436) (xy 60.460766 -72.221869) (xy 60.405004 -72.266338) (xy 60.344613 -72.304284)
			(xy 60.280354 -72.335229) (xy 60.213034 -72.358786) (xy 60.143499 -72.374656) (xy 60.072625 -72.382642)
			(xy 60.001303 -72.382642) (xy 59.930429 -72.374656) (xy 59.860894 -72.358786) (xy 59.793574 -72.335229)
			(xy 59.729315 -72.304284) (xy 59.668924 -72.266338) (xy 59.613162 -72.221869) (xy 59.562729 -72.171436)
			(xy 59.51826 -72.115674) (xy 59.480314 -72.055283) (xy 59.449369 -71.991024) (xy 59.425812 -71.923704)
			(xy 59.409942 -71.854169) (xy 59.401956 -71.783295) (xy 58.43093 -71.783295) (xy 58.422944 -71.854169)
			(xy 58.407074 -71.923704) (xy 58.383517 -71.991024) (xy 58.352572 -72.055283) (xy 58.314626 -72.115674)
			(xy 58.270157 -72.171436) (xy 58.219724 -72.221869) (xy 58.163962 -72.266338) (xy 58.103571 -72.304284)
			(xy 58.039312 -72.335229) (xy 57.971992 -72.358786) (xy 57.902457 -72.374656) (xy 57.831583 -72.382642)
			(xy 57.760261 -72.382642) (xy 57.689387 -72.374656) (xy 57.619852 -72.358786) (xy 57.552532 -72.335229)
			(xy 57.488273 -72.304284) (xy 57.427882 -72.266338) (xy 57.37212 -72.221869) (xy 57.321687 -72.171436)
			(xy 57.277218 -72.115674) (xy 57.239272 -72.055283) (xy 57.208327 -71.991024) (xy 57.18477 -71.923704)
			(xy 57.1689 -71.854169) (xy 57.160914 -71.783295) (xy 45.089377 -71.783295) (xy 45.09339 -71.818907)
			(xy 45.09389 -71.854568) (xy 45.09339 -71.890229) (xy 45.085404 -71.961103) (xy 45.069534 -72.030638)
			(xy 45.045977 -72.097958) (xy 45.015032 -72.162217) (xy 44.977086 -72.222608) (xy 44.932617 -72.27837)
			(xy 44.882184 -72.328803) (xy 44.826422 -72.373272) (xy 44.766031 -72.411218) (xy 44.701772 -72.442163)
			(xy 44.634452 -72.46572) (xy 44.564917 -72.48159) (xy 44.494043 -72.489576) (xy 44.422721 -72.489576)
			(xy 44.351847 -72.48159) (xy 44.282312 -72.46572) (xy 44.214992 -72.442163) (xy 44.150733 -72.411218)
			(xy 44.090342 -72.373272) (xy 44.03458 -72.328803) (xy 43.984147 -72.27837) (xy 43.939678 -72.222608)
			(xy 43.901732 -72.162217) (xy 43.870787 -72.097958) (xy 43.84723 -72.030638) (xy 43.83136 -71.961103)
			(xy 43.823374 -71.890229) (xy 24.743781 -71.890229) (xy 24.743797 -73.901401) (xy 43.77994 -73.901401)
			(xy 43.77994 -73.830079) (xy 43.787926 -73.759205) (xy 43.803796 -73.68967) (xy 43.827353 -73.62235)
			(xy 43.858298 -73.558091) (xy 43.896244 -73.4977) (xy 43.940713 -73.441938) (xy 43.991146 -73.391505)
			(xy 44.046908 -73.347036) (xy 44.107299 -73.30909) (xy 44.171558 -73.278145) (xy 44.238878 -73.254588)
			(xy 44.308413 -73.238718) (xy 44.379287 -73.230732) (xy 44.450609 -73.230732) (xy 44.521483 -73.238718)
			(xy 44.591018 -73.254588) (xy 44.658338 -73.278145) (xy 44.722597 -73.30909) (xy 44.782988 -73.347036)
			(xy 44.83875 -73.391505) (xy 44.889183 -73.441938) (xy 44.933652 -73.4977) (xy 44.971598 -73.558091)
			(xy 45.002543 -73.62235) (xy 45.0261 -73.68967) (xy 45.026888 -73.693121) (xy 57.160914 -73.693121)
			(xy 57.160914 -73.621799) (xy 57.1689 -73.550925) (xy 57.18477 -73.48139) (xy 57.208327 -73.41407)
			(xy 57.239272 -73.349811) (xy 57.277218 -73.28942) (xy 57.321687 -73.233658) (xy 57.37212 -73.183225)
			(xy 57.427882 -73.138756) (xy 57.488273 -73.10081) (xy 57.552532 -73.069865) (xy 57.619852 -73.046308)
			(xy 57.689387 -73.030438) (xy 57.760261 -73.022452) (xy 57.831583 -73.022452) (xy 57.902457 -73.030438)
			(xy 57.971992 -73.046308) (xy 58.039312 -73.069865) (xy 58.103571 -73.10081) (xy 58.163962 -73.138756)
			(xy 58.219724 -73.183225) (xy 58.270157 -73.233658) (xy 58.314626 -73.28942) (xy 58.352572 -73.349811)
			(xy 58.383517 -73.41407) (xy 58.407074 -73.48139) (xy 58.422944 -73.550925) (xy 58.43093 -73.621799)
			(xy 58.43143 -73.65746) (xy 58.43093 -73.693121) (xy 59.401956 -73.693121) (xy 59.401956 -73.621799)
			(xy 59.409942 -73.550925) (xy 59.425812 -73.48139) (xy 59.449369 -73.41407) (xy 59.480314 -73.349811)
			(xy 59.51826 -73.28942) (xy 59.562729 -73.233658) (xy 59.613162 -73.183225) (xy 59.668924 -73.138756)
			(xy 59.729315 -73.10081) (xy 59.793574 -73.069865) (xy 59.860894 -73.046308) (xy 59.930429 -73.030438)
			(xy 60.001303 -73.022452) (xy 60.072625 -73.022452) (xy 60.143499 -73.030438) (xy 60.213034 -73.046308)
			(xy 60.280354 -73.069865) (xy 60.344613 -73.10081) (xy 60.405004 -73.138756) (xy 60.460766 -73.183225)
			(xy 60.511199 -73.233658) (xy 60.555668 -73.28942) (xy 60.593614 -73.349811) (xy 60.624559 -73.41407)
			(xy 60.648116 -73.48139) (xy 60.663986 -73.550925) (xy 60.671972 -73.621799) (xy 60.672472 -73.65746)
			(xy 60.671972 -73.693121) (xy 61.30594 -73.693121) (xy 61.30594 -73.621799) (xy 61.313926 -73.550925)
			(xy 61.329796 -73.48139) (xy 61.353353 -73.41407) (xy 61.384298 -73.349811) (xy 61.422244 -73.28942)
			(xy 61.466713 -73.233658) (xy 61.517146 -73.183225) (xy 61.572908 -73.138756) (xy 61.633299 -73.10081)
			(xy 61.697558 -73.069865) (xy 61.764878 -73.046308) (xy 61.834413 -73.030438) (xy 61.905287 -73.022452)
			(xy 61.976609 -73.022452) (xy 62.047483 -73.030438) (xy 62.117018 -73.046308) (xy 62.184338 -73.069865)
			(xy 62.248597 -73.10081) (xy 62.308988 -73.138756) (xy 62.36475 -73.183225) (xy 62.415183 -73.233658)
			(xy 62.459652 -73.28942) (xy 62.497598 -73.349811) (xy 62.528543 -73.41407) (xy 62.5521 -73.48139)
			(xy 62.56797 -73.550925) (xy 62.575956 -73.621799) (xy 62.576456 -73.65746) (xy 62.575956 -73.693121)
			(xy 62.56797 -73.763995) (xy 62.5521 -73.83353) (xy 62.528543 -73.90085) (xy 62.497598 -73.965109)
			(xy 62.459652 -74.0255) (xy 62.415183 -74.081262) (xy 62.36475 -74.131695) (xy 62.308988 -74.176164)
			(xy 62.248597 -74.21411) (xy 62.184338 -74.245055) (xy 62.117018 -74.268612) (xy 62.047483 -74.284482)
			(xy 61.976609 -74.292468) (xy 61.905287 -74.292468) (xy 61.834413 -74.284482) (xy 61.764878 -74.268612)
			(xy 61.697558 -74.245055) (xy 61.633299 -74.21411) (xy 61.572908 -74.176164) (xy 61.517146 -74.131695)
			(xy 61.466713 -74.081262) (xy 61.422244 -74.0255) (xy 61.384298 -73.965109) (xy 61.353353 -73.90085)
			(xy 61.329796 -73.83353) (xy 61.313926 -73.763995) (xy 61.30594 -73.693121) (xy 60.671972 -73.693121)
			(xy 60.663986 -73.763995) (xy 60.648116 -73.83353) (xy 60.624559 -73.90085) (xy 60.593614 -73.965109)
			(xy 60.555668 -74.0255) (xy 60.511199 -74.081262) (xy 60.460766 -74.131695) (xy 60.405004 -74.176164)
			(xy 60.344613 -74.21411) (xy 60.280354 -74.245055) (xy 60.213034 -74.268612) (xy 60.143499 -74.284482)
			(xy 60.072625 -74.292468) (xy 60.001303 -74.292468) (xy 59.930429 -74.284482) (xy 59.860894 -74.268612)
			(xy 59.793574 -74.245055) (xy 59.729315 -74.21411) (xy 59.668924 -74.176164) (xy 59.613162 -74.131695)
			(xy 59.562729 -74.081262) (xy 59.51826 -74.0255) (xy 59.480314 -73.965109) (xy 59.449369 -73.90085)
			(xy 59.425812 -73.83353) (xy 59.409942 -73.763995) (xy 59.401956 -73.693121) (xy 58.43093 -73.693121)
			(xy 58.422944 -73.763995) (xy 58.407074 -73.83353) (xy 58.383517 -73.90085) (xy 58.352572 -73.965109)
			(xy 58.314626 -74.0255) (xy 58.270157 -74.081262) (xy 58.219724 -74.131695) (xy 58.163962 -74.176164)
			(xy 58.103571 -74.21411) (xy 58.039312 -74.245055) (xy 57.971992 -74.268612) (xy 57.902457 -74.284482)
			(xy 57.831583 -74.292468) (xy 57.760261 -74.292468) (xy 57.689387 -74.284482) (xy 57.619852 -74.268612)
			(xy 57.552532 -74.245055) (xy 57.488273 -74.21411) (xy 57.427882 -74.176164) (xy 57.37212 -74.131695)
			(xy 57.321687 -74.081262) (xy 57.277218 -74.0255) (xy 57.239272 -73.965109) (xy 57.208327 -73.90085)
			(xy 57.18477 -73.83353) (xy 57.1689 -73.763995) (xy 57.160914 -73.693121) (xy 45.026888 -73.693121)
			(xy 45.04197 -73.759205) (xy 45.049956 -73.830079) (xy 45.050456 -73.86574) (xy 45.049956 -73.901401)
			(xy 45.04197 -73.972275) (xy 45.0261 -74.04181) (xy 45.002543 -74.10913) (xy 44.971598 -74.173389)
			(xy 44.933652 -74.23378) (xy 44.889183 -74.289542) (xy 44.83875 -74.339975) (xy 44.782988 -74.384444)
			(xy 44.722597 -74.42239) (xy 44.658338 -74.453335) (xy 44.591018 -74.476892) (xy 44.521483 -74.492762)
			(xy 44.450609 -74.500748) (xy 44.379287 -74.500748) (xy 44.308413 -74.492762) (xy 44.238878 -74.476892)
			(xy 44.171558 -74.453335) (xy 44.107299 -74.42239) (xy 44.046908 -74.384444) (xy 43.991146 -74.339975)
			(xy 43.940713 -74.289542) (xy 43.896244 -74.23378) (xy 43.858298 -74.173389) (xy 43.827353 -74.10913)
			(xy 43.803796 -74.04181) (xy 43.787926 -73.972275) (xy 43.77994 -73.901401) (xy 24.743797 -73.901401)
			(xy 24.743812 -75.791923) (xy 43.77994 -75.791923) (xy 43.77994 -75.720601) (xy 43.787926 -75.649727)
			(xy 43.803796 -75.580192) (xy 43.827353 -75.512872) (xy 43.858298 -75.448613) (xy 43.896244 -75.388222)
			(xy 43.940713 -75.33246) (xy 43.991146 -75.282027) (xy 44.046908 -75.237558) (xy 44.107299 -75.199612)
			(xy 44.171558 -75.168667) (xy 44.238878 -75.14511) (xy 44.308413 -75.12924) (xy 44.379287 -75.121254)
			(xy 44.450609 -75.121254) (xy 44.521483 -75.12924) (xy 44.591018 -75.14511) (xy 44.658338 -75.168667)
			(xy 44.722597 -75.199612) (xy 44.782988 -75.237558) (xy 44.83875 -75.282027) (xy 44.889183 -75.33246)
			(xy 44.933652 -75.388222) (xy 44.971598 -75.448613) (xy 45.002543 -75.512872) (xy 45.0261 -75.580192)
			(xy 45.04197 -75.649727) (xy 45.049956 -75.720601) (xy 45.050456 -75.756262) (xy 45.049956 -75.791923)
			(xy 45.04197 -75.862797) (xy 45.0261 -75.932332) (xy 45.002543 -75.999652) (xy 44.971598 -76.063911)
			(xy 44.933652 -76.124302) (xy 44.889183 -76.180064) (xy 44.83875 -76.230497) (xy 44.782988 -76.274966)
			(xy 44.722597 -76.312912) (xy 44.658338 -76.343857) (xy 44.591018 -76.367414) (xy 44.521483 -76.383284)
			(xy 44.450609 -76.39127) (xy 44.379287 -76.39127) (xy 44.308413 -76.383284) (xy 44.238878 -76.367414)
			(xy 44.171558 -76.343857) (xy 44.107299 -76.312912) (xy 44.046908 -76.274966) (xy 43.991146 -76.230497)
			(xy 43.940713 -76.180064) (xy 43.896244 -76.124302) (xy 43.858298 -76.063911) (xy 43.827353 -75.999652)
			(xy 43.803796 -75.932332) (xy 43.787926 -75.862797) (xy 43.77994 -75.791923) (xy 24.743812 -75.791923)
			(xy 24.743829 -77.833067) (xy 43.77994 -77.833067) (xy 43.77994 -77.761745) (xy 43.787926 -77.690871)
			(xy 43.803796 -77.621336) (xy 43.827353 -77.554016) (xy 43.858298 -77.489757) (xy 43.896244 -77.429366)
			(xy 43.940713 -77.373604) (xy 43.991146 -77.323171) (xy 44.046908 -77.278702) (xy 44.107299 -77.240756)
			(xy 44.171558 -77.209811) (xy 44.238878 -77.186254) (xy 44.308413 -77.170384) (xy 44.379287 -77.162398)
			(xy 44.450609 -77.162398) (xy 44.521483 -77.170384) (xy 44.591018 -77.186254) (xy 44.658338 -77.209811)
			(xy 44.722597 -77.240756) (xy 44.782988 -77.278702) (xy 44.83875 -77.323171) (xy 44.889183 -77.373604)
			(xy 44.933652 -77.429366) (xy 44.971598 -77.489757) (xy 45.002543 -77.554016) (xy 45.0261 -77.621336)
			(xy 45.04197 -77.690871) (xy 45.049956 -77.761745) (xy 45.050456 -77.797406) (xy 45.049956 -77.833067)
			(xy 45.04197 -77.903941) (xy 45.0261 -77.973476) (xy 45.002543 -78.040796) (xy 44.971598 -78.105055)
			(xy 44.933652 -78.165446) (xy 44.889183 -78.221208) (xy 44.83875 -78.271641) (xy 44.782988 -78.31611)
			(xy 44.722597 -78.354056) (xy 44.658338 -78.385001) (xy 44.591018 -78.408558) (xy 44.521483 -78.424428)
			(xy 44.450609 -78.432414) (xy 44.379287 -78.432414) (xy 44.308413 -78.424428) (xy 44.238878 -78.408558)
			(xy 44.171558 -78.385001) (xy 44.107299 -78.354056) (xy 44.046908 -78.31611) (xy 43.991146 -78.271641)
			(xy 43.940713 -78.221208) (xy 43.896244 -78.165446) (xy 43.858298 -78.105055) (xy 43.827353 -78.040796)
			(xy 43.803796 -77.973476) (xy 43.787926 -77.903941) (xy 43.77994 -77.833067) (xy 24.743829 -77.833067)
			(xy 24.743845 -79.742893) (xy 43.77994 -79.742893) (xy 43.77994 -79.671571) (xy 43.787926 -79.600697)
			(xy 43.803796 -79.531162) (xy 43.827353 -79.463842) (xy 43.858298 -79.399583) (xy 43.896244 -79.339192)
			(xy 43.940713 -79.28343) (xy 43.991146 -79.232997) (xy 44.046908 -79.188528) (xy 44.107299 -79.150582)
			(xy 44.171558 -79.119637) (xy 44.238878 -79.09608) (xy 44.308413 -79.08021) (xy 44.379287 -79.072224)
			(xy 44.450609 -79.072224) (xy 44.521483 -79.08021) (xy 44.591018 -79.09608) (xy 44.658338 -79.119637)
			(xy 44.722597 -79.150582) (xy 44.782988 -79.188528) (xy 44.83875 -79.232997) (xy 44.889183 -79.28343)
			(xy 44.933652 -79.339192) (xy 44.971598 -79.399583) (xy 45.002543 -79.463842) (xy 45.0261 -79.531162)
			(xy 45.04197 -79.600697) (xy 45.049956 -79.671571) (xy 45.050456 -79.707232) (xy 45.049956 -79.742893)
			(xy 45.04197 -79.813767) (xy 45.0261 -79.883302) (xy 45.002543 -79.950622) (xy 44.971598 -80.014881)
			(xy 44.933652 -80.075272) (xy 44.889183 -80.131034) (xy 44.83875 -80.181467) (xy 44.782988 -80.225936)
			(xy 44.722597 -80.263882) (xy 44.658338 -80.294827) (xy 44.591018 -80.318384) (xy 44.521483 -80.334254)
			(xy 44.450609 -80.34224) (xy 44.379287 -80.34224) (xy 44.308413 -80.334254) (xy 44.238878 -80.318384)
			(xy 44.171558 -80.294827) (xy 44.107299 -80.263882) (xy 44.046908 -80.225936) (xy 43.991146 -80.181467)
			(xy 43.940713 -80.131034) (xy 43.896244 -80.075272) (xy 43.858298 -80.014881) (xy 43.827353 -79.950622)
			(xy 43.803796 -79.883302) (xy 43.787926 -79.813767) (xy 43.77994 -79.742893) (xy 24.743845 -79.742893)
			(xy 24.743882 -84.314199) (xy 47.642008 -84.314199) (xy 47.642008 -84.233089) (xy 47.649958 -84.15237)
			(xy 47.665781 -84.072819) (xy 47.689326 -83.995203) (xy 47.720365 -83.920267) (xy 47.7586 -83.848735)
			(xy 47.803662 -83.781295) (xy 47.855117 -83.718596) (xy 47.91247 -83.661243) (xy 47.975169 -83.609788)
			(xy 48.042609 -83.564726) (xy 48.114141 -83.526491) (xy 48.189077 -83.495452) (xy 48.266693 -83.471907)
			(xy 48.346244 -83.456084) (xy 48.426963 -83.448134) (xy 48.508073 -83.448134) (xy 48.588792 -83.456084)
			(xy 48.668343 -83.471907) (xy 48.745959 -83.495452) (xy 48.820895 -83.526491) (xy 48.892427 -83.564726)
			(xy 48.959867 -83.609788) (xy 49.022566 -83.661243) (xy 49.079919 -83.718596) (xy 49.131374 -83.781295)
			(xy 49.176436 -83.848735) (xy 49.214671 -83.920267) (xy 49.24571 -83.995203) (xy 49.269255 -84.072819)
			(xy 49.285078 -84.15237) (xy 49.293028 -84.233089) (xy 49.293526 -84.273644) (xy 49.293028 -84.314199)
			(xy 49.285078 -84.394918) (xy 49.269255 -84.474469) (xy 49.24571 -84.552085) (xy 49.214671 -84.627021)
			(xy 49.176436 -84.698553) (xy 49.131374 -84.765993) (xy 49.079919 -84.828692) (xy 49.022566 -84.886045)
			(xy 48.959867 -84.9375) (xy 48.892427 -84.982562) (xy 48.820895 -85.020797) (xy 48.745959 -85.051836)
			(xy 48.668343 -85.075381) (xy 48.588792 -85.091204) (xy 48.508073 -85.099154) (xy 48.426963 -85.099154)
			(xy 48.346244 -85.091204) (xy 48.266693 -85.075381) (xy 48.189077 -85.051836) (xy 48.114141 -85.020797)
			(xy 48.042609 -84.982562) (xy 47.975169 -84.9375) (xy 47.91247 -84.886045) (xy 47.855117 -84.828692)
			(xy 47.803662 -84.765993) (xy 47.7586 -84.698553) (xy 47.720365 -84.627021) (xy 47.689326 -84.552085)
			(xy 47.665781 -84.474469) (xy 47.649958 -84.394918) (xy 47.642008 -84.314199) (xy 24.743882 -84.314199)
			(xy 24.743918 -88.645746) (xy 24.744397 -88.66845) (xy 24.752421 -88.713143) (xy 24.768261 -88.755699)
			(xy 24.791411 -88.794762) (xy 24.821134 -88.82909) (xy 24.856485 -88.857589) (xy 24.896338 -88.879352)
			(xy 24.939424 -88.893686) (xy 24.984371 -88.900136) (xy 25.029749 -88.898495) (xy 25.074113 -88.888816)
			(xy 25.116051 -88.871407) (xy 25.154228 -88.846822) (xy 25.171146 -88.831674) (xy 28.091384 -85.911436)
			(xy 51.403758 -85.911436) (xy 74.139298 -63.175896) (xy 74.148818 -63.164771) (xy 74.163 -63.139163)
			(xy 74.170968 -63.110996) (xy 74.172064 -63.096394) (xy 74.172064 -59.80176) (xy 80.320134 -53.653436)
			(xy 81.84261 -53.653436) (xy 82.860388 -52.635658) (xy 82.860388 -49.613566) (xy 83.825842 -48.648112)
			(xy 83.835361 -48.636986) (xy 83.849541 -48.611378) (xy 83.85751 -48.583211) (xy 83.858608 -48.56861)
			(xy 83.858608 -13.271246) (xy 83.842606 -13.242544) (xy 83.829695 -13.218203) (xy 83.810239 -13.166654)
			(xy 83.798402 -13.112842) (xy 83.79443 -13.057888) (xy 83.798405 -13.002933) (xy 83.810246 -12.949122)
			(xy 83.829705 -12.897575) (xy 83.842606 -12.873228) (xy 83.858608 -12.844526) (xy 83.858608 -5.65277)
			(xy 85.974174 -3.537204) (xy 90.97137 -3.537204) (xy 91.71178 -4.27736) (xy 91.723481 -4.288434)
			(xy 91.751207 -4.30482) (xy 91.782157 -4.313724) (xy 91.814352 -4.314577) (xy 91.830144 -4.311396)
			(xy 91.866936 -4.303426) (xy 91.941675 -4.294367) (xy 92.016952 -4.293247) (xy 92.091927 -4.300077)
			(xy 92.165762 -4.314782) (xy 92.237633 -4.337197) (xy 92.306737 -4.367071) (xy 92.372302 -4.404072)
			(xy 92.433597 -4.447785) (xy 92.489936 -4.497724) (xy 92.540689 -4.553329) (xy 92.585292 -4.613979)
			(xy 92.623244 -4.678999) (xy 92.654122 -4.74766) (xy 92.677582 -4.819197) (xy 92.693361 -4.89281)
			(xy 92.701283 -4.967677) (xy 92.70126 -5.042963) (xy 92.693291 -5.117825) (xy 92.677467 -5.191428)
			(xy 92.653963 -5.262951) (xy 92.623042 -5.331593) (xy 92.58505 -5.396589) (xy 92.54041 -5.457212)
			(xy 92.489622 -5.512786) (xy 92.433252 -5.562689) (xy 92.371931 -5.606365) (xy 92.306342 -5.643325)
			(xy 92.23722 -5.673156) (xy 92.165335 -5.695527) (xy 92.09149 -5.710186) (xy 92.016511 -5.71697)
			(xy 91.941235 -5.715803) (xy 91.866503 -5.706698) (xy 91.793148 -5.689757) (xy 91.721991 -5.665169)
			(xy 91.653826 -5.633209) (xy 91.589415 -5.594234) (xy 91.529477 -5.548678) (xy 91.474682 -5.497052)
			(xy 91.42564 -5.43993) (xy 91.382901 -5.377953) (xy 91.346942 -5.31181) (xy 91.318164 -5.242243)
			(xy 91.296888 -5.170026) (xy 91.289632 -5.133086) (xy 91.28125 -5.08762) (xy 91.210892 -5.028946)
			(xy 91.164664 -5.028946) (xy 91.148015 -5.029445) (xy 91.115853 -5.038073) (xy 91.08702 -5.054732)
			(xy 91.063481 -5.078285) (xy 91.046842 -5.107129) (xy 91.038234 -5.139296) (xy 91.037664 -5.155946)
			(xy 91.037664 -5.564124) (xy 91.038138 -5.580218) (xy 91.0462 -5.611381) (xy 91.061805 -5.639534)
			(xy 91.083959 -5.662885) (xy 91.097354 -5.67182) (xy 91.128796 -5.692039) (xy 91.187681 -5.738097)
			(xy 91.241412 -5.790076) (xy 91.289397 -5.847402) (xy 91.331106 -5.909443) (xy 91.36608 -5.975516)
			(xy 91.393932 -6.044892) (xy 91.414357 -6.116806) (xy 91.427128 -6.190466) (xy 91.432106 -6.265058)
			(xy 91.429234 -6.339761) (xy 91.418546 -6.413751) (xy 91.400157 -6.486213) (xy 91.387676 -6.52145)
			(xy 91.374475 -6.555911) (xy 91.341921 -6.622144) (xy 91.302686 -6.684651) (xy 91.257191 -6.742761)
			(xy 91.205925 -6.795849) (xy 91.149439 -6.843344) (xy 91.08834 -6.884738) (xy 91.023284 -6.919584)
			(xy 90.95497 -6.947508) (xy 90.884133 -6.96821) (xy 90.847926 -6.975348) (xy 90.80246 -6.98373) (xy 90.743786 -7.054088)
			(xy 90.743786 -7.100316) (xy 90.744331 -7.116964) (xy 90.752951 -7.149124) (xy 90.7696 -7.177958)
			(xy 90.793144 -7.201501) (xy 90.821978 -7.218149) (xy 90.854138 -7.226769) (xy 90.870786 -7.227316)
			(xy 91.278964 -7.227316) (xy 91.295062 -7.226849) (xy 91.326233 -7.218797) (xy 91.354396 -7.203198)
			(xy 91.377757 -7.181044) (xy 91.38666 -7.167626) (xy 91.406969 -7.136082) (xy 91.453239 -7.07702)
			(xy 91.505465 -7.023154) (xy 91.56307 -6.975083) (xy 91.625412 -6.933338) (xy 91.6918 -6.898385)
			(xy 91.761497 -6.87061) (xy 91.83373 -6.850323) (xy 91.907696 -6.837748) (xy 91.982575 -6.833025)
			(xy 92.057535 -6.836207) (xy 92.131744 -6.847257) (xy 92.204379 -6.866054) (xy 92.274633 -6.892389)
			(xy 92.341726 -6.925969) (xy 92.404914 -6.966422) (xy 92.463495 -7.013299) (xy 92.516818 -7.066079)
			(xy 92.564293 -7.124176) (xy 92.605391 -7.186946) (xy 92.639658 -7.253691) (xy 92.666711 -7.323672)
			(xy 92.686252 -7.39611) (xy 92.698063 -7.470202) (xy 92.702012 -7.545125) (xy 92.698057 -7.620049)
			(xy 92.686241 -7.69414) (xy 92.666695 -7.766577) (xy 92.639637 -7.836555) (xy 92.605366 -7.903298)
			(xy 92.564263 -7.966065) (xy 92.516784 -8.024159) (xy 92.463457 -8.076935) (xy 92.404872 -8.123807)
			(xy 92.341682 -8.164256) (xy 92.274586 -8.197831) (xy 92.20433 -8.224161) (xy 92.131694 -8.242953)
			(xy 92.057484 -8.253998) (xy 91.982524 -8.257174) (xy 91.907646 -8.252446) (xy 91.83368 -8.239866)
			(xy 91.761449 -8.219573) (xy 91.691754 -8.191794) (xy 91.625368 -8.156836) (xy 91.563029 -8.115087)
			(xy 91.505428 -8.067011) (xy 91.453205 -8.013142) (xy 91.40694 -7.954077) (xy 91.38666 -7.922514)
			(xy 91.37773 -7.909116) (xy 91.354379 -7.886962) (xy 91.326223 -7.871362) (xy 91.295058 -7.86331)
			(xy 91.278964 -7.862824) (xy 90.956638 -7.862824) (xy 90.939913 -7.863298) (xy 90.907599 -7.871938)
			(xy 90.878646 -7.888687) (xy 90.866468 -7.900162) (xy 90.852498 -7.914386) (xy 90.849958 -7.916926)
			(xy 90.838711 -7.929191) (xy 90.822374 -7.958167) (xy 90.81407 -7.990379) (xy 90.814361 -8.023642)
			(xy 90.823229 -8.055703) (xy 90.840071 -8.084388) (xy 90.851482 -8.096504) (xy 90.875104 -8.119618)
			(xy 90.907108 -8.128508) (xy 90.942361 -8.138593) (xy 91.010749 -8.165055) (xy 91.076053 -8.19841)
			(xy 91.13758 -8.238304) (xy 91.164605 -8.26008) (xy 93.154506 -8.26008) (xy 93.158522 -8.14381) (xy 93.170549 -8.028095)
			(xy 93.190531 -7.913485) (xy 93.218373 -7.800526) (xy 93.253942 -7.689758) (xy 93.297068 -7.581707)
			(xy 93.347545 -7.476889) (xy 93.405134 -7.375804) (xy 93.46956 -7.278932) (xy 93.540515 -7.186736)
			(xy 93.617662 -7.099655) (xy 93.700633 -7.018104) (xy 93.789033 -6.942472) (xy 93.88244 -6.873118)
			(xy 93.980409 -6.810375) (xy 94.082473 -6.754539) (xy 94.188147 -6.705878) (xy 94.296926 -6.664624)
			(xy 94.408291 -6.630973) (xy 94.521714 -6.605085) (xy 94.636651 -6.587084) (xy 94.752557 -6.577055)
			(xy 94.868879 -6.575047) (xy 94.985062 -6.581069) (xy 95.100553 -6.595092) (xy 95.214801 -6.61705)
			(xy 95.327262 -6.646837) (xy 95.4374 -6.684312) (xy 95.54469 -6.729297) (xy 95.648621 -6.781576)
			(xy 95.748697 -6.840901) (xy 95.844443 -6.906989) (xy 95.9354 -6.979525) (xy 96.021136 -7.058164)
			(xy 96.101243 -7.14253) (xy 96.175339 -7.232222) (xy 96.243069 -7.326812) (xy 96.304113 -7.42585)
			(xy 96.358178 -7.528863) (xy 96.405008 -7.63536) (xy 96.444379 -7.744835) (xy 96.476103 -7.856765)
			(xy 96.500029 -7.970617) (xy 96.516043 -8.085849) (xy 96.52407 -8.201911) (xy 96.524572 -8.26008)
			(xy 96.52407 -8.318249) (xy 96.516043 -8.434311) (xy 96.500029 -8.549543) (xy 96.476103 -8.663395)
			(xy 96.444379 -8.775325) (xy 96.405008 -8.8848) (xy 96.358178 -8.991297) (xy 96.304113 -9.09431)
			(xy 96.243069 -9.193348) (xy 96.175339 -9.287938) (xy 96.101243 -9.37763) (xy 96.021136 -9.461996)
			(xy 95.9354 -9.540635) (xy 95.844443 -9.613171) (xy 95.748697 -9.679259) (xy 95.648621 -9.738584)
			(xy 95.54469 -9.790863) (xy 95.4374 -9.835848) (xy 95.327262 -9.873323) (xy 95.214801 -9.90311) (xy 95.100553 -9.925068)
			(xy 94.985062 -9.939091) (xy 94.868879 -9.945113) (xy 94.752557 -9.943105) (xy 94.636651 -9.933076)
			(xy 94.521714 -9.915075) (xy 94.408291 -9.889187) (xy 94.296926 -9.855536) (xy 94.188147 -9.814282)
			(xy 94.082473 -9.765621) (xy 93.980409 -9.709785) (xy 93.88244 -9.647042) (xy 93.789033 -9.577688)
			(xy 93.700633 -9.502056) (xy 93.617662 -9.420505) (xy 93.540515 -9.333424) (xy 93.46956 -9.241228)
			(xy 93.405134 -9.144356) (xy 93.347545 -9.043271) (xy 93.297068 -8.938453) (xy 93.253942 -8.830402)
			(xy 93.218373 -8.719634) (xy 93.190531 -8.606675) (xy 93.170549 -8.492065) (xy 93.158522 -8.37635)
			(xy 93.154506 -8.26008) (xy 91.164605 -8.26008) (xy 91.19468 -8.284313) (xy 91.246745 -8.335949)
			(xy 91.293224 -8.392666) (xy 91.333625 -8.453862) (xy 91.367518 -8.518888) (xy 91.394545 -8.587055)
			(xy 91.414419 -8.657639) (xy 91.426929 -8.729893) (xy 91.431943 -8.80305) (xy 91.43111 -8.839708)
			(xy 91.429357 -8.87657) (xy 91.419169 -8.949665) (xy 91.401473 -9.021314) (xy 91.376461 -9.090747)
			(xy 91.344399 -9.157221) (xy 91.305633 -9.220021) (xy 91.260578 -9.278473) (xy 91.209718 -9.331951)
			(xy 91.153598 -9.379881) (xy 91.092821 -9.421747) (xy 91.028039 -9.457102) (xy 90.959947 -9.485565)
			(xy 90.889276 -9.506831) (xy 90.816784 -9.520671) (xy 90.743249 -9.526938) (xy 90.66946 -9.525564)
			(xy 90.596209 -9.516564) (xy 90.560144 -9.508744) (xy 90.544349 -9.505602) (xy 90.512165 -9.506477)
			(xy 90.481222 -9.515371) (xy 90.453487 -9.531721) (xy 90.44178 -9.54278) (xy 88.820244 -11.164062)
			(xy 88.808896 -11.176211) (xy 88.792308 -11.205007) (xy 88.783713 -11.237108) (xy 88.78316 -11.253724)
			(xy 88.78316 -12.705842) (xy 88.799162 -12.734544) (xy 88.812075 -12.758885) (xy 88.831534 -12.810434)
			(xy 88.843374 -12.864246) (xy 88.847348 -12.919202) (xy 88.843373 -12.974158) (xy 88.831533 -13.02797)
			(xy 88.812073 -13.079518) (xy 88.799162 -13.10386) (xy 88.78316 -13.132562) (xy 88.78316 -13.256006)
			(xy 91.040456 -13.256006) (xy 91.044527 -13.200384) (xy 91.056653 -13.145947) (xy 91.076576 -13.093856)
			(xy 91.103872 -13.045221) (xy 91.137958 -13.001078) (xy 91.178107 -12.962369) (xy 91.223465 -12.929918)
			(xy 91.273065 -12.904417) (xy 91.325849 -12.88641) (xy 91.380692 -12.87628) (xy 91.436426 -12.874243)
			(xy 91.491863 -12.880343) (xy 91.54582 -12.894449) (xy 91.597149 -12.916261) (xy 91.644755 -12.945315)
			(xy 91.687623 -12.98099) (xy 91.72484 -13.022527) (xy 91.755613 -13.06904) (xy 91.779285 -13.119537)
			(xy 91.795353 -13.172944) (xy 91.803473 -13.22812) (xy 91.803982 -13.256006) (xy 91.803473 -13.283892)
			(xy 91.802082 -13.293344) (xy 92.510862 -13.293344) (xy 92.514933 -13.237722) (xy 92.527059 -13.183285)
			(xy 92.546982 -13.131194) (xy 92.574278 -13.082559) (xy 92.608364 -13.038416) (xy 92.648513 -12.999707)
			(xy 92.693871 -12.967256) (xy 92.743471 -12.941755) (xy 92.796255 -12.923748) (xy 92.851098 -12.913618)
			(xy 92.906832 -12.911581) (xy 92.962269 -12.917681) (xy 93.016226 -12.931787) (xy 93.067555 -12.953599)
			(xy 93.115161 -12.982653) (xy 93.158029 -13.018328) (xy 93.195246 -13.059865) (xy 93.226019 -13.106378)
			(xy 93.249691 -13.156875) (xy 93.265759 -13.210282) (xy 93.271329 -13.248132) (xy 95.94926 -13.248132)
			(xy 95.953331 -13.19251) (xy 95.965457 -13.138073) (xy 95.98538 -13.085982) (xy 96.012676 -13.037347)
			(xy 96.046762 -12.993204) (xy 96.086911 -12.954495) (xy 96.132269 -12.922044) (xy 96.181869 -12.896543)
			(xy 96.234653 -12.878536) (xy 96.289496 -12.868406) (xy 96.34523 -12.866369) (xy 96.400667 -12.872469)
			(xy 96.454624 -12.886575) (xy 96.505953 -12.908387) (xy 96.553559 -12.937441) (xy 96.596427 -12.973116)
			(xy 96.633644 -13.014653) (xy 96.664417 -13.061166) (xy 96.688089 -13.111663) (xy 96.704157 -13.16507)
			(xy 96.712277 -13.220246) (xy 96.712786 -13.248132) (xy 96.712277 -13.276018) (xy 96.704157 -13.331194)
			(xy 96.688089 -13.384601) (xy 96.664417 -13.435098) (xy 96.633644 -13.481611) (xy 96.596427 -13.523148)
			(xy 96.553559 -13.558823) (xy 96.505953 -13.587877) (xy 96.454624 -13.609689) (xy 96.400667 -13.623795)
			(xy 96.34523 -13.629895) (xy 96.289496 -13.627858) (xy 96.234653 -13.617728) (xy 96.181869 -13.599721)
			(xy 96.132269 -13.57422) (xy 96.086911 -13.541769) (xy 96.046762 -13.50306) (xy 96.012676 -13.458917)
			(xy 95.98538 -13.410282) (xy 95.965457 -13.358191) (xy 95.953331 -13.303754) (xy 95.94926 -13.248132)
			(xy 93.271329 -13.248132) (xy 93.273879 -13.265458) (xy 93.274388 -13.293344) (xy 93.273879 -13.32123)
			(xy 93.265759 -13.376406) (xy 93.249691 -13.429813) (xy 93.226019 -13.48031) (xy 93.195246 -13.526823)
			(xy 93.158029 -13.56836) (xy 93.115161 -13.604035) (xy 93.067555 -13.633089) (xy 93.016226 -13.654901)
			(xy 92.962269 -13.669007) (xy 92.906832 -13.675107) (xy 92.851098 -13.67307) (xy 92.796255 -13.66294)
			(xy 92.743471 -13.644933) (xy 92.693871 -13.619432) (xy 92.648513 -13.586981) (xy 92.608364 -13.548272)
			(xy 92.574278 -13.504129) (xy 92.546982 -13.455494) (xy 92.527059 -13.403403) (xy 92.514933 -13.348966)
			(xy 92.510862 -13.293344) (xy 91.802082 -13.293344) (xy 91.795353 -13.339068) (xy 91.779285 -13.392475)
			(xy 91.755613 -13.442972) (xy 91.72484 -13.489485) (xy 91.687623 -13.531022) (xy 91.644755 -13.566697)
			(xy 91.597149 -13.595751) (xy 91.54582 -13.617563) (xy 91.491863 -13.631669) (xy 91.436426 -13.637769)
			(xy 91.380692 -13.635732) (xy 91.325849 -13.625602) (xy 91.273065 -13.607595) (xy 91.223465 -13.582094)
			(xy 91.178107 -13.549643) (xy 91.137958 -13.510934) (xy 91.103872 -13.466791) (xy 91.076576 -13.418156)
			(xy 91.056653 -13.366065) (xy 91.044527 -13.311628) (xy 91.040456 -13.256006) (xy 88.78316 -13.256006)
			(xy 88.78316 -14.256004) (xy 94.157798 -14.256004) (xy 94.161869 -14.200382) (xy 94.173995 -14.145945)
			(xy 94.193918 -14.093854) (xy 94.221214 -14.045219) (xy 94.2553 -14.001076) (xy 94.295449 -13.962367)
			(xy 94.340807 -13.929916) (xy 94.390407 -13.904415) (xy 94.443191 -13.886408) (xy 94.498034 -13.876278)
			(xy 94.553768 -13.874241) (xy 94.609205 -13.880341) (xy 94.663162 -13.894447) (xy 94.714491 -13.916259)
			(xy 94.762097 -13.945313) (xy 94.804965 -13.980988) (xy 94.842182 -14.022525) (xy 94.872955 -14.069038)
			(xy 94.896627 -14.119535) (xy 94.912695 -14.172942) (xy 94.920815 -14.228118) (xy 94.921324 -14.256004)
			(xy 94.920815 -14.28389) (xy 94.912695 -14.339066) (xy 94.896627 -14.392473) (xy 94.872955 -14.44297)
			(xy 94.842182 -14.489483) (xy 94.804965 -14.53102) (xy 94.762097 -14.566695) (xy 94.714491 -14.595749)
			(xy 94.663162 -14.617561) (xy 94.609205 -14.631667) (xy 94.553768 -14.637767) (xy 94.498034 -14.63573)
			(xy 94.443191 -14.6256) (xy 94.390407 -14.607593) (xy 94.340807 -14.582092) (xy 94.295449 -14.549641)
			(xy 94.2553 -14.510932) (xy 94.221214 -14.466789) (xy 94.193918 -14.418154) (xy 94.173995 -14.366063)
			(xy 94.161869 -14.311626) (xy 94.157798 -14.256004) (xy 88.78316 -14.256004) (xy 88.78316 -14.59738)
			(xy 88.536526 -14.844014) (xy 96.02927 -14.844014) (xy 96.033341 -14.788392) (xy 96.045467 -14.733955)
			(xy 96.06539 -14.681864) (xy 96.092686 -14.633229) (xy 96.126772 -14.589086) (xy 96.166921 -14.550377)
			(xy 96.212279 -14.517926) (xy 96.261879 -14.492425) (xy 96.314663 -14.474418) (xy 96.369506 -14.464288)
			(xy 96.42524 -14.462251) (xy 96.480677 -14.468351) (xy 96.534634 -14.482457) (xy 96.585963 -14.504269)
			(xy 96.633569 -14.533323) (xy 96.676437 -14.568998) (xy 96.713654 -14.610535) (xy 96.744427 -14.657048)
			(xy 96.768099 -14.707545) (xy 96.784167 -14.760952) (xy 96.792287 -14.816128) (xy 96.792796 -14.844014)
			(xy 96.792287 -14.8719) (xy 96.784167 -14.927076) (xy 96.768099 -14.980483) (xy 96.744427 -15.03098)
			(xy 96.713654 -15.077493) (xy 96.676437 -15.11903) (xy 96.633569 -15.154705) (xy 96.585963 -15.183759)
			(xy 96.534634 -15.205571) (xy 96.480677 -15.219677) (xy 96.42524 -15.225777) (xy 96.369506 -15.22374)
			(xy 96.314663 -15.21361) (xy 96.261879 -15.195603) (xy 96.212279 -15.170102) (xy 96.166921 -15.137651)
			(xy 96.126772 -15.098942) (xy 96.092686 -15.054799) (xy 96.06539 -15.006164) (xy 96.045467 -14.954073)
			(xy 96.033341 -14.899636) (xy 96.02927 -14.844014) (xy 88.536526 -14.844014) (xy 86.199472 -17.181068)
			(xy 86.199472 -20.01012) (xy 86.877404 -20.01012) (xy 86.881424 -19.819469) (xy 86.893478 -19.629156)
			(xy 86.913544 -19.439521) (xy 86.941587 -19.2509) (xy 86.977556 -19.06363) (xy 87.021388 -18.878042)
			(xy 87.073005 -18.694467) (xy 87.132315 -18.513231) (xy 87.199213 -18.334656) (xy 87.273579 -18.159061)
			(xy 87.355281 -17.986756) (xy 87.444175 -17.818049) (xy 87.540101 -17.653239) (xy 87.64289 -17.49262)
			(xy 87.752359 -17.336477) (xy 87.868313 -17.185088) (xy 87.990547 -17.038721) (xy 88.118841 -16.897637)
			(xy 88.252969 -16.762088) (xy 88.392693 -16.632313) (xy 88.537763 -16.508543) (xy 88.687921 -16.391)
			(xy 88.842902 -16.279891) (xy 89.002429 -16.175414) (xy 89.166218 -16.077755) (xy 89.333978 -15.987088)
			(xy 89.505412 -15.903574) (xy 89.680214 -15.827361) (xy 89.858073 -15.758585) (xy 90.038674 -15.697367)
			(xy 90.221694 -15.643818) (xy 90.40681 -15.598032) (xy 90.593691 -15.56009) (xy 90.782006 -15.530061)
			(xy 90.971419 -15.507996) (xy 91.161593 -15.493937) (xy 91.352192 -15.487907) (xy 91.542875 -15.489917)
			(xy 91.733304 -15.499964) (xy 91.92314 -15.51803) (xy 92.112046 -15.544083) (xy 92.299685 -15.578076)
			(xy 92.485725 -15.619949) (xy 92.669834 -15.669628) (xy 92.851685 -15.727024) (xy 93.030955 -15.792035)
			(xy 93.207325 -15.864546) (xy 93.380481 -15.944427) (xy 93.550116 -16.031537) (xy 93.715928 -16.125721)
			(xy 93.877622 -16.226812) (xy 94.03491 -16.334628) (xy 94.187513 -16.44898) (xy 94.335161 -16.569663)
			(xy 94.477589 -16.696464) (xy 94.614545 -16.829155) (xy 94.745786 -16.967503) (xy 94.871078 -17.11126)
			(xy 94.990198 -17.260171) (xy 95.102934 -17.413972) (xy 95.209087 -17.572388) (xy 95.308467 -17.735139)
			(xy 95.400897 -17.901934) (xy 95.486214 -18.072478) (xy 95.564266 -18.246466) (xy 95.634913 -18.423591)
			(xy 95.698031 -18.603536) (xy 95.753507 -18.785982) (xy 95.801242 -18.970605) (xy 95.841152 -19.157075)
			(xy 95.873165 -19.345063) (xy 95.895305 -19.519138) (xy 98.049078 -19.519138) (xy 98.053149 -19.463516)
			(xy 98.065275 -19.409079) (xy 98.085198 -19.356988) (xy 98.112494 -19.308353) (xy 98.14658 -19.26421)
			(xy 98.186729 -19.225501) (xy 98.232087 -19.19305) (xy 98.281687 -19.167549) (xy 98.334471 -19.149542)
			(xy 98.389314 -19.139412) (xy 98.445048 -19.137375) (xy 98.500485 -19.143475) (xy 98.554442 -19.157581)
			(xy 98.605771 -19.179393) (xy 98.653377 -19.208447) (xy 98.696245 -19.244122) (xy 98.733462 -19.285659)
			(xy 98.764235 -19.332172) (xy 98.787907 -19.382669) (xy 98.803975 -19.436076) (xy 98.812095 -19.491252)
			(xy 98.812604 -19.519138) (xy 98.812095 -19.547024) (xy 98.803975 -19.6022) (xy 98.787907 -19.655607)
			(xy 98.764235 -19.706104) (xy 98.733462 -19.752617) (xy 98.696245 -19.794154) (xy 98.653377 -19.829829)
			(xy 98.605771 -19.858883) (xy 98.554442 -19.880695) (xy 98.500485 -19.894801) (xy 98.445048 -19.900901)
			(xy 98.389314 -19.898864) (xy 98.334471 -19.888734) (xy 98.281687 -19.870727) (xy 98.232087 -19.845226)
			(xy 98.186729 -19.812775) (xy 98.14658 -19.774066) (xy 98.112494 -19.729923) (xy 98.085198 -19.681288)
			(xy 98.065275 -19.629197) (xy 98.053149 -19.57476) (xy 98.049078 -19.519138) (xy 95.895305 -19.519138)
			(xy 95.897225 -19.534233) (xy 95.913288 -19.724249) (xy 95.921327 -19.914773) (xy 95.92183 -20.01012)
			(xy 95.921327 -20.105467) (xy 95.913288 -20.295991) (xy 95.897225 -20.486007) (xy 95.873165 -20.675177)
			(xy 95.841152 -20.863165) (xy 95.801242 -21.049635) (xy 95.753507 -21.234258) (xy 95.698031 -21.416704)
			(xy 95.634913 -21.596649) (xy 95.564266 -21.773774) (xy 95.486214 -21.947762) (xy 95.400897 -22.118306)
			(xy 95.308467 -22.285101) (xy 95.209087 -22.447852) (xy 95.102934 -22.606268) (xy 94.990198 -22.760069)
			(xy 94.871078 -22.90898) (xy 94.745786 -23.052737) (xy 94.614545 -23.191085) (xy 94.477589 -23.323776)
			(xy 94.335161 -23.450577) (xy 94.187513 -23.57126) (xy 94.03491 -23.685612) (xy 93.877622 -23.793428)
			(xy 93.715928 -23.894519) (xy 93.550116 -23.988703) (xy 93.380481 -24.075813) (xy 93.207325 -24.155694)
			(xy 93.030955 -24.228205) (xy 92.851685 -24.293216) (xy 92.669834 -24.350612) (xy 92.485725 -24.400291)
			(xy 92.299685 -24.442164) (xy 92.112046 -24.476157) (xy 91.92314 -24.50221) (xy 91.733304 -24.520276)
			(xy 91.542875 -24.530323) (xy 91.352192 -24.532333) (xy 91.161593 -24.526303) (xy 90.971419 -24.512244)
			(xy 90.782006 -24.490179) (xy 90.593691 -24.46015) (xy 90.40681 -24.422208) (xy 90.221694 -24.376422)
			(xy 90.038674 -24.322873) (xy 89.858073 -24.261655) (xy 89.680214 -24.192879) (xy 89.505412 -24.116666)
			(xy 89.333978 -24.033152) (xy 89.166218 -23.942485) (xy 89.002429 -23.844826) (xy 88.842902 -23.740349)
			(xy 88.687921 -23.62924) (xy 88.537763 -23.511697) (xy 88.392693 -23.387927) (xy 88.252969 -23.258152)
			(xy 88.118841 -23.122603) (xy 87.990547 -22.981519) (xy 87.868313 -22.835152) (xy 87.752359 -22.683763)
			(xy 87.64289 -22.52762) (xy 87.540101 -22.367001) (xy 87.444175 -22.202191) (xy 87.355281 -22.033484)
			(xy 87.273579 -21.861179) (xy 87.199213 -21.685584) (xy 87.132315 -21.507009) (xy 87.073005 -21.325773)
			(xy 87.021388 -21.142198) (xy 86.977556 -20.95661) (xy 86.941587 -20.76934) (xy 86.913544 -20.580719)
			(xy 86.893478 -20.391084) (xy 86.881424 -20.200771) (xy 86.877404 -20.01012) (xy 86.199472 -20.01012)
			(xy 86.199472 -48.612044) (xy 86.200729 -48.635206) (xy 86.210601 -48.680524) (xy 86.22853 -48.723299)
			(xy 86.253922 -48.762111) (xy 86.285933 -48.795674) (xy 86.323501 -48.822872) (xy 86.36538 -48.842804)
			(xy 86.410181 -48.854807) (xy 86.456415 -48.858485) (xy 86.50255 -48.853713) (xy 86.547053 -48.840652)
			(xy 86.568026 -48.830738) (xy 86.603195 -48.812101) (xy 86.676836 -48.78189) (xy 86.753388 -48.760088)
			(xy 86.831896 -48.746969) (xy 86.911378 -48.742695) (xy 86.99084 -48.747321) (xy 87.069289 -48.760788)
			(xy 87.145744 -48.782929) (xy 87.219249 -48.813467) (xy 87.254334 -48.832262) (xy 87.288787 -48.851946)
			(xy 87.353519 -48.897841) (xy 87.412748 -48.950647) (xy 87.465742 -49.009708) (xy 87.511843 -49.074294)
			(xy 87.55048 -49.143603) (xy 87.581175 -49.216777) (xy 87.603546 -49.29291) (xy 87.617317 -49.371057)
			(xy 87.620348 -49.41062) (xy 87.623396 -49.458626) (xy 87.657432 -49.492662) (xy 87.66955 -49.504101)
			(xy 87.698389 -49.520777) (xy 87.730564 -49.529409) (xy 87.763878 -49.529409) (xy 87.796053 -49.520777)
			(xy 87.824892 -49.504101) (xy 87.83701 -49.492662) (xy 87.885524 -49.444148) (xy 88.622632 -49.444148)
			(xy 88.637507 -49.443739) (xy 88.666446 -49.436832) (xy 88.692993 -49.423403) (xy 88.715703 -49.404183)
			(xy 88.733337 -49.380221) (xy 88.744933 -49.352823) (xy 88.747854 -49.33823) (xy 88.747854 -49.337976)
			(xy 88.754428 -49.301456) (xy 88.774181 -49.229927) (xy 88.801271 -49.160842) (xy 88.835404 -49.094951)
			(xy 88.876207 -49.03297) (xy 88.923239 -48.975571) (xy 88.975989 -48.923378) (xy 89.033884 -48.876958)
			(xy 89.096296 -48.836815) (xy 89.162545 -48.803384) (xy 89.231914 -48.777029) (xy 89.303649 -48.758036)
			(xy 89.376971 -48.746611) (xy 89.451084 -48.742879) (xy 89.525183 -48.746879) (xy 89.598463 -48.758568)
			(xy 89.670129 -48.77782) (xy 89.739403 -48.804424) (xy 89.805532 -48.838094) (xy 89.867798 -48.878462)
			(xy 89.925525 -48.92509) (xy 89.978086 -48.977473) (xy 90.024911 -49.035041) (xy 90.065491 -49.097169)
			(xy 90.082878 -49.12995) (xy 90.099422 -49.163214) (xy 90.126295 -49.232478) (xy 90.145806 -49.304165)
			(xy 90.157743 -49.377494) (xy 90.161976 -49.451668) (xy 90.161815 -49.45507) (xy 91.277697 -49.45507)
			(xy 91.281732 -49.379366) (xy 91.293791 -49.304521) (xy 91.313737 -49.23138) (xy 91.341344 -49.160775)
			(xy 91.3763 -49.093504) (xy 91.418208 -49.030329) (xy 91.466594 -48.971967) (xy 91.52091 -48.919079)
			(xy 91.580539 -48.872264) (xy 91.644807 -48.832052) (xy 91.712984 -48.7989) (xy 91.7843 -48.773182)
			(xy 91.857945 -48.75519) (xy 91.933085 -48.745128) (xy 92.008869 -48.743109) (xy 92.084439 -48.749158)
			(xy 92.158937 -48.763205) (xy 92.23152 -48.785091) (xy 92.301366 -48.814568) (xy 92.367683 -48.851303)
			(xy 92.429719 -48.894878) (xy 92.486772 -48.9448) (xy 92.538196 -49.000504) (xy 92.583407 -49.061359)
			(xy 92.621894 -49.126674) (xy 92.65322 -49.19571) (xy 92.67703 -49.267685) (xy 92.693055 -49.341783)
			(xy 92.701114 -49.417164) (xy 92.701618 -49.45507) (xy 92.701114 -49.492976) (xy 92.693055 -49.568357)
			(xy 92.67703 -49.642455) (xy 92.65322 -49.71443) (xy 92.621894 -49.783466) (xy 92.583407 -49.848781)
			(xy 92.538196 -49.909636) (xy 92.486772 -49.96534) (xy 92.429719 -50.015262) (xy 92.367683 -50.058837)
			(xy 92.301366 -50.095572) (xy 92.23152 -50.125049) (xy 92.158937 -50.146935) (xy 92.084439 -50.160982)
			(xy 92.008869 -50.167031) (xy 91.933085 -50.165012) (xy 91.857945 -50.15495) (xy 91.7843 -50.136958)
			(xy 91.712984 -50.11124) (xy 91.644807 -50.078088) (xy 91.580539 -50.037876) (xy 91.52091 -49.991061)
			(xy 91.466594 -49.938173) (xy 91.418208 -49.879811) (xy 91.3763 -49.816636) (xy 91.341344 -49.749365)
			(xy 91.313737 -49.67876) (xy 91.293791 -49.605619) (xy 91.281732 -49.530774) (xy 91.277697 -49.45507)
			(xy 90.161815 -49.45507) (xy 90.158458 -49.525879) (xy 90.147228 -49.59932) (xy 90.128409 -49.671192)
			(xy 90.102205 -49.740712) (xy 90.0689 -49.807124) (xy 90.028859 -49.869704) (xy 89.982516 -49.927773)
			(xy 89.930375 -49.980698) (xy 89.873005 -50.027903) (xy 89.811029 -50.068875) (xy 89.745122 -50.103167)
			(xy 89.676001 -50.130407) (xy 89.604418 -50.150297) (xy 89.531153 -50.162622) (xy 89.457002 -50.167247)
			(xy 89.382773 -50.164123) (xy 89.309274 -50.153282) (xy 89.237304 -50.134843) (xy 89.167646 -50.109008)
			(xy 89.134188 -50.092864) (xy 89.107772 -50.079656) (xy 89.054686 -50.079656) (xy 89.032094 -50.080863)
			(xy 88.987845 -50.090274) (xy 88.945962 -50.107371) (xy 88.907767 -50.131614) (xy 88.874469 -50.162236)
			(xy 88.847119 -50.198271) (xy 88.826581 -50.238579) (xy 88.813505 -50.281886) (xy 88.808304 -50.326824)
			(xy 88.811141 -50.371974) (xy 88.821928 -50.415907) (xy 88.830658 -50.43678) (xy 88.845676 -50.471879)
			(xy 88.868976 -50.544585) (xy 88.884352 -50.619369) (xy 88.891629 -50.69537) (xy 88.891276 -50.72507)
			(xy 90.007697 -50.72507) (xy 90.011732 -50.649366) (xy 90.023791 -50.574521) (xy 90.043737 -50.50138)
			(xy 90.071344 -50.430775) (xy 90.1063 -50.363504) (xy 90.148208 -50.300329) (xy 90.196594 -50.241967)
			(xy 90.25091 -50.189079) (xy 90.310539 -50.142264) (xy 90.374807 -50.102052) (xy 90.442984 -50.0689)
			(xy 90.5143 -50.043182) (xy 90.587945 -50.02519) (xy 90.663085 -50.015128) (xy 90.738869 -50.013109)
			(xy 90.814439 -50.019158) (xy 90.888937 -50.033205) (xy 90.96152 -50.055091) (xy 91.031366 -50.084568)
			(xy 91.097683 -50.121303) (xy 91.159719 -50.164878) (xy 91.216772 -50.2148) (xy 91.268196 -50.270504)
			(xy 91.313407 -50.331359) (xy 91.351894 -50.396674) (xy 91.38322 -50.46571) (xy 91.40703 -50.537685)
			(xy 91.423055 -50.611783) (xy 91.431114 -50.687164) (xy 91.431618 -50.72507) (xy 91.431114 -50.762976)
			(xy 91.423055 -50.838357) (xy 91.40703 -50.912455) (xy 91.38322 -50.98443) (xy 91.351894 -51.053466)
			(xy 91.313407 -51.118781) (xy 91.268196 -51.179636) (xy 91.216772 -51.23534) (xy 91.159719 -51.285262)
			(xy 91.097683 -51.328837) (xy 91.031366 -51.365572) (xy 90.96152 -51.395049) (xy 90.888937 -51.416935)
			(xy 90.814439 -51.430982) (xy 90.738869 -51.437031) (xy 90.663085 -51.435012) (xy 90.587945 -51.42495)
			(xy 90.5143 -51.406958) (xy 90.442984 -51.38124) (xy 90.374807 -51.348088) (xy 90.310539 -51.307876)
			(xy 90.25091 -51.261061) (xy 90.196594 -51.208173) (xy 90.148208 -51.149811) (xy 90.1063 -51.086636)
			(xy 90.071344 -51.019365) (xy 90.043737 -50.94876) (xy 90.023791 -50.875619) (xy 90.011732 -50.800774)
			(xy 90.007697 -50.72507) (xy 88.891276 -50.72507) (xy 88.890722 -50.771712) (xy 88.881642 -50.847518)
			(xy 88.873584 -50.884836) (xy 88.873584 -50.88509) (xy 88.87045 -50.900839) (xy 88.871307 -50.932929)
			(xy 88.880142 -50.963791) (xy 88.896395 -50.991473) (xy 88.907366 -51.0032) (xy 88.91778 -51.013614)
			(xy 88.91778 -51.078384) (xy 88.919004 -51.101389) (xy 88.928729 -51.146416) (xy 88.946411 -51.188953)
			(xy 88.971471 -51.227605) (xy 89.003089 -51.261106) (xy 89.040227 -51.288359) (xy 89.08167 -51.30847)
			(xy 89.12606 -51.320782) (xy 89.171941 -51.324889) (xy 89.217812 -51.320659) (xy 89.240106 -51.314858)
			(xy 89.276553 -51.304135) (xy 89.351129 -51.289612) (xy 89.426828 -51.283114) (xy 89.502788 -51.284718)
			(xy 89.578145 -51.294403) (xy 89.652042 -51.31206) (xy 89.723638 -51.337488) (xy 89.792117 -51.370398)
			(xy 89.856702 -51.410415) (xy 89.916656 -51.457084) (xy 89.971299 -51.509873) (xy 90.020007 -51.568183)
			(xy 90.062227 -51.631349) (xy 90.097479 -51.698654) (xy 90.12536 -51.76933) (xy 90.145555 -51.842574)
			(xy 90.157833 -51.917552) (xy 90.162054 -51.993412) (xy 90.161969 -51.99507) (xy 91.277697 -51.99507)
			(xy 91.281732 -51.919366) (xy 91.293791 -51.844521) (xy 91.313737 -51.77138) (xy 91.341344 -51.700775)
			(xy 91.3763 -51.633504) (xy 91.418208 -51.570329) (xy 91.466594 -51.511967) (xy 91.52091 -51.459079)
			(xy 91.580539 -51.412264) (xy 91.644807 -51.372052) (xy 91.712984 -51.3389) (xy 91.7843 -51.313182)
			(xy 91.857945 -51.29519) (xy 91.933085 -51.285128) (xy 92.008869 -51.283109) (xy 92.084439 -51.289158)
			(xy 92.158937 -51.303205) (xy 92.23152 -51.325091) (xy 92.301366 -51.354568) (xy 92.367683 -51.391303)
			(xy 92.429719 -51.434878) (xy 92.486772 -51.4848) (xy 92.538196 -51.540504) (xy 92.583407 -51.601359)
			(xy 92.621894 -51.666674) (xy 92.65322 -51.73571) (xy 92.67703 -51.807685) (xy 92.693055 -51.881783)
			(xy 92.701114 -51.957164) (xy 92.701618 -51.99507) (xy 92.701114 -52.032976) (xy 92.693055 -52.108357)
			(xy 92.67703 -52.182455) (xy 92.65322 -52.25443) (xy 92.621894 -52.323466) (xy 92.583407 -52.388781)
			(xy 92.538196 -52.449636) (xy 92.486772 -52.50534) (xy 92.429719 -52.555262) (xy 92.367683 -52.598837)
			(xy 92.301366 -52.635572) (xy 92.23152 -52.665049) (xy 92.158937 -52.686935) (xy 92.084439 -52.700982)
			(xy 92.008869 -52.707031) (xy 91.933085 -52.705012) (xy 91.857945 -52.69495) (xy 91.7843 -52.676958)
			(xy 91.712984 -52.65124) (xy 91.644807 -52.618088) (xy 91.580539 -52.577876) (xy 91.52091 -52.531061)
			(xy 91.466594 -52.478173) (xy 91.418208 -52.419811) (xy 91.3763 -52.356636) (xy 91.341344 -52.289365)
			(xy 91.313737 -52.21876) (xy 91.293791 -52.145619) (xy 91.281732 -52.070774) (xy 91.277697 -51.99507)
			(xy 90.161969 -51.99507) (xy 90.158171 -52.06929) (xy 90.146228 -52.144322) (xy 90.12636 -52.217656)
			(xy 90.098794 -52.288455) (xy 90.063843 -52.355916) (xy 90.021905 -52.41927) (xy 89.973457 -52.477796)
			(xy 89.91905 -52.530829) (xy 89.859305 -52.577765) (xy 89.827354 -52.59832) (xy 89.81396 -52.607253)
			(xy 89.791812 -52.630607) (xy 89.776216 -52.658761) (xy 89.768163 -52.689923) (xy 89.767664 -52.706016)
			(xy 89.767664 -53.114194) (xy 89.768206 -53.130845) (xy 89.776823 -53.163012) (xy 89.793469 -53.191853)
			(xy 89.817013 -53.215405) (xy 89.845849 -53.232061) (xy 89.878014 -53.240688) (xy 89.894664 -53.241194)
			(xy 89.940892 -53.241194) (xy 90.01125 -53.18252) (xy 90.019632 -53.137054) (xy 90.02695 -53.099741)
			(xy 90.048513 -53.02682) (xy 90.077726 -52.956613) (xy 90.114256 -52.88992) (xy 90.157686 -52.8275)
			(xy 90.207523 -52.770066) (xy 90.263198 -52.71827) (xy 90.324076 -52.672705) (xy 90.389464 -52.633888)
			(xy 90.458618 -52.602262) (xy 90.530749 -52.578187) (xy 90.605034 -52.561938) (xy 90.680629 -52.5537)
			(xy 90.756671 -52.553566) (xy 90.832294 -52.561539) (xy 90.906636 -52.577527) (xy 90.978851 -52.601348)
			(xy 91.048115 -52.63273) (xy 91.11364 -52.671317) (xy 91.16581 -52.71008) (xy 93.154506 -52.71008)
			(xy 93.158522 -52.59381) (xy 93.170549 -52.478095) (xy 93.190531 -52.363485) (xy 93.218373 -52.250526)
			(xy 93.253942 -52.139758) (xy 93.297068 -52.031707) (xy 93.347545 -51.926889) (xy 93.405134 -51.825804)
			(xy 93.46956 -51.728932) (xy 93.540515 -51.636736) (xy 93.617662 -51.549655) (xy 93.700633 -51.468104)
			(xy 93.789033 -51.392472) (xy 93.88244 -51.323118) (xy 93.980409 -51.260375) (xy 94.082473 -51.204539)
			(xy 94.188147 -51.155878) (xy 94.296926 -51.114624) (xy 94.408291 -51.080973) (xy 94.521714 -51.055085)
			(xy 94.636651 -51.037084) (xy 94.752557 -51.027055) (xy 94.868879 -51.025047) (xy 94.985062 -51.031069)
			(xy 95.100553 -51.045092) (xy 95.214801 -51.06705) (xy 95.327262 -51.096837) (xy 95.4374 -51.134312)
			(xy 95.54469 -51.179297) (xy 95.648621 -51.231576) (xy 95.748697 -51.290901) (xy 95.844443 -51.356989)
			(xy 95.9354 -51.429525) (xy 96.021136 -51.508164) (xy 96.101243 -51.59253) (xy 96.175339 -51.682222)
			(xy 96.243069 -51.776812) (xy 96.304113 -51.87585) (xy 96.358178 -51.978863) (xy 96.405008 -52.08536)
			(xy 96.444379 -52.194835) (xy 96.476103 -52.306765) (xy 96.500029 -52.420617) (xy 96.516043 -52.535849)
			(xy 96.52407 -52.651911) (xy 96.524572 -52.71008) (xy 96.52407 -52.768249) (xy 96.516043 -52.884311)
			(xy 96.500029 -52.999543) (xy 96.476103 -53.113395) (xy 96.444379 -53.225325) (xy 96.405008 -53.3348)
			(xy 96.358178 -53.441297) (xy 96.304113 -53.54431) (xy 96.243069 -53.643348) (xy 96.175339 -53.737938)
			(xy 96.101243 -53.82763) (xy 96.021136 -53.911996) (xy 95.9354 -53.990635) (xy 95.844443 -54.063171)
			(xy 95.748697 -54.129259) (xy 95.648621 -54.188584) (xy 95.54469 -54.240863) (xy 95.4374 -54.285848)
			(xy 95.327262 -54.323323) (xy 95.214801 -54.35311) (xy 95.100553 -54.375068) (xy 94.985062 -54.389091)
			(xy 94.868879 -54.395113) (xy 94.752557 -54.393105) (xy 94.636651 -54.383076) (xy 94.521714 -54.365075)
			(xy 94.408291 -54.339187) (xy 94.296926 -54.305536) (xy 94.188147 -54.264282) (xy 94.082473 -54.215621)
			(xy 93.980409 -54.159785) (xy 93.88244 -54.097042) (xy 93.789033 -54.027688) (xy 93.700633 -53.952056)
			(xy 93.617662 -53.870505) (xy 93.540515 -53.783424) (xy 93.46956 -53.691228) (xy 93.405134 -53.594356)
			(xy 93.347545 -53.493271) (xy 93.297068 -53.388453) (xy 93.253942 -53.280402) (xy 93.218373 -53.169634)
			(xy 93.190531 -53.056675) (xy 93.170549 -52.942065) (xy 93.158522 -52.82635) (xy 93.154506 -52.71008)
			(xy 91.16581 -52.71008) (xy 91.174678 -52.716669) (xy 91.230534 -52.768268) (xy 91.280573 -52.825527)
			(xy 91.324222 -52.887793) (xy 91.360986 -52.954358) (xy 91.390446 -53.024462) (xy 91.412265 -53.097306)
			(xy 91.426195 -53.172062) (xy 91.432078 -53.247876) (xy 91.429846 -53.323885) (xy 91.419524 -53.399224)
			(xy 91.401232 -53.473033) (xy 91.375176 -53.544472) (xy 91.341653 -53.612726) (xy 91.301046 -53.677018)
			(xy 91.253818 -53.736616) (xy 91.200506 -53.79084) (xy 91.141718 -53.839073) (xy 91.078124 -53.880764)
			(xy 91.010448 -53.91544) (xy 90.939462 -53.942704) (xy 90.865974 -53.962247) (xy 90.790821 -53.973844)
			(xy 90.714861 -53.977366) (xy 90.638957 -53.97277) (xy 90.563977 -53.96011) (xy 90.490772 -53.93953)
			(xy 90.420179 -53.911264) (xy 90.353 -53.875635) (xy 90.290002 -53.833048) (xy 90.231902 -53.783988)
			(xy 90.205306 -53.756814) (xy 90.189091 -53.740561) (xy 90.151931 -53.71361) (xy 90.110536 -53.693767)
			(xy 90.066251 -53.681678) (xy 90.020515 -53.677735) (xy 89.974815 -53.682067) (xy 89.930635 -53.694533)
			(xy 89.88941 -53.714728) (xy 89.852481 -53.741995) (xy 89.821046 -53.775449) (xy 89.796128 -53.814003)
			(xy 89.778536 -53.856403) (xy 89.768842 -53.901273) (xy 89.767664 -53.9242) (xy 89.767664 -54.62651)
			(xy 89.096596 -55.297832) (xy 89.012268 -55.38216) (xy 89.012268 -57.643268) (xy 84.17814 -62.477396)
			(xy 84.168996 -62.508892) (xy 84.160918 -62.535291) (xy 84.13821 -62.585611) (xy 84.108489 -62.632133)
			(xy 84.072373 -62.673887) (xy 84.030617 -62.710001) (xy 83.984093 -62.73972) (xy 83.933772 -62.762424)
			(xy 83.907376 -62.770512) (xy 83.87588 -62.779656) (xy 82.195416 -64.46012) (xy 86.877404 -64.46012)
			(xy 86.881424 -64.269469) (xy 86.893478 -64.079156) (xy 86.913544 -63.889521) (xy 86.941587 -63.7009)
			(xy 86.977556 -63.51363) (xy 87.021388 -63.328042) (xy 87.073005 -63.144467) (xy 87.132315 -62.963231)
			(xy 87.199213 -62.784656) (xy 87.273579 -62.609061) (xy 87.355281 -62.436756) (xy 87.444175 -62.268049)
			(xy 87.540101 -62.103239) (xy 87.64289 -61.94262) (xy 87.752359 -61.786477) (xy 87.868313 -61.635088)
			(xy 87.990547 -61.488721) (xy 88.118841 -61.347637) (xy 88.252969 -61.212088) (xy 88.392693 -61.082313)
			(xy 88.537763 -60.958543) (xy 88.687921 -60.841) (xy 88.842902 -60.729891) (xy 89.002429 -60.625414)
			(xy 89.166218 -60.527755) (xy 89.333978 -60.437088) (xy 89.505412 -60.353574) (xy 89.680214 -60.277361)
			(xy 89.858073 -60.208585) (xy 90.038674 -60.147367) (xy 90.221694 -60.093818) (xy 90.40681 -60.048032)
			(xy 90.593691 -60.01009) (xy 90.782006 -59.980061) (xy 90.971419 -59.957996) (xy 91.161593 -59.943937)
			(xy 91.352192 -59.937907) (xy 91.542875 -59.939917) (xy 91.733304 -59.949964) (xy 91.92314 -59.96803)
			(xy 92.112046 -59.994083) (xy 92.299685 -60.028076) (xy 92.485725 -60.069949) (xy 92.669834 -60.119628)
			(xy 92.851685 -60.177024) (xy 93.030955 -60.242035) (xy 93.207325 -60.314546) (xy 93.380481 -60.394427)
			(xy 93.550116 -60.481537) (xy 93.715928 -60.575721) (xy 93.877622 -60.676812) (xy 94.03491 -60.784628)
			(xy 94.187513 -60.89898) (xy 94.335161 -61.019663) (xy 94.477589 -61.146464) (xy 94.614545 -61.279155)
			(xy 94.745786 -61.417503) (xy 94.871078 -61.56126) (xy 94.990198 -61.710171) (xy 95.102934 -61.863972)
			(xy 95.209087 -62.022388) (xy 95.308467 -62.185139) (xy 95.400897 -62.351934) (xy 95.486214 -62.522478)
			(xy 95.564266 -62.696466) (xy 95.634913 -62.873591) (xy 95.698031 -63.053536) (xy 95.753507 -63.235982)
			(xy 95.801242 -63.420605) (xy 95.841152 -63.607075) (xy 95.873165 -63.795063) (xy 95.897225 -63.984233)
			(xy 95.913288 -64.174249) (xy 95.921327 -64.364773) (xy 95.92183 -64.46012) (xy 95.921327 -64.555467)
			(xy 95.913288 -64.745991) (xy 95.897225 -64.936007) (xy 95.873165 -65.125177) (xy 95.841152 -65.313165)
			(xy 95.801242 -65.499635) (xy 95.753507 -65.684258) (xy 95.698031 -65.866704) (xy 95.634913 -66.046649)
			(xy 95.564266 -66.223774) (xy 95.486214 -66.397762) (xy 95.400897 -66.568306) (xy 95.308467 -66.735101)
			(xy 95.209087 -66.897852) (xy 95.102934 -67.056268) (xy 94.990198 -67.210069) (xy 94.871078 -67.35898)
			(xy 94.745786 -67.502737) (xy 94.614545 -67.641085) (xy 94.477589 -67.773776) (xy 94.335161 -67.900577)
			(xy 94.187513 -68.02126) (xy 94.03491 -68.135612) (xy 93.877622 -68.243428) (xy 93.715928 -68.344519)
			(xy 93.550116 -68.438703) (xy 93.380481 -68.525813) (xy 93.207325 -68.605694) (xy 93.030955 -68.678205)
			(xy 92.851685 -68.743216) (xy 92.669834 -68.800612) (xy 92.485725 -68.850291) (xy 92.299685 -68.892164)
			(xy 92.112046 -68.926157) (xy 91.92314 -68.95221) (xy 91.733304 -68.970276) (xy 91.542875 -68.980323)
			(xy 91.352192 -68.982333) (xy 91.161593 -68.976303) (xy 90.971419 -68.962244) (xy 90.782006 -68.940179)
			(xy 90.593691 -68.91015) (xy 90.40681 -68.872208) (xy 90.221694 -68.826422) (xy 90.038674 -68.772873)
			(xy 89.858073 -68.711655) (xy 89.680214 -68.642879) (xy 89.505412 -68.566666) (xy 89.333978 -68.483152)
			(xy 89.166218 -68.392485) (xy 89.002429 -68.294826) (xy 88.842902 -68.190349) (xy 88.687921 -68.07924)
			(xy 88.537763 -67.961697) (xy 88.392693 -67.837927) (xy 88.252969 -67.708152) (xy 88.118841 -67.572603)
			(xy 87.990547 -67.431519) (xy 87.868313 -67.285152) (xy 87.752359 -67.133763) (xy 87.64289 -66.97762)
			(xy 87.540101 -66.817001) (xy 87.444175 -66.652191) (xy 87.355281 -66.483484) (xy 87.273579 -66.311179)
			(xy 87.199213 -66.135584) (xy 87.132315 -65.957009) (xy 87.073005 -65.775773) (xy 87.021388 -65.592198)
			(xy 86.977556 -65.40661) (xy 86.941587 -65.21934) (xy 86.913544 -65.030719) (xy 86.893478 -64.841084)
			(xy 86.881424 -64.650771) (xy 86.877404 -64.46012) (xy 82.195416 -64.46012) (xy 68.276876 -78.37866)
			(xy 74.888589 -78.37866) (xy 74.888589 -78.220976) (xy 74.896576 -78.063495) (xy 74.912528 -77.90662)
			(xy 74.936406 -77.750755) (xy 74.968148 -77.596299) (xy 75.007671 -77.443649) (xy 75.054876 -77.293197)
			(xy 75.10964 -77.145329) (xy 75.171824 -77.000424) (xy 75.241267 -76.858855) (xy 75.317791 -76.720985)
			(xy 75.4012 -76.587168) (xy 75.49128 -76.457747) (xy 75.587799 -76.333054) (xy 75.69051 -76.21341)
			(xy 75.799148 -76.099122) (xy 75.913436 -75.990484) (xy 76.03308 -75.887773) (xy 76.157773 -75.791254)
			(xy 76.287194 -75.701174) (xy 76.421011 -75.617765) (xy 76.558881 -75.541241) (xy 76.70045 -75.471798)
			(xy 76.845355 -75.409614) (xy 76.993223 -75.35485) (xy 77.143675 -75.307645) (xy 77.296325 -75.268122)
			(xy 77.450781 -75.23638) (xy 77.606646 -75.212502) (xy 77.763521 -75.19655) (xy 77.921002 -75.188563)
			(xy 77.999844 -75.188064) (xy 78.078686 -75.188563) (xy 78.236167 -75.19655) (xy 78.393042 -75.212502)
			(xy 78.548907 -75.23638) (xy 78.703363 -75.268122) (xy 78.856013 -75.307645) (xy 79.006465 -75.35485)
			(xy 79.154333 -75.409614) (xy 79.299238 -75.471798) (xy 79.440807 -75.541241) (xy 79.578677 -75.617765)
			(xy 79.712494 -75.701174) (xy 79.841915 -75.791254) (xy 79.966608 -75.887773) (xy 80.086252 -75.990484)
			(xy 80.20054 -76.099122) (xy 80.309178 -76.21341) (xy 80.411889 -76.333054) (xy 80.508408 -76.457747)
			(xy 80.598488 -76.587168) (xy 80.681897 -76.720985) (xy 80.758421 -76.858855) (xy 80.827864 -77.000424)
			(xy 80.890048 -77.145329) (xy 80.944812 -77.293197) (xy 80.992017 -77.443649) (xy 81.03154 -77.596299)
			(xy 81.063282 -77.750755) (xy 81.08716 -77.90662) (xy 81.103112 -78.063495) (xy 81.111099 -78.220976)
			(xy 81.111099 -78.37866) (xy 81.103112 -78.536141) (xy 81.08716 -78.693016) (xy 81.063282 -78.848881)
			(xy 81.03154 -79.003337) (xy 80.992017 -79.155987) (xy 80.944812 -79.306439) (xy 80.890048 -79.454307)
			(xy 80.827864 -79.599212) (xy 80.758421 -79.740781) (xy 80.681897 -79.878651) (xy 80.598488 -80.012468)
			(xy 80.508408 -80.141889) (xy 80.411889 -80.266582) (xy 80.309178 -80.386226) (xy 80.20054 -80.500514)
			(xy 80.086252 -80.609152) (xy 79.966608 -80.711863) (xy 79.841915 -80.808382) (xy 79.712494 -80.898462)
			(xy 79.578677 -80.981871) (xy 79.440807 -81.058395) (xy 79.299238 -81.127838) (xy 79.154333 -81.190022)
			(xy 79.006465 -81.244786) (xy 78.856013 -81.291991) (xy 78.703363 -81.331514) (xy 78.548907 -81.363256)
			(xy 78.393042 -81.387134) (xy 78.236167 -81.403086) (xy 78.078686 -81.411073) (xy 77.921002 -81.411073)
			(xy 77.763521 -81.403086) (xy 77.606646 -81.387134) (xy 77.450781 -81.363256) (xy 77.296325 -81.331514)
			(xy 77.143675 -81.291991) (xy 76.993223 -81.244786) (xy 76.845355 -81.190022) (xy 76.70045 -81.127838)
			(xy 76.558881 -81.058395) (xy 76.421011 -80.981871) (xy 76.287194 -80.898462) (xy 76.157773 -80.808382)
			(xy 76.03308 -80.711863) (xy 75.913436 -80.609152) (xy 75.799148 -80.500514) (xy 75.69051 -80.386226)
			(xy 75.587799 -80.266582) (xy 75.49128 -80.141889) (xy 75.4012 -80.012468) (xy 75.317791 -79.878651)
			(xy 75.241267 -79.740781) (xy 75.171824 -79.599212) (xy 75.10964 -79.454307) (xy 75.054876 -79.306439)
			(xy 75.007671 -79.155987) (xy 74.968148 -79.003337) (xy 74.936406 -78.848881) (xy 74.912528 -78.693016)
			(xy 74.896576 -78.536141) (xy 74.888589 -78.37866) (xy 68.276876 -78.37866) (xy 60.882784 -85.772752)
			(xy 71.010778 -85.772752) (xy 71.014849 -85.71713) (xy 71.026975 -85.662693) (xy 71.046898 -85.610602)
			(xy 71.074194 -85.561967) (xy 71.10828 -85.517824) (xy 71.148429 -85.479115) (xy 71.193787 -85.446664)
			(xy 71.243387 -85.421163) (xy 71.296171 -85.403156) (xy 71.351014 -85.393026) (xy 71.406748 -85.390989)
			(xy 71.462185 -85.397089) (xy 71.516142 -85.411195) (xy 71.567471 -85.433007) (xy 71.615077 -85.462061)
			(xy 71.657945 -85.497736) (xy 71.695162 -85.539273) (xy 71.725935 -85.585786) (xy 71.749607 -85.636283)
			(xy 71.765675 -85.68969) (xy 71.773795 -85.744866) (xy 71.774304 -85.772752) (xy 72.138284 -85.772752)
			(xy 72.142355 -85.71713) (xy 72.154481 -85.662693) (xy 72.174404 -85.610602) (xy 72.2017 -85.561967)
			(xy 72.235786 -85.517824) (xy 72.275935 -85.479115) (xy 72.321293 -85.446664) (xy 72.370893 -85.421163)
			(xy 72.423677 -85.403156) (xy 72.47852 -85.393026) (xy 72.534254 -85.390989) (xy 72.589691 -85.397089)
			(xy 72.643648 -85.411195) (xy 72.694977 -85.433007) (xy 72.742583 -85.462061) (xy 72.785451 -85.497736)
			(xy 72.822668 -85.539273) (xy 72.853441 -85.585786) (xy 72.877113 -85.636283) (xy 72.893181 -85.68969)
			(xy 72.901301 -85.744866) (xy 72.90181 -85.772752) (xy 73.251312 -85.772752) (xy 73.255383 -85.71713)
			(xy 73.267509 -85.662693) (xy 73.287432 -85.610602) (xy 73.314728 -85.561967) (xy 73.348814 -85.517824)
			(xy 73.388963 -85.479115) (xy 73.434321 -85.446664) (xy 73.483921 -85.421163) (xy 73.536705 -85.403156)
			(xy 73.591548 -85.393026) (xy 73.647282 -85.390989) (xy 73.702719 -85.397089) (xy 73.756676 -85.411195)
			(xy 73.808005 -85.433007) (xy 73.855611 -85.462061) (xy 73.898479 -85.497736) (xy 73.935696 -85.539273)
			(xy 73.966469 -85.585786) (xy 73.990141 -85.636283) (xy 74.006209 -85.68969) (xy 74.014329 -85.744866)
			(xy 74.014838 -85.772752) (xy 74.422506 -85.772752) (xy 74.426577 -85.71713) (xy 74.438703 -85.662693)
			(xy 74.458626 -85.610602) (xy 74.485922 -85.561967) (xy 74.520008 -85.517824) (xy 74.560157 -85.479115)
			(xy 74.605515 -85.446664) (xy 74.655115 -85.421163) (xy 74.707899 -85.403156) (xy 74.762742 -85.393026)
			(xy 74.818476 -85.390989) (xy 74.873913 -85.397089) (xy 74.92787 -85.411195) (xy 74.979199 -85.433007)
			(xy 75.026805 -85.462061) (xy 75.069673 -85.497736) (xy 75.10689 -85.539273) (xy 75.137663 -85.585786)
			(xy 75.161335 -85.636283) (xy 75.177403 -85.68969) (xy 75.185523 -85.744866) (xy 75.186032 -85.772752)
			(xy 75.185523 -85.800638) (xy 75.177403 -85.855814) (xy 75.161335 -85.909221) (xy 75.137663 -85.959718)
			(xy 75.10689 -86.006231) (xy 75.069673 -86.047768) (xy 75.026805 -86.083443) (xy 74.979199 -86.112497)
			(xy 74.92787 -86.134309) (xy 74.873913 -86.148415) (xy 74.818476 -86.154515) (xy 74.762742 -86.152478)
			(xy 74.707899 -86.142348) (xy 74.655115 -86.124341) (xy 74.605515 -86.09884) (xy 74.560157 -86.066389)
			(xy 74.520008 -86.02768) (xy 74.485922 -85.983537) (xy 74.458626 -85.934902) (xy 74.438703 -85.882811)
			(xy 74.426577 -85.828374) (xy 74.422506 -85.772752) (xy 74.014838 -85.772752) (xy 74.014329 -85.800638)
			(xy 74.006209 -85.855814) (xy 73.990141 -85.909221) (xy 73.966469 -85.959718) (xy 73.935696 -86.006231)
			(xy 73.898479 -86.047768) (xy 73.855611 -86.083443) (xy 73.808005 -86.112497) (xy 73.756676 -86.134309)
			(xy 73.702719 -86.148415) (xy 73.647282 -86.154515) (xy 73.591548 -86.152478) (xy 73.536705 -86.142348)
			(xy 73.483921 -86.124341) (xy 73.434321 -86.09884) (xy 73.388963 -86.066389) (xy 73.348814 -86.02768)
			(xy 73.314728 -85.983537) (xy 73.287432 -85.934902) (xy 73.267509 -85.882811) (xy 73.255383 -85.828374)
			(xy 73.251312 -85.772752) (xy 72.90181 -85.772752) (xy 72.901301 -85.800638) (xy 72.893181 -85.855814)
			(xy 72.877113 -85.909221) (xy 72.853441 -85.959718) (xy 72.822668 -86.006231) (xy 72.785451 -86.047768)
			(xy 72.742583 -86.083443) (xy 72.694977 -86.112497) (xy 72.643648 -86.134309) (xy 72.589691 -86.148415)
			(xy 72.534254 -86.154515) (xy 72.47852 -86.152478) (xy 72.423677 -86.142348) (xy 72.370893 -86.124341)
			(xy 72.321293 -86.09884) (xy 72.275935 -86.066389) (xy 72.235786 -86.02768) (xy 72.2017 -85.983537)
			(xy 72.174404 -85.934902) (xy 72.154481 -85.882811) (xy 72.142355 -85.828374) (xy 72.138284 -85.772752)
			(xy 71.774304 -85.772752) (xy 71.773795 -85.800638) (xy 71.765675 -85.855814) (xy 71.749607 -85.909221)
			(xy 71.725935 -85.959718) (xy 71.695162 -86.006231) (xy 71.657945 -86.047768) (xy 71.615077 -86.083443)
			(xy 71.567471 -86.112497) (xy 71.516142 -86.134309) (xy 71.462185 -86.148415) (xy 71.406748 -86.154515)
			(xy 71.351014 -86.152478) (xy 71.296171 -86.142348) (xy 71.243387 -86.124341) (xy 71.193787 -86.09884)
			(xy 71.148429 -86.066389) (xy 71.10828 -86.02768) (xy 71.074194 -85.983537) (xy 71.046898 -85.934902)
			(xy 71.026975 -85.882811) (xy 71.014849 -85.828374) (xy 71.010778 -85.772752) (xy 60.882784 -85.772752)
			(xy 55.576724 -91.078812) (xy 31.095442 -91.078812) (xy 30.531562 -91.642692) (xy 30.515949 -91.659)
			(xy 30.490172 -91.696059) (xy 30.471348 -91.737089) (xy 30.460067 -91.7808) (xy 30.456685 -91.825816)
			(xy 30.461309 -91.870721) (xy 30.473793 -91.914103) (xy 30.493743 -91.954598) (xy 30.520534 -91.990931)
			(xy 30.553321 -92.021961) (xy 30.591075 -92.04671) (xy 30.632606 -92.064401) (xy 30.654498 -92.06992)
			(xy 30.697756 -92.079599) (xy 30.782372 -92.106037) (xy 30.864123 -92.140322) (xy 30.942284 -92.18215)
			(xy 31.016161 -92.231149) (xy 31.085099 -92.286884) (xy 31.148484 -92.34886) (xy 31.205754 -92.416528)
			(xy 31.256401 -92.489285) (xy 31.299975 -92.566486) (xy 31.336089 -92.647446) (xy 31.364423 -92.731446)
			(xy 31.384724 -92.81774) (xy 31.396813 -92.905561) (xy 31.400582 -92.994131) (xy 31.398551 -93.033358)
			(xy 34.599874 -93.033358) (xy 34.599874 -92.946458) (xy 34.607892 -92.859929) (xy 34.62386 -92.774509)
			(xy 34.647641 -92.690927) (xy 34.679033 -92.609895) (xy 34.717767 -92.532106) (xy 34.763514 -92.458222)
			(xy 34.815883 -92.388875) (xy 34.874427 -92.324655) (xy 34.938647 -92.266111) (xy 35.007994 -92.213742)
			(xy 35.081878 -92.167995) (xy 35.159667 -92.129261) (xy 35.240699 -92.097869) (xy 35.324281 -92.074088)
			(xy 35.409701 -92.05812) (xy 35.49623 -92.050102) (xy 35.58313 -92.050102) (xy 35.669659 -92.05812)
			(xy 35.755079 -92.074088) (xy 35.838661 -92.097869) (xy 35.919693 -92.129261) (xy 35.997482 -92.167995)
			(xy 36.071366 -92.213742) (xy 36.140713 -92.266111) (xy 36.204933 -92.324655) (xy 36.263477 -92.388875)
			(xy 36.315846 -92.458222) (xy 36.361593 -92.532106) (xy 36.400327 -92.609895) (xy 36.431719 -92.690927)
			(xy 36.4555 -92.774509) (xy 36.471468 -92.859929) (xy 36.479486 -92.946458) (xy 36.479988 -92.989908)
			(xy 36.479486 -93.033358) (xy 36.471468 -93.119887) (xy 36.4555 -93.205307) (xy 36.431719 -93.288889)
			(xy 36.400327 -93.369921) (xy 36.361593 -93.44771) (xy 36.315846 -93.521594) (xy 36.263477 -93.590941)
			(xy 36.204933 -93.655161) (xy 36.140713 -93.713705) (xy 36.071366 -93.766074) (xy 35.997482 -93.811821)
			(xy 35.919693 -93.850555) (xy 35.838661 -93.881947) (xy 35.755079 -93.905728) (xy 35.669659 -93.921696)
			(xy 35.58313 -93.929714) (xy 35.49623 -93.929714) (xy 35.409701 -93.921696) (xy 35.324281 -93.905728)
			(xy 35.240699 -93.881947) (xy 35.159667 -93.850555) (xy 35.081878 -93.811821) (xy 35.007994 -93.766074)
			(xy 34.938647 -93.713705) (xy 34.874427 -93.655161) (xy 34.815883 -93.590941) (xy 34.763514 -93.521594)
			(xy 34.717767 -93.44771) (xy 34.679033 -93.369921) (xy 34.647641 -93.288889) (xy 34.62386 -93.205307)
			(xy 34.607892 -93.119887) (xy 34.599874 -93.033358) (xy 31.398551 -93.033358) (xy 31.395998 -93.082662)
			(xy 31.383101 -93.170368) (xy 31.362006 -93.256471) (xy 31.3329 -93.340207) (xy 31.296043 -93.420831)
			(xy 31.25176 -93.497628) (xy 31.200445 -93.569916) (xy 31.171896 -93.603826) (xy 31.143548 -93.635984)
			(xy 31.081892 -93.695556) (xy 31.015069 -93.749269) (xy 30.943635 -93.796676) (xy 30.868183 -93.837384)
			(xy 30.789338 -93.871056) (xy 30.707755 -93.897411) (xy 30.624113 -93.916231) (xy 30.539105 -93.92736)
			(xy 30.453436 -93.930704) (xy 30.367819 -93.926237) (xy 30.282964 -93.913996) (xy 30.199575 -93.894082)
			(xy 30.118345 -93.86666) (xy 30.039948 -93.831959) (xy 29.965035 -93.790265) (xy 29.894228 -93.741926)
			(xy 29.828115 -93.687343) (xy 29.767245 -93.626968) (xy 29.739336 -93.594428) (xy 29.724908 -93.577951)
			(xy 29.691421 -93.549729) (xy 29.653593 -93.527663) (xy 29.612543 -93.512407) (xy 29.569486 -93.504411)
			(xy 29.525695 -93.503911) (xy 29.482467 -93.510924) (xy 29.44108 -93.525241) (xy 29.402759 -93.546439)
			(xy 29.368638 -93.573891) (xy 29.339725 -93.606784) (xy 29.316878 -93.644144) (xy 29.300771 -93.684868)
			(xy 29.291881 -93.72775) (xy 29.290772 -93.749622) (xy 29.290772 -94.770194) (xy 29.291928 -94.792065)
			(xy 29.300806 -94.83495) (xy 29.316903 -94.875679) (xy 29.339743 -94.913045) (xy 29.368651 -94.945943)
			(xy 29.402769 -94.973399) (xy 29.441089 -94.9946) (xy 29.482477 -95.008919) (xy 29.525706 -95.015932)
			(xy 29.569497 -95.015431) (xy 29.612554 -95.007431) (xy 29.653603 -94.992169) (xy 29.691428 -94.970097)
			(xy 29.724909 -94.941867) (xy 29.739336 -94.925388) (xy 29.767591 -94.892491) (xy 29.82922 -94.831474)
			(xy 29.896204 -94.77639) (xy 29.967976 -94.727708) (xy 30.043926 -94.685841) (xy 30.123407 -94.651144)
			(xy 30.205746 -94.623913) (xy 30.290242 -94.604379) (xy 30.376178 -94.592708) (xy 30.462823 -94.588999)
			(xy 30.549442 -94.593283) (xy 30.635298 -94.605525) (xy 30.719663 -94.625619) (xy 30.801819 -94.653396)
			(xy 30.881069 -94.68862) (xy 30.956739 -94.73099) (xy 31.028186 -94.780148) (xy 31.094803 -94.835675)
			(xy 31.156025 -94.8971) (xy 31.211331 -94.963901) (xy 31.260252 -95.035511) (xy 31.302372 -95.111321)
			(xy 31.337332 -95.190686) (xy 31.364837 -95.272934) (xy 31.384652 -95.357365) (xy 31.396609 -95.443261)
			(xy 31.400606 -95.529894) (xy 31.398601 -95.573358) (xy 34.599874 -95.573358) (xy 34.599874 -95.486458)
			(xy 34.607892 -95.399929) (xy 34.62386 -95.314509) (xy 34.647641 -95.230927) (xy 34.679033 -95.149895)
			(xy 34.717767 -95.072106) (xy 34.763514 -94.998222) (xy 34.815883 -94.928875) (xy 34.874427 -94.864655)
			(xy 34.938647 -94.806111) (xy 35.007994 -94.753742) (xy 35.081878 -94.707995) (xy 35.159667 -94.669261)
			(xy 35.240699 -94.637869) (xy 35.324281 -94.614088) (xy 35.409701 -94.59812) (xy 35.49623 -94.590102)
			(xy 35.58313 -94.590102) (xy 35.669659 -94.59812) (xy 35.755079 -94.614088) (xy 35.838661 -94.637869)
			(xy 35.919693 -94.669261) (xy 35.997482 -94.707995) (xy 36.071366 -94.753742) (xy 36.140713 -94.806111)
			(xy 36.204933 -94.864655) (xy 36.263477 -94.928875) (xy 36.315846 -94.998222) (xy 36.361593 -95.072106)
			(xy 36.400327 -95.149895) (xy 36.431719 -95.230927) (xy 36.4555 -95.314509) (xy 36.471468 -95.399929)
			(xy 36.479486 -95.486458) (xy 36.479988 -95.529908) (xy 36.479486 -95.573358) (xy 36.471468 -95.659887)
			(xy 36.4555 -95.745307) (xy 36.437073 -95.81007) (xy 39.818063 -95.81007) (xy 39.82207 -95.694046)
			(xy 39.834072 -95.578574) (xy 39.854012 -95.464206) (xy 39.881795 -95.351486) (xy 39.917289 -95.240952)
			(xy 39.960324 -95.133129) (xy 40.010695 -95.028532) (xy 40.068162 -94.92766) (xy 40.132452 -94.830993)
			(xy 40.203257 -94.738992) (xy 40.280241 -94.652095) (xy 40.363037 -94.570716) (xy 40.45125 -94.495243)
			(xy 40.54446 -94.426036) (xy 40.642223 -94.363424) (xy 40.744072 -94.307707) (xy 40.849522 -94.259149)
			(xy 40.958071 -94.217981) (xy 41.069202 -94.184401) (xy 41.182385 -94.158568) (xy 41.29708 -94.140605)
			(xy 41.412742 -94.130597) (xy 41.528818 -94.128594) (xy 41.644756 -94.134603) (xy 41.760003 -94.148596)
			(xy 41.874009 -94.170507) (xy 41.986233 -94.200232) (xy 42.096139 -94.237628) (xy 42.203202 -94.282517)
			(xy 42.306914 -94.334686) (xy 42.406779 -94.393886) (xy 42.502322 -94.459835) (xy 42.502604 -94.46006)
			(xy 43.327577 -94.46006) (xy 43.331612 -94.384356) (xy 43.343671 -94.309511) (xy 43.363617 -94.23637)
			(xy 43.391224 -94.165765) (xy 43.42618 -94.098494) (xy 43.468088 -94.035319) (xy 43.516474 -93.976957)
			(xy 43.57079 -93.924069) (xy 43.630419 -93.877254) (xy 43.694687 -93.837042) (xy 43.762864 -93.80389)
			(xy 43.83418 -93.778172) (xy 43.907825 -93.76018) (xy 43.982965 -93.750118) (xy 44.058749 -93.748099)
			(xy 44.134319 -93.754148) (xy 44.208817 -93.768195) (xy 44.2814 -93.790081) (xy 44.351246 -93.819558)
			(xy 44.417563 -93.856293) (xy 44.479599 -93.899868) (xy 44.536652 -93.94979) (xy 44.588076 -94.005494)
			(xy 44.633287 -94.066349) (xy 44.671774 -94.131664) (xy 44.7031 -94.2007) (xy 44.72691 -94.272675)
			(xy 44.742935 -94.346773) (xy 44.750994 -94.422154) (xy 44.751498 -94.46006) (xy 45.867577 -94.46006)
			(xy 45.871612 -94.384356) (xy 45.883671 -94.309511) (xy 45.903617 -94.23637) (xy 45.931224 -94.165765)
			(xy 45.96618 -94.098494) (xy 46.008088 -94.035319) (xy 46.056474 -93.976957) (xy 46.11079 -93.924069)
			(xy 46.170419 -93.877254) (xy 46.234687 -93.837042) (xy 46.302864 -93.80389) (xy 46.37418 -93.778172)
			(xy 46.447825 -93.76018) (xy 46.522965 -93.750118) (xy 46.598749 -93.748099) (xy 46.674319 -93.754148)
			(xy 46.748817 -93.768195) (xy 46.8214 -93.790081) (xy 46.891246 -93.819558) (xy 46.957563 -93.856293)
			(xy 47.019599 -93.899868) (xy 47.076652 -93.94979) (xy 47.128076 -94.005494) (xy 47.173287 -94.066349)
			(xy 47.211774 -94.131664) (xy 47.2431 -94.2007) (xy 47.26691 -94.272675) (xy 47.282935 -94.346773)
			(xy 47.290994 -94.422154) (xy 47.291498 -94.46006) (xy 48.407577 -94.46006) (xy 48.411612 -94.384356)
			(xy 48.423671 -94.309511) (xy 48.443617 -94.23637) (xy 48.471224 -94.165765) (xy 48.50618 -94.098494)
			(xy 48.548088 -94.035319) (xy 48.596474 -93.976957) (xy 48.65079 -93.924069) (xy 48.710419 -93.877254)
			(xy 48.774687 -93.837042) (xy 48.842864 -93.80389) (xy 48.91418 -93.778172) (xy 48.987825 -93.76018)
			(xy 49.062965 -93.750118) (xy 49.138749 -93.748099) (xy 49.214319 -93.754148) (xy 49.288817 -93.768195)
			(xy 49.3614 -93.790081) (xy 49.431246 -93.819558) (xy 49.497563 -93.856293) (xy 49.559599 -93.899868)
			(xy 49.616652 -93.94979) (xy 49.668076 -94.005494) (xy 49.713287 -94.066349) (xy 49.751774 -94.131664)
			(xy 49.7831 -94.2007) (xy 49.80691 -94.272675) (xy 49.822935 -94.346773) (xy 49.830994 -94.422154)
			(xy 49.831498 -94.46006) (xy 50.947577 -94.46006) (xy 50.951612 -94.384356) (xy 50.963671 -94.309511)
			(xy 50.983617 -94.23637) (xy 51.011224 -94.165765) (xy 51.04618 -94.098494) (xy 51.088088 -94.035319)
			(xy 51.136474 -93.976957) (xy 51.19079 -93.924069) (xy 51.250419 -93.877254) (xy 51.314687 -93.837042)
			(xy 51.382864 -93.80389) (xy 51.45418 -93.778172) (xy 51.527825 -93.76018) (xy 51.602965 -93.750118)
			(xy 51.678749 -93.748099) (xy 51.754319 -93.754148) (xy 51.828817 -93.768195) (xy 51.9014 -93.790081)
			(xy 51.971246 -93.819558) (xy 52.037563 -93.856293) (xy 52.099599 -93.899868) (xy 52.156652 -93.94979)
			(xy 52.208076 -94.005494) (xy 52.253287 -94.066349) (xy 52.291774 -94.131664) (xy 52.3231 -94.2007)
			(xy 52.34691 -94.272675) (xy 52.362935 -94.346773) (xy 52.370994 -94.422154) (xy 52.371498 -94.46006)
			(xy 53.487577 -94.46006) (xy 53.491612 -94.384356) (xy 53.503671 -94.309511) (xy 53.523617 -94.23637)
			(xy 53.551224 -94.165765) (xy 53.58618 -94.098494) (xy 53.628088 -94.035319) (xy 53.676474 -93.976957)
			(xy 53.73079 -93.924069) (xy 53.790419 -93.877254) (xy 53.854687 -93.837042) (xy 53.922864 -93.80389)
			(xy 53.99418 -93.778172) (xy 54.067825 -93.76018) (xy 54.142965 -93.750118) (xy 54.218749 -93.748099)
			(xy 54.294319 -93.754148) (xy 54.368817 -93.768195) (xy 54.4414 -93.790081) (xy 54.511246 -93.819558)
			(xy 54.577563 -93.856293) (xy 54.639599 -93.899868) (xy 54.696652 -93.94979) (xy 54.748076 -94.005494)
			(xy 54.793287 -94.066349) (xy 54.831774 -94.131664) (xy 54.8631 -94.2007) (xy 54.88691 -94.272675)
			(xy 54.902935 -94.346773) (xy 54.910994 -94.422154) (xy 54.911498 -94.46006) (xy 56.027577 -94.46006)
			(xy 56.031612 -94.384356) (xy 56.043671 -94.309511) (xy 56.063617 -94.23637) (xy 56.091224 -94.165765)
			(xy 56.12618 -94.098494) (xy 56.168088 -94.035319) (xy 56.216474 -93.976957) (xy 56.27079 -93.924069)
			(xy 56.330419 -93.877254) (xy 56.394687 -93.837042) (xy 56.462864 -93.80389) (xy 56.53418 -93.778172)
			(xy 56.607825 -93.76018) (xy 56.682965 -93.750118) (xy 56.758749 -93.748099) (xy 56.834319 -93.754148)
			(xy 56.908817 -93.768195) (xy 56.9814 -93.790081) (xy 57.051246 -93.819558) (xy 57.117563 -93.856293)
			(xy 57.179599 -93.899868) (xy 57.236652 -93.94979) (xy 57.288076 -94.005494) (xy 57.333287 -94.066349)
			(xy 57.371774 -94.131664) (xy 57.4031 -94.2007) (xy 57.42691 -94.272675) (xy 57.442935 -94.346773)
			(xy 57.450994 -94.422154) (xy 57.451498 -94.46006) (xy 58.567577 -94.46006) (xy 58.571612 -94.384356)
			(xy 58.583671 -94.309511) (xy 58.603617 -94.23637) (xy 58.631224 -94.165765) (xy 58.66618 -94.098494)
			(xy 58.708088 -94.035319) (xy 58.756474 -93.976957) (xy 58.81079 -93.924069) (xy 58.870419 -93.877254)
			(xy 58.934687 -93.837042) (xy 59.002864 -93.80389) (xy 59.07418 -93.778172) (xy 59.147825 -93.76018)
			(xy 59.222965 -93.750118) (xy 59.298749 -93.748099) (xy 59.374319 -93.754148) (xy 59.448817 -93.768195)
			(xy 59.5214 -93.790081) (xy 59.591246 -93.819558) (xy 59.657563 -93.856293) (xy 59.719599 -93.899868)
			(xy 59.776652 -93.94979) (xy 59.828076 -94.005494) (xy 59.873287 -94.066349) (xy 59.911774 -94.131664)
			(xy 59.9431 -94.2007) (xy 59.96691 -94.272675) (xy 59.982935 -94.346773) (xy 59.990994 -94.422154)
			(xy 59.991498 -94.46006) (xy 61.107577 -94.46006) (xy 61.111612 -94.384356) (xy 61.123671 -94.309511)
			(xy 61.143617 -94.23637) (xy 61.171224 -94.165765) (xy 61.20618 -94.098494) (xy 61.248088 -94.035319)
			(xy 61.296474 -93.976957) (xy 61.35079 -93.924069) (xy 61.410419 -93.877254) (xy 61.474687 -93.837042)
			(xy 61.542864 -93.80389) (xy 61.61418 -93.778172) (xy 61.687825 -93.76018) (xy 61.762965 -93.750118)
			(xy 61.838749 -93.748099) (xy 61.914319 -93.754148) (xy 61.988817 -93.768195) (xy 62.0614 -93.790081)
			(xy 62.131246 -93.819558) (xy 62.197563 -93.856293) (xy 62.259599 -93.899868) (xy 62.316652 -93.94979)
			(xy 62.368076 -94.005494) (xy 62.413287 -94.066349) (xy 62.451774 -94.131664) (xy 62.4831 -94.2007)
			(xy 62.50691 -94.272675) (xy 62.522935 -94.346773) (xy 62.530994 -94.422154) (xy 62.531498 -94.46006)
			(xy 62.530994 -94.497966) (xy 62.522935 -94.573347) (xy 62.50691 -94.647445) (xy 62.4831 -94.71942)
			(xy 62.451774 -94.788456) (xy 62.413287 -94.853771) (xy 62.368076 -94.914626) (xy 62.316652 -94.97033)
			(xy 62.259599 -95.020252) (xy 62.197563 -95.063827) (xy 62.131246 -95.100562) (xy 62.0614 -95.130039)
			(xy 61.988817 -95.151925) (xy 61.914319 -95.165972) (xy 61.838749 -95.172021) (xy 61.762965 -95.170002)
			(xy 61.687825 -95.15994) (xy 61.61418 -95.141948) (xy 61.542864 -95.11623) (xy 61.474687 -95.083078)
			(xy 61.410419 -95.042866) (xy 61.35079 -94.996051) (xy 61.296474 -94.943163) (xy 61.248088 -94.884801)
			(xy 61.20618 -94.821626) (xy 61.171224 -94.754355) (xy 61.143617 -94.68375) (xy 61.123671 -94.610609)
			(xy 61.111612 -94.535764) (xy 61.107577 -94.46006) (xy 59.991498 -94.46006) (xy 59.990994 -94.497966)
			(xy 59.982935 -94.573347) (xy 59.96691 -94.647445) (xy 59.9431 -94.71942) (xy 59.911774 -94.788456)
			(xy 59.873287 -94.853771) (xy 59.828076 -94.914626) (xy 59.776652 -94.97033) (xy 59.719599 -95.020252)
			(xy 59.657563 -95.063827) (xy 59.591246 -95.100562) (xy 59.5214 -95.130039) (xy 59.448817 -95.151925)
			(xy 59.374319 -95.165972) (xy 59.298749 -95.172021) (xy 59.222965 -95.170002) (xy 59.147825 -95.15994)
			(xy 59.07418 -95.141948) (xy 59.002864 -95.11623) (xy 58.934687 -95.083078) (xy 58.870419 -95.042866)
			(xy 58.81079 -94.996051) (xy 58.756474 -94.943163) (xy 58.708088 -94.884801) (xy 58.66618 -94.821626)
			(xy 58.631224 -94.754355) (xy 58.603617 -94.68375) (xy 58.583671 -94.610609) (xy 58.571612 -94.535764)
			(xy 58.567577 -94.46006) (xy 57.451498 -94.46006) (xy 57.450994 -94.497966) (xy 57.442935 -94.573347)
			(xy 57.42691 -94.647445) (xy 57.4031 -94.71942) (xy 57.371774 -94.788456) (xy 57.333287 -94.853771)
			(xy 57.288076 -94.914626) (xy 57.236652 -94.97033) (xy 57.179599 -95.020252) (xy 57.117563 -95.063827)
			(xy 57.051246 -95.100562) (xy 56.9814 -95.130039) (xy 56.908817 -95.151925) (xy 56.834319 -95.165972)
			(xy 56.758749 -95.172021) (xy 56.682965 -95.170002) (xy 56.607825 -95.15994) (xy 56.53418 -95.141948)
			(xy 56.462864 -95.11623) (xy 56.394687 -95.083078) (xy 56.330419 -95.042866) (xy 56.27079 -94.996051)
			(xy 56.216474 -94.943163) (xy 56.168088 -94.884801) (xy 56.12618 -94.821626) (xy 56.091224 -94.754355)
			(xy 56.063617 -94.68375) (xy 56.043671 -94.610609) (xy 56.031612 -94.535764) (xy 56.027577 -94.46006)
			(xy 54.911498 -94.46006) (xy 54.910994 -94.497966) (xy 54.902935 -94.573347) (xy 54.88691 -94.647445)
			(xy 54.8631 -94.71942) (xy 54.831774 -94.788456) (xy 54.793287 -94.853771) (xy 54.748076 -94.914626)
			(xy 54.696652 -94.97033) (xy 54.639599 -95.020252) (xy 54.577563 -95.063827) (xy 54.511246 -95.100562)
			(xy 54.4414 -95.130039) (xy 54.368817 -95.151925) (xy 54.294319 -95.165972) (xy 54.218749 -95.172021)
			(xy 54.142965 -95.170002) (xy 54.067825 -95.15994) (xy 53.99418 -95.141948) (xy 53.922864 -95.11623)
			(xy 53.854687 -95.083078) (xy 53.790419 -95.042866) (xy 53.73079 -94.996051) (xy 53.676474 -94.943163)
			(xy 53.628088 -94.884801) (xy 53.58618 -94.821626) (xy 53.551224 -94.754355) (xy 53.523617 -94.68375)
			(xy 53.503671 -94.610609) (xy 53.491612 -94.535764) (xy 53.487577 -94.46006) (xy 52.371498 -94.46006)
			(xy 52.370994 -94.497966) (xy 52.362935 -94.573347) (xy 52.34691 -94.647445) (xy 52.3231 -94.71942)
			(xy 52.291774 -94.788456) (xy 52.253287 -94.853771) (xy 52.208076 -94.914626) (xy 52.156652 -94.97033)
			(xy 52.099599 -95.020252) (xy 52.037563 -95.063827) (xy 51.971246 -95.100562) (xy 51.9014 -95.130039)
			(xy 51.828817 -95.151925) (xy 51.754319 -95.165972) (xy 51.678749 -95.172021) (xy 51.602965 -95.170002)
			(xy 51.527825 -95.15994) (xy 51.45418 -95.141948) (xy 51.382864 -95.11623) (xy 51.314687 -95.083078)
			(xy 51.250419 -95.042866) (xy 51.19079 -94.996051) (xy 51.136474 -94.943163) (xy 51.088088 -94.884801)
			(xy 51.04618 -94.821626) (xy 51.011224 -94.754355) (xy 50.983617 -94.68375) (xy 50.963671 -94.610609)
			(xy 50.951612 -94.535764) (xy 50.947577 -94.46006) (xy 49.831498 -94.46006) (xy 49.830994 -94.497966)
			(xy 49.822935 -94.573347) (xy 49.80691 -94.647445) (xy 49.7831 -94.71942) (xy 49.751774 -94.788456)
			(xy 49.713287 -94.853771) (xy 49.668076 -94.914626) (xy 49.616652 -94.97033) (xy 49.559599 -95.020252)
			(xy 49.497563 -95.063827) (xy 49.431246 -95.100562) (xy 49.3614 -95.130039) (xy 49.288817 -95.151925)
			(xy 49.214319 -95.165972) (xy 49.138749 -95.172021) (xy 49.062965 -95.170002) (xy 48.987825 -95.15994)
			(xy 48.91418 -95.141948) (xy 48.842864 -95.11623) (xy 48.774687 -95.083078) (xy 48.710419 -95.042866)
			(xy 48.65079 -94.996051) (xy 48.596474 -94.943163) (xy 48.548088 -94.884801) (xy 48.50618 -94.821626)
			(xy 48.471224 -94.754355) (xy 48.443617 -94.68375) (xy 48.423671 -94.610609) (xy 48.411612 -94.535764)
			(xy 48.407577 -94.46006) (xy 47.291498 -94.46006) (xy 47.290994 -94.497966) (xy 47.282935 -94.573347)
			(xy 47.26691 -94.647445) (xy 47.2431 -94.71942) (xy 47.211774 -94.788456) (xy 47.173287 -94.853771)
			(xy 47.128076 -94.914626) (xy 47.076652 -94.97033) (xy 47.019599 -95.020252) (xy 46.957563 -95.063827)
			(xy 46.891246 -95.100562) (xy 46.8214 -95.130039) (xy 46.748817 -95.151925) (xy 46.674319 -95.165972)
			(xy 46.598749 -95.172021) (xy 46.522965 -95.170002) (xy 46.447825 -95.15994) (xy 46.37418 -95.141948)
			(xy 46.302864 -95.11623) (xy 46.234687 -95.083078) (xy 46.170419 -95.042866) (xy 46.11079 -94.996051)
			(xy 46.056474 -94.943163) (xy 46.008088 -94.884801) (xy 45.96618 -94.821626) (xy 45.931224 -94.754355)
			(xy 45.903617 -94.68375) (xy 45.883671 -94.610609) (xy 45.871612 -94.535764) (xy 45.867577 -94.46006)
			(xy 44.751498 -94.46006) (xy 44.750994 -94.497966) (xy 44.742935 -94.573347) (xy 44.72691 -94.647445)
			(xy 44.7031 -94.71942) (xy 44.671774 -94.788456) (xy 44.633287 -94.853771) (xy 44.588076 -94.914626)
			(xy 44.536652 -94.97033) (xy 44.479599 -95.020252) (xy 44.417563 -95.063827) (xy 44.351246 -95.100562)
			(xy 44.2814 -95.130039) (xy 44.208817 -95.151925) (xy 44.134319 -95.165972) (xy 44.058749 -95.172021)
			(xy 43.982965 -95.170002) (xy 43.907825 -95.15994) (xy 43.83418 -95.141948) (xy 43.762864 -95.11623)
			(xy 43.694687 -95.083078) (xy 43.630419 -95.042866) (xy 43.57079 -94.996051) (xy 43.516474 -94.943163)
			(xy 43.468088 -94.884801) (xy 43.42618 -94.821626) (xy 43.391224 -94.754355) (xy 43.363617 -94.68375)
			(xy 43.343671 -94.610609) (xy 43.331612 -94.535764) (xy 43.327577 -94.46006) (xy 42.502604 -94.46006)
			(xy 42.593088 -94.532218) (xy 42.678643 -94.610691) (xy 42.758581 -94.694879) (xy 42.83252 -94.784381)
			(xy 42.900108 -94.878772) (xy 42.961022 -94.9776) (xy 43.014974 -95.080396) (xy 43.061704 -95.186669)
			(xy 43.100992 -95.295913) (xy 43.132649 -95.407606) (xy 43.156525 -95.521218) (xy 43.172506 -95.636206)
			(xy 43.180515 -95.752023) (xy 43.181016 -95.81007) (xy 43.180515 -95.868117) (xy 43.172506 -95.983934)
			(xy 43.156525 -96.098922) (xy 43.132649 -96.212534) (xy 43.100992 -96.324227) (xy 43.061704 -96.433471)
			(xy 43.014974 -96.539744) (xy 42.961022 -96.64254) (xy 42.900108 -96.741368) (xy 42.83252 -96.835759)
			(xy 42.758581 -96.925261) (xy 42.678643 -97.009449) (xy 42.593088 -97.087922) (xy 42.502604 -97.16008)
			(xy 43.327577 -97.16008) (xy 43.331612 -97.084376) (xy 43.343671 -97.009531) (xy 43.363617 -96.93639)
			(xy 43.391224 -96.865785) (xy 43.42618 -96.798514) (xy 43.468088 -96.735339) (xy 43.516474 -96.676977)
			(xy 43.57079 -96.624089) (xy 43.630419 -96.577274) (xy 43.694687 -96.537062) (xy 43.762864 -96.50391)
			(xy 43.83418 -96.478192) (xy 43.907825 -96.4602) (xy 43.982965 -96.450138) (xy 44.058749 -96.448119)
			(xy 44.134319 -96.454168) (xy 44.208817 -96.468215) (xy 44.2814 -96.490101) (xy 44.351246 -96.519578)
			(xy 44.417563 -96.556313) (xy 44.479599 -96.599888) (xy 44.536652 -96.64981) (xy 44.588076 -96.705514)
			(xy 44.633287 -96.766369) (xy 44.671774 -96.831684) (xy 44.7031 -96.90072) (xy 44.72691 -96.972695)
			(xy 44.742935 -97.046793) (xy 44.750994 -97.122174) (xy 44.751498 -97.16008) (xy 45.867577 -97.16008)
			(xy 45.871612 -97.084376) (xy 45.883671 -97.009531) (xy 45.903617 -96.93639) (xy 45.931224 -96.865785)
			(xy 45.96618 -96.798514) (xy 46.008088 -96.735339) (xy 46.056474 -96.676977) (xy 46.11079 -96.624089)
			(xy 46.170419 -96.577274) (xy 46.234687 -96.537062) (xy 46.302864 -96.50391) (xy 46.37418 -96.478192)
			(xy 46.447825 -96.4602) (xy 46.522965 -96.450138) (xy 46.598749 -96.448119) (xy 46.674319 -96.454168)
			(xy 46.748817 -96.468215) (xy 46.8214 -96.490101) (xy 46.891246 -96.519578) (xy 46.957563 -96.556313)
			(xy 47.019599 -96.599888) (xy 47.076652 -96.64981) (xy 47.128076 -96.705514) (xy 47.173287 -96.766369)
			(xy 47.211774 -96.831684) (xy 47.2431 -96.90072) (xy 47.26691 -96.972695) (xy 47.282935 -97.046793)
			(xy 47.290994 -97.122174) (xy 47.291498 -97.16008) (xy 48.407577 -97.16008) (xy 48.411612 -97.084376)
			(xy 48.423671 -97.009531) (xy 48.443617 -96.93639) (xy 48.471224 -96.865785) (xy 48.50618 -96.798514)
			(xy 48.548088 -96.735339) (xy 48.596474 -96.676977) (xy 48.65079 -96.624089) (xy 48.710419 -96.577274)
			(xy 48.774687 -96.537062) (xy 48.842864 -96.50391) (xy 48.91418 -96.478192) (xy 48.987825 -96.4602)
			(xy 49.062965 -96.450138) (xy 49.138749 -96.448119) (xy 49.214319 -96.454168) (xy 49.288817 -96.468215)
			(xy 49.3614 -96.490101) (xy 49.431246 -96.519578) (xy 49.497563 -96.556313) (xy 49.559599 -96.599888)
			(xy 49.616652 -96.64981) (xy 49.668076 -96.705514) (xy 49.713287 -96.766369) (xy 49.751774 -96.831684)
			(xy 49.7831 -96.90072) (xy 49.80691 -96.972695) (xy 49.822935 -97.046793) (xy 49.830994 -97.122174)
			(xy 49.831498 -97.16008) (xy 50.947577 -97.16008) (xy 50.951612 -97.084376) (xy 50.963671 -97.009531)
			(xy 50.983617 -96.93639) (xy 51.011224 -96.865785) (xy 51.04618 -96.798514) (xy 51.088088 -96.735339)
			(xy 51.136474 -96.676977) (xy 51.19079 -96.624089) (xy 51.250419 -96.577274) (xy 51.314687 -96.537062)
			(xy 51.382864 -96.50391) (xy 51.45418 -96.478192) (xy 51.527825 -96.4602) (xy 51.602965 -96.450138)
			(xy 51.678749 -96.448119) (xy 51.754319 -96.454168) (xy 51.828817 -96.468215) (xy 51.9014 -96.490101)
			(xy 51.971246 -96.519578) (xy 52.037563 -96.556313) (xy 52.099599 -96.599888) (xy 52.156652 -96.64981)
			(xy 52.208076 -96.705514) (xy 52.253287 -96.766369) (xy 52.291774 -96.831684) (xy 52.3231 -96.90072)
			(xy 52.34691 -96.972695) (xy 52.362935 -97.046793) (xy 52.370994 -97.122174) (xy 52.371498 -97.16008)
			(xy 53.487577 -97.16008) (xy 53.491612 -97.084376) (xy 53.503671 -97.009531) (xy 53.523617 -96.93639)
			(xy 53.551224 -96.865785) (xy 53.58618 -96.798514) (xy 53.628088 -96.735339) (xy 53.676474 -96.676977)
			(xy 53.73079 -96.624089) (xy 53.790419 -96.577274) (xy 53.854687 -96.537062) (xy 53.922864 -96.50391)
			(xy 53.99418 -96.478192) (xy 54.067825 -96.4602) (xy 54.142965 -96.450138) (xy 54.218749 -96.448119)
			(xy 54.294319 -96.454168) (xy 54.368817 -96.468215) (xy 54.4414 -96.490101) (xy 54.511246 -96.519578)
			(xy 54.577563 -96.556313) (xy 54.639599 -96.599888) (xy 54.696652 -96.64981) (xy 54.748076 -96.705514)
			(xy 54.793287 -96.766369) (xy 54.831774 -96.831684) (xy 54.8631 -96.90072) (xy 54.88691 -96.972695)
			(xy 54.902935 -97.046793) (xy 54.910994 -97.122174) (xy 54.911498 -97.16008) (xy 56.027577 -97.16008)
			(xy 56.031612 -97.084376) (xy 56.043671 -97.009531) (xy 56.063617 -96.93639) (xy 56.091224 -96.865785)
			(xy 56.12618 -96.798514) (xy 56.168088 -96.735339) (xy 56.216474 -96.676977) (xy 56.27079 -96.624089)
			(xy 56.330419 -96.577274) (xy 56.394687 -96.537062) (xy 56.462864 -96.50391) (xy 56.53418 -96.478192)
			(xy 56.607825 -96.4602) (xy 56.682965 -96.450138) (xy 56.758749 -96.448119) (xy 56.834319 -96.454168)
			(xy 56.908817 -96.468215) (xy 56.9814 -96.490101) (xy 57.051246 -96.519578) (xy 57.117563 -96.556313)
			(xy 57.179599 -96.599888) (xy 57.236652 -96.64981) (xy 57.288076 -96.705514) (xy 57.333287 -96.766369)
			(xy 57.371774 -96.831684) (xy 57.4031 -96.90072) (xy 57.42691 -96.972695) (xy 57.442935 -97.046793)
			(xy 57.450994 -97.122174) (xy 57.451498 -97.16008) (xy 58.567577 -97.16008) (xy 58.571612 -97.084376)
			(xy 58.583671 -97.009531) (xy 58.603617 -96.93639) (xy 58.631224 -96.865785) (xy 58.66618 -96.798514)
			(xy 58.708088 -96.735339) (xy 58.756474 -96.676977) (xy 58.81079 -96.624089) (xy 58.870419 -96.577274)
			(xy 58.934687 -96.537062) (xy 59.002864 -96.50391) (xy 59.07418 -96.478192) (xy 59.147825 -96.4602)
			(xy 59.222965 -96.450138) (xy 59.298749 -96.448119) (xy 59.374319 -96.454168) (xy 59.448817 -96.468215)
			(xy 59.5214 -96.490101) (xy 59.591246 -96.519578) (xy 59.657563 -96.556313) (xy 59.719599 -96.599888)
			(xy 59.776652 -96.64981) (xy 59.828076 -96.705514) (xy 59.873287 -96.766369) (xy 59.911774 -96.831684)
			(xy 59.9431 -96.90072) (xy 59.96691 -96.972695) (xy 59.982935 -97.046793) (xy 59.990994 -97.122174)
			(xy 59.991498 -97.16008) (xy 61.107577 -97.16008) (xy 61.111612 -97.084376) (xy 61.123671 -97.009531)
			(xy 61.143617 -96.93639) (xy 61.171224 -96.865785) (xy 61.20618 -96.798514) (xy 61.248088 -96.735339)
			(xy 61.296474 -96.676977) (xy 61.35079 -96.624089) (xy 61.410419 -96.577274) (xy 61.474687 -96.537062)
			(xy 61.542864 -96.50391) (xy 61.61418 -96.478192) (xy 61.687825 -96.4602) (xy 61.762965 -96.450138)
			(xy 61.838749 -96.448119) (xy 61.914319 -96.454168) (xy 61.988817 -96.468215) (xy 62.0614 -96.490101)
			(xy 62.131246 -96.519578) (xy 62.197563 -96.556313) (xy 62.259599 -96.599888) (xy 62.316652 -96.64981)
			(xy 62.368076 -96.705514) (xy 62.413287 -96.766369) (xy 62.451774 -96.831684) (xy 62.4831 -96.90072)
			(xy 62.50691 -96.972695) (xy 62.522935 -97.046793) (xy 62.530994 -97.122174) (xy 62.531498 -97.16008)
			(xy 62.530994 -97.197986) (xy 62.522935 -97.273367) (xy 62.50691 -97.347465) (xy 62.4831 -97.41944)
			(xy 62.451774 -97.488476) (xy 62.413287 -97.553791) (xy 62.368076 -97.614646) (xy 62.316652 -97.67035)
			(xy 62.259599 -97.720272) (xy 62.197563 -97.763847) (xy 62.131246 -97.800582) (xy 62.0614 -97.830059)
			(xy 61.988817 -97.851945) (xy 61.914319 -97.865992) (xy 61.838749 -97.872041) (xy 61.762965 -97.870022)
			(xy 61.687825 -97.85996) (xy 61.61418 -97.841968) (xy 61.542864 -97.81625) (xy 61.474687 -97.783098)
			(xy 61.410419 -97.742886) (xy 61.35079 -97.696071) (xy 61.296474 -97.643183) (xy 61.248088 -97.584821)
			(xy 61.20618 -97.521646) (xy 61.171224 -97.454375) (xy 61.143617 -97.38377) (xy 61.123671 -97.310629)
			(xy 61.111612 -97.235784) (xy 61.107577 -97.16008) (xy 59.991498 -97.16008) (xy 59.990994 -97.197986)
			(xy 59.982935 -97.273367) (xy 59.96691 -97.347465) (xy 59.9431 -97.41944) (xy 59.911774 -97.488476)
			(xy 59.873287 -97.553791) (xy 59.828076 -97.614646) (xy 59.776652 -97.67035) (xy 59.719599 -97.720272)
			(xy 59.657563 -97.763847) (xy 59.591246 -97.800582) (xy 59.5214 -97.830059) (xy 59.448817 -97.851945)
			(xy 59.374319 -97.865992) (xy 59.298749 -97.872041) (xy 59.222965 -97.870022) (xy 59.147825 -97.85996)
			(xy 59.07418 -97.841968) (xy 59.002864 -97.81625) (xy 58.934687 -97.783098) (xy 58.870419 -97.742886)
			(xy 58.81079 -97.696071) (xy 58.756474 -97.643183) (xy 58.708088 -97.584821) (xy 58.66618 -97.521646)
			(xy 58.631224 -97.454375) (xy 58.603617 -97.38377) (xy 58.583671 -97.310629) (xy 58.571612 -97.235784)
			(xy 58.567577 -97.16008) (xy 57.451498 -97.16008) (xy 57.450994 -97.197986) (xy 57.442935 -97.273367)
			(xy 57.42691 -97.347465) (xy 57.4031 -97.41944) (xy 57.371774 -97.488476) (xy 57.333287 -97.553791)
			(xy 57.288076 -97.614646) (xy 57.236652 -97.67035) (xy 57.179599 -97.720272) (xy 57.117563 -97.763847)
			(xy 57.051246 -97.800582) (xy 56.9814 -97.830059) (xy 56.908817 -97.851945) (xy 56.834319 -97.865992)
			(xy 56.758749 -97.872041) (xy 56.682965 -97.870022) (xy 56.607825 -97.85996) (xy 56.53418 -97.841968)
			(xy 56.462864 -97.81625) (xy 56.394687 -97.783098) (xy 56.330419 -97.742886) (xy 56.27079 -97.696071)
			(xy 56.216474 -97.643183) (xy 56.168088 -97.584821) (xy 56.12618 -97.521646) (xy 56.091224 -97.454375)
			(xy 56.063617 -97.38377) (xy 56.043671 -97.310629) (xy 56.031612 -97.235784) (xy 56.027577 -97.16008)
			(xy 54.911498 -97.16008) (xy 54.910994 -97.197986) (xy 54.902935 -97.273367) (xy 54.88691 -97.347465)
			(xy 54.8631 -97.41944) (xy 54.831774 -97.488476) (xy 54.793287 -97.553791) (xy 54.748076 -97.614646)
			(xy 54.696652 -97.67035) (xy 54.639599 -97.720272) (xy 54.577563 -97.763847) (xy 54.511246 -97.800582)
			(xy 54.4414 -97.830059) (xy 54.368817 -97.851945) (xy 54.294319 -97.865992) (xy 54.218749 -97.872041)
			(xy 54.142965 -97.870022) (xy 54.067825 -97.85996) (xy 53.99418 -97.841968) (xy 53.922864 -97.81625)
			(xy 53.854687 -97.783098) (xy 53.790419 -97.742886) (xy 53.73079 -97.696071) (xy 53.676474 -97.643183)
			(xy 53.628088 -97.584821) (xy 53.58618 -97.521646) (xy 53.551224 -97.454375) (xy 53.523617 -97.38377)
			(xy 53.503671 -97.310629) (xy 53.491612 -97.235784) (xy 53.487577 -97.16008) (xy 52.371498 -97.16008)
			(xy 52.370994 -97.197986) (xy 52.362935 -97.273367) (xy 52.34691 -97.347465) (xy 52.3231 -97.41944)
			(xy 52.291774 -97.488476) (xy 52.253287 -97.553791) (xy 52.208076 -97.614646) (xy 52.156652 -97.67035)
			(xy 52.099599 -97.720272) (xy 52.037563 -97.763847) (xy 51.971246 -97.800582) (xy 51.9014 -97.830059)
			(xy 51.828817 -97.851945) (xy 51.754319 -97.865992) (xy 51.678749 -97.872041) (xy 51.602965 -97.870022)
			(xy 51.527825 -97.85996) (xy 51.45418 -97.841968) (xy 51.382864 -97.81625) (xy 51.314687 -97.783098)
			(xy 51.250419 -97.742886) (xy 51.19079 -97.696071) (xy 51.136474 -97.643183) (xy 51.088088 -97.584821)
			(xy 51.04618 -97.521646) (xy 51.011224 -97.454375) (xy 50.983617 -97.38377) (xy 50.963671 -97.310629)
			(xy 50.951612 -97.235784) (xy 50.947577 -97.16008) (xy 49.831498 -97.16008) (xy 49.830994 -97.197986)
			(xy 49.822935 -97.273367) (xy 49.80691 -97.347465) (xy 49.7831 -97.41944) (xy 49.751774 -97.488476)
			(xy 49.713287 -97.553791) (xy 49.668076 -97.614646) (xy 49.616652 -97.67035) (xy 49.559599 -97.720272)
			(xy 49.497563 -97.763847) (xy 49.431246 -97.800582) (xy 49.3614 -97.830059) (xy 49.288817 -97.851945)
			(xy 49.214319 -97.865992) (xy 49.138749 -97.872041) (xy 49.062965 -97.870022) (xy 48.987825 -97.85996)
			(xy 48.91418 -97.841968) (xy 48.842864 -97.81625) (xy 48.774687 -97.783098) (xy 48.710419 -97.742886)
			(xy 48.65079 -97.696071) (xy 48.596474 -97.643183) (xy 48.548088 -97.584821) (xy 48.50618 -97.521646)
			(xy 48.471224 -97.454375) (xy 48.443617 -97.38377) (xy 48.423671 -97.310629) (xy 48.411612 -97.235784)
			(xy 48.407577 -97.16008) (xy 47.291498 -97.16008) (xy 47.290994 -97.197986) (xy 47.282935 -97.273367)
			(xy 47.26691 -97.347465) (xy 47.2431 -97.41944) (xy 47.211774 -97.488476) (xy 47.173287 -97.553791)
			(xy 47.128076 -97.614646) (xy 47.076652 -97.67035) (xy 47.019599 -97.720272) (xy 46.957563 -97.763847)
			(xy 46.891246 -97.800582) (xy 46.8214 -97.830059) (xy 46.748817 -97.851945) (xy 46.674319 -97.865992)
			(xy 46.598749 -97.872041) (xy 46.522965 -97.870022) (xy 46.447825 -97.85996) (xy 46.37418 -97.841968)
			(xy 46.302864 -97.81625) (xy 46.234687 -97.783098) (xy 46.170419 -97.742886) (xy 46.11079 -97.696071)
			(xy 46.056474 -97.643183) (xy 46.008088 -97.584821) (xy 45.96618 -97.521646) (xy 45.931224 -97.454375)
			(xy 45.903617 -97.38377) (xy 45.883671 -97.310629) (xy 45.871612 -97.235784) (xy 45.867577 -97.16008)
			(xy 44.751498 -97.16008) (xy 44.750994 -97.197986) (xy 44.742935 -97.273367) (xy 44.72691 -97.347465)
			(xy 44.7031 -97.41944) (xy 44.671774 -97.488476) (xy 44.633287 -97.553791) (xy 44.588076 -97.614646)
			(xy 44.536652 -97.67035) (xy 44.479599 -97.720272) (xy 44.417563 -97.763847) (xy 44.351246 -97.800582)
			(xy 44.2814 -97.830059) (xy 44.208817 -97.851945) (xy 44.134319 -97.865992) (xy 44.058749 -97.872041)
			(xy 43.982965 -97.870022) (xy 43.907825 -97.85996) (xy 43.83418 -97.841968) (xy 43.762864 -97.81625)
			(xy 43.694687 -97.783098) (xy 43.630419 -97.742886) (xy 43.57079 -97.696071) (xy 43.516474 -97.643183)
			(xy 43.468088 -97.584821) (xy 43.42618 -97.521646) (xy 43.391224 -97.454375) (xy 43.363617 -97.38377)
			(xy 43.343671 -97.310629) (xy 43.331612 -97.235784) (xy 43.327577 -97.16008) (xy 42.502604 -97.16008)
			(xy 42.502322 -97.160305) (xy 42.406779 -97.226254) (xy 42.306914 -97.285454) (xy 42.203202 -97.337623)
			(xy 42.096139 -97.382512) (xy 41.986233 -97.419908) (xy 41.874009 -97.449633) (xy 41.760003 -97.471544)
			(xy 41.644756 -97.485537) (xy 41.528818 -97.491546) (xy 41.412742 -97.489543) (xy 41.29708 -97.479535)
			(xy 41.182385 -97.461572) (xy 41.069202 -97.435739) (xy 40.958071 -97.402159) (xy 40.849522 -97.360991)
			(xy 40.744072 -97.312433) (xy 40.642223 -97.256716) (xy 40.54446 -97.194104) (xy 40.45125 -97.124897)
			(xy 40.363037 -97.049424) (xy 40.280241 -96.968045) (xy 40.203257 -96.881148) (xy 40.132452 -96.789147)
			(xy 40.068162 -96.69248) (xy 40.010695 -96.591608) (xy 39.960324 -96.487011) (xy 39.917289 -96.379188)
			(xy 39.881795 -96.268654) (xy 39.854012 -96.155934) (xy 39.834072 -96.041566) (xy 39.82207 -95.926094)
			(xy 39.818063 -95.81007) (xy 36.437073 -95.81007) (xy 36.431719 -95.828889) (xy 36.400327 -95.909921)
			(xy 36.361593 -95.98771) (xy 36.315846 -96.061594) (xy 36.263477 -96.130941) (xy 36.204933 -96.195161)
			(xy 36.140713 -96.253705) (xy 36.071366 -96.306074) (xy 35.997482 -96.351821) (xy 35.919693 -96.390555)
			(xy 35.838661 -96.421947) (xy 35.755079 -96.445728) (xy 35.669659 -96.461696) (xy 35.58313 -96.469714)
			(xy 35.49623 -96.469714) (xy 35.409701 -96.461696) (xy 35.324281 -96.445728) (xy 35.240699 -96.421947)
			(xy 35.159667 -96.390555) (xy 35.081878 -96.351821) (xy 35.007994 -96.306074) (xy 34.938647 -96.253705)
			(xy 34.874427 -96.195161) (xy 34.815883 -96.130941) (xy 34.763514 -96.061594) (xy 34.717767 -95.98771)
			(xy 34.679033 -95.909921) (xy 34.647641 -95.828889) (xy 34.62386 -95.745307) (xy 34.607892 -95.659887)
			(xy 34.599874 -95.573358) (xy 31.398601 -95.573358) (xy 31.39661 -95.616526) (xy 31.384654 -95.702423)
			(xy 31.36484 -95.786854) (xy 31.337337 -95.869102) (xy 31.302377 -95.948468) (xy 31.260259 -96.024279)
			(xy 31.211339 -96.095889) (xy 31.156033 -96.162691) (xy 31.094812 -96.224117) (xy 31.028195 -96.279645)
			(xy 30.956749 -96.328803) (xy 30.88108 -96.371175) (xy 30.801831 -96.406399) (xy 30.719675 -96.434177)
			(xy 30.635311 -96.454273) (xy 30.549454 -96.466515) (xy 30.462835 -96.470801) (xy 30.37619 -96.467093)
			(xy 30.290254 -96.455423) (xy 30.205758 -96.43589) (xy 30.123419 -96.40866) (xy 30.043937 -96.373965)
			(xy 29.967987 -96.332098) (xy 29.896214 -96.283417) (xy 29.829229 -96.228334) (xy 29.767599 -96.167318)
			(xy 29.739336 -96.134428) (xy 29.724908 -96.117951) (xy 29.691421 -96.089729) (xy 29.653593 -96.067663)
			(xy 29.612543 -96.052407) (xy 29.569486 -96.044411) (xy 29.525695 -96.043911) (xy 29.482467 -96.050924)
			(xy 29.44108 -96.065241) (xy 29.402759 -96.086439) (xy 29.368638 -96.113891) (xy 29.339725 -96.146784)
			(xy 29.316878 -96.184144) (xy 29.300771 -96.224868) (xy 29.291881 -96.26775) (xy 29.290772 -96.289622)
			(xy 29.290772 -97.310194) (xy 29.291928 -97.332065) (xy 29.300806 -97.37495) (xy 29.316903 -97.415679)
			(xy 29.339743 -97.453045) (xy 29.368651 -97.485943) (xy 29.402769 -97.513399) (xy 29.441089 -97.5346)
			(xy 29.482477 -97.548919) (xy 29.525706 -97.555932) (xy 29.569497 -97.555431) (xy 29.612554 -97.547431)
			(xy 29.653603 -97.532169) (xy 29.691428 -97.510097) (xy 29.724909 -97.481867) (xy 29.739336 -97.465388)
			(xy 29.767591 -97.432491) (xy 29.82922 -97.371474) (xy 29.896204 -97.31639) (xy 29.967976 -97.267708)
			(xy 30.043926 -97.225841) (xy 30.123407 -97.191144) (xy 30.205746 -97.163913) (xy 30.290242 -97.144379)
			(xy 30.376178 -97.132708) (xy 30.462823 -97.128999) (xy 30.549442 -97.133283) (xy 30.635298 -97.145525)
			(xy 30.719663 -97.165619) (xy 30.801819 -97.193396) (xy 30.881069 -97.22862) (xy 30.956739 -97.27099)
			(xy 31.028186 -97.320148) (xy 31.094803 -97.375675) (xy 31.156025 -97.4371) (xy 31.211331 -97.503901)
			(xy 31.260252 -97.575511) (xy 31.302372 -97.651321) (xy 31.337332 -97.730686) (xy 31.364837 -97.812934)
			(xy 31.384652 -97.897365) (xy 31.396609 -97.983261) (xy 31.400606 -98.069894) (xy 31.398601 -98.113358)
			(xy 34.599874 -98.113358) (xy 34.599874 -98.026458) (xy 34.607892 -97.939929) (xy 34.62386 -97.854509)
			(xy 34.647641 -97.770927) (xy 34.679033 -97.689895) (xy 34.717767 -97.612106) (xy 34.763514 -97.538222)
			(xy 34.815883 -97.468875) (xy 34.874427 -97.404655) (xy 34.938647 -97.346111) (xy 35.007994 -97.293742)
			(xy 35.081878 -97.247995) (xy 35.159667 -97.209261) (xy 35.240699 -97.177869) (xy 35.324281 -97.154088)
			(xy 35.409701 -97.13812) (xy 35.49623 -97.130102) (xy 35.58313 -97.130102) (xy 35.669659 -97.13812)
			(xy 35.755079 -97.154088) (xy 35.838661 -97.177869) (xy 35.919693 -97.209261) (xy 35.997482 -97.247995)
			(xy 36.071366 -97.293742) (xy 36.140713 -97.346111) (xy 36.204933 -97.404655) (xy 36.263477 -97.468875)
			(xy 36.315846 -97.538222) (xy 36.361593 -97.612106) (xy 36.400327 -97.689895) (xy 36.431719 -97.770927)
			(xy 36.4555 -97.854509) (xy 36.471468 -97.939929) (xy 36.479486 -98.026458) (xy 36.479988 -98.069908)
			(xy 36.479486 -98.113358) (xy 36.471468 -98.199887) (xy 36.4555 -98.285307) (xy 36.431719 -98.368889)
			(xy 36.400327 -98.449921) (xy 36.361593 -98.52771) (xy 36.315846 -98.601594) (xy 36.263477 -98.670941)
			(xy 36.204933 -98.735161) (xy 36.140713 -98.793705) (xy 36.071366 -98.846074) (xy 35.997482 -98.891821)
			(xy 35.919693 -98.930555) (xy 35.838661 -98.961947) (xy 35.755079 -98.985728) (xy 35.669659 -99.001696)
			(xy 35.58313 -99.009714) (xy 35.49623 -99.009714) (xy 35.409701 -99.001696) (xy 35.324281 -98.985728)
			(xy 35.240699 -98.961947) (xy 35.159667 -98.930555) (xy 35.081878 -98.891821) (xy 35.007994 -98.846074)
			(xy 34.938647 -98.793705) (xy 34.874427 -98.735161) (xy 34.815883 -98.670941) (xy 34.763514 -98.601594)
			(xy 34.717767 -98.52771) (xy 34.679033 -98.449921) (xy 34.647641 -98.368889) (xy 34.62386 -98.285307)
			(xy 34.607892 -98.199887) (xy 34.599874 -98.113358) (xy 31.398601 -98.113358) (xy 31.39661 -98.156526)
			(xy 31.384654 -98.242423) (xy 31.36484 -98.326854) (xy 31.337337 -98.409102) (xy 31.302377 -98.488468)
			(xy 31.260259 -98.564279) (xy 31.211339 -98.635889) (xy 31.156033 -98.702691) (xy 31.094812 -98.764117)
			(xy 31.028195 -98.819645) (xy 30.956749 -98.868803) (xy 30.88108 -98.911175) (xy 30.801831 -98.946399)
			(xy 30.719675 -98.974177) (xy 30.635311 -98.994273) (xy 30.549454 -99.006515) (xy 30.462835 -99.010801)
			(xy 30.37619 -99.007093) (xy 30.290254 -98.995423) (xy 30.205758 -98.97589) (xy 30.123419 -98.94866)
			(xy 30.043937 -98.913965) (xy 29.967987 -98.872098) (xy 29.896214 -98.823417) (xy 29.829229 -98.768334)
			(xy 29.767599 -98.707318) (xy 29.739336 -98.674428) (xy 29.724908 -98.657951) (xy 29.691421 -98.629729)
			(xy 29.653593 -98.607663) (xy 29.612543 -98.592407) (xy 29.569486 -98.584411) (xy 29.525695 -98.583911)
			(xy 29.482467 -98.590924) (xy 29.44108 -98.605241) (xy 29.402759 -98.626439) (xy 29.368638 -98.653891)
			(xy 29.339725 -98.686784) (xy 29.316878 -98.724144) (xy 29.300771 -98.764868) (xy 29.291881 -98.80775)
			(xy 29.290772 -98.829622) (xy 29.290772 -100.07346) (xy 29.253942 -100.11029) (xy 29.242504 -100.12241)
			(xy 29.225829 -100.151251) (xy 29.217195 -100.183428) (xy 29.217191 -100.216743) (xy 29.225818 -100.248921)
			(xy 29.242486 -100.277767) (xy 29.253942 -100.289868) (xy 29.265118 -100.301044) (xy 29.27858 -100.309172)
			(xy 29.296846 -100.320474) (xy 29.330967 -100.346568) (xy 29.346652 -100.361242) (xy 29.354272 -100.368862)
			(xy 29.366069 -100.38011) (xy 29.394082 -100.396754) (xy 29.425395 -100.405771) (xy 29.45797 -100.406572)
			(xy 29.489688 -100.399107) (xy 29.518486 -100.383861) (xy 29.542491 -100.361825) (xy 29.560139 -100.334434)
			(xy 29.5656 -100.319078) (xy 29.579735 -100.277284) (xy 29.614789 -100.196313) (xy 29.657274 -100.118982)
			(xy 29.706817 -100.045972) (xy 29.762982 -99.977924) (xy 29.825275 -99.915436) (xy 29.893148 -99.859059)
			(xy 29.966004 -99.809289) (xy 30.043202 -99.766563) (xy 30.124063 -99.731256) (xy 30.207876 -99.70368)
			(xy 30.293904 -99.684077) (xy 30.38139 -99.67262) (xy 30.469565 -99.669409) (xy 30.557653 -99.674472)
			(xy 30.644879 -99.687765) (xy 30.730476 -99.709172) (xy 30.813691 -99.738503) (xy 30.893792 -99.7755)
			(xy 30.970075 -99.819839) (xy 31.041869 -99.87113) (xy 31.108543 -99.92892) (xy 31.169509 -99.992703)
			(xy 31.224232 -100.061916) (xy 31.27223 -100.135952) (xy 31.313081 -100.214158) (xy 31.346426 -100.295848)
			(xy 31.371971 -100.380302) (xy 31.389493 -100.466778) (xy 31.394654 -100.510594) (xy 31.398763 -100.55391)
			(xy 31.399919 -100.640918) (xy 31.398931 -100.653358) (xy 34.599874 -100.653358) (xy 34.599874 -100.566458)
			(xy 34.607892 -100.479929) (xy 34.62386 -100.394509) (xy 34.647641 -100.310927) (xy 34.679033 -100.229895)
			(xy 34.717767 -100.152106) (xy 34.763514 -100.078222) (xy 34.815883 -100.008875) (xy 34.874427 -99.944655)
			(xy 34.938647 -99.886111) (xy 35.007994 -99.833742) (xy 35.081878 -99.787995) (xy 35.159667 -99.749261)
			(xy 35.240699 -99.717869) (xy 35.324281 -99.694088) (xy 35.409701 -99.67812) (xy 35.49623 -99.670102)
			(xy 35.58313 -99.670102) (xy 35.669659 -99.67812) (xy 35.755079 -99.694088) (xy 35.838661 -99.717869)
			(xy 35.919693 -99.749261) (xy 35.997482 -99.787995) (xy 36.071366 -99.833742) (xy 36.140713 -99.886111)
			(xy 36.204933 -99.944655) (xy 36.263477 -100.008875) (xy 36.315846 -100.078222) (xy 36.361593 -100.152106)
			(xy 36.400327 -100.229895) (xy 36.431719 -100.310927) (xy 36.4555 -100.394509) (xy 36.471468 -100.479929)
			(xy 36.479486 -100.566458) (xy 36.479988 -100.609908) (xy 36.479486 -100.653358) (xy 36.471468 -100.739887)
			(xy 36.4555 -100.825307) (xy 36.431719 -100.908889) (xy 36.400327 -100.989921) (xy 36.361593 -101.06771)
			(xy 36.315846 -101.141594) (xy 36.263477 -101.210941) (xy 36.204933 -101.275161) (xy 36.140713 -101.333705)
			(xy 36.071366 -101.386074) (xy 35.997482 -101.431821) (xy 35.919693 -101.470555) (xy 35.838661 -101.501947)
			(xy 35.755079 -101.525728) (xy 35.669659 -101.541696) (xy 35.58313 -101.549714) (xy 35.49623 -101.549714)
			(xy 35.409701 -101.541696) (xy 35.324281 -101.525728) (xy 35.240699 -101.501947) (xy 35.159667 -101.470555)
			(xy 35.081878 -101.431821) (xy 35.007994 -101.386074) (xy 34.938647 -101.333705) (xy 34.874427 -101.275161)
			(xy 34.815883 -101.210941) (xy 34.763514 -101.141594) (xy 34.717767 -101.06771) (xy 34.679033 -100.989921)
			(xy 34.647641 -100.908889) (xy 34.62386 -100.825307) (xy 34.607892 -100.739887) (xy 34.599874 -100.653358)
			(xy 31.398931 -100.653358) (xy 31.393031 -100.727661) (xy 31.378159 -100.813397) (xy 31.355429 -100.897391)
			(xy 31.325037 -100.978927) (xy 31.287241 -101.057306) (xy 31.242365 -101.131857) (xy 31.190794 -101.201944)
			(xy 31.132968 -101.266966) (xy 31.069382 -101.326368) (xy 31.00058 -101.379641) (xy 30.927151 -101.42633)
			(xy 30.849721 -101.466035) (xy 30.768955 -101.498416) (xy 30.685542 -101.523197) (xy 30.600197 -101.540165)
			(xy 30.513649 -101.549176) (xy 30.426639 -101.550152) (xy 30.339911 -101.543086) (xy 30.254206 -101.528036)
			(xy 30.170258 -101.505133) (xy 30.088786 -101.474572) (xy 30.010485 -101.436615) (xy 29.936027 -101.391585)
			(xy 29.866047 -101.339869) (xy 29.833316 -101.311202) (xy 29.825188 -101.303836) (xy 29.808158 -101.289039)
			(xy 29.769927 -101.265096) (xy 29.728069 -101.248279) (xy 29.683899 -101.239117) (xy 29.638806 -101.237898)
			(xy 29.594205 -101.244659) (xy 29.551499 -101.259189) (xy 29.51203 -101.281031) (xy 29.477037 -101.309498)
			(xy 29.44762 -101.343697) (xy 29.424703 -101.382552) (xy 29.409007 -101.424843) (xy 29.401024 -101.469241)
			(xy 29.4005 -101.491796) (xy 29.4005 -101.906578) (xy 39.461692 -101.906578) (xy 39.465763 -101.850956)
			(xy 39.477889 -101.796519) (xy 39.497812 -101.744428) (xy 39.525108 -101.695793) (xy 39.559194 -101.65165)
			(xy 39.599343 -101.612941) (xy 39.644701 -101.58049) (xy 39.694301 -101.554989) (xy 39.747085 -101.536982)
			(xy 39.801928 -101.526852) (xy 39.857662 -101.524815) (xy 39.913099 -101.530915) (xy 39.967056 -101.545021)
			(xy 40.018385 -101.566833) (xy 40.065991 -101.595887) (xy 40.108859 -101.631562) (xy 40.146076 -101.673099)
			(xy 40.176849 -101.719612) (xy 40.200521 -101.770109) (xy 40.216589 -101.823516) (xy 40.224709 -101.878692)
			(xy 40.225218 -101.906578) (xy 40.224709 -101.934464) (xy 40.216589 -101.98964) (xy 40.200521 -102.043047)
			(xy 40.176849 -102.093544) (xy 40.146076 -102.140057) (xy 40.108859 -102.181594) (xy 40.065991 -102.217269)
			(xy 40.018385 -102.246323) (xy 39.967056 -102.268135) (xy 39.913099 -102.282241) (xy 39.857662 -102.288341)
			(xy 39.801928 -102.286304) (xy 39.747085 -102.276174) (xy 39.694301 -102.258167) (xy 39.644701 -102.232666)
			(xy 39.599343 -102.200215) (xy 39.559194 -102.161506) (xy 39.525108 -102.117363) (xy 39.497812 -102.068728)
			(xy 39.477889 -102.016637) (xy 39.465763 -101.9622) (xy 39.461692 -101.906578) (xy 29.4005 -101.906578)
			(xy 29.4005 -102.26802) (xy 29.400982 -102.290583) (xy 29.408941 -102.335002) (xy 29.424622 -102.377316)
			(xy 29.447532 -102.416194) (xy 29.476951 -102.450413) (xy 29.511953 -102.478895) (xy 29.551436 -102.500746)
			(xy 29.594158 -102.515278) (xy 29.638776 -102.522033) (xy 29.683885 -102.520799) (xy 29.728067 -102.511614)
			(xy 29.769931 -102.494769) (xy 29.80816 -102.470792) (xy 29.825188 -102.45598) (xy 29.857603 -102.427001)
			(xy 29.926919 -102.374498) (xy 30.000786 -102.328619) (xy 30.078574 -102.289757) (xy 30.159617 -102.258242)
			(xy 30.243224 -102.234344) (xy 30.328681 -102.218268) (xy 30.415256 -102.210151) (xy 30.502211 -102.210061)
			(xy 30.588803 -102.218001) (xy 30.674293 -102.233901) (xy 30.757949 -102.257627) (xy 30.839057 -102.288975)
			(xy 30.916924 -102.327677) (xy 30.990885 -102.373404) (xy 31.060309 -102.425764) (xy 31.124602 -102.48431)
			(xy 31.183214 -102.548543) (xy 31.235646 -102.617912) (xy 31.281449 -102.691826) (xy 31.320233 -102.769653)
			(xy 31.351664 -102.850729) (xy 31.375477 -102.93436) (xy 31.391465 -103.019833) (xy 31.399494 -103.106417)
			(xy 31.399495 -103.193358) (xy 34.599874 -103.193358) (xy 34.599874 -103.106458) (xy 34.607892 -103.019929)
			(xy 34.62386 -102.934509) (xy 34.647641 -102.850927) (xy 34.679033 -102.769895) (xy 34.717767 -102.692106)
			(xy 34.763514 -102.618222) (xy 34.815883 -102.548875) (xy 34.874427 -102.484655) (xy 34.938647 -102.426111)
			(xy 35.007994 -102.373742) (xy 35.081878 -102.327995) (xy 35.159667 -102.289261) (xy 35.240699 -102.257869)
			(xy 35.324281 -102.234088) (xy 35.409701 -102.21812) (xy 35.49623 -102.210102) (xy 35.58313 -102.210102)
			(xy 35.669659 -102.21812) (xy 35.755079 -102.234088) (xy 35.838661 -102.257869) (xy 35.919693 -102.289261)
			(xy 35.997482 -102.327995) (xy 36.071366 -102.373742) (xy 36.140713 -102.426111) (xy 36.204933 -102.484655)
			(xy 36.263477 -102.548875) (xy 36.315846 -102.618222) (xy 36.361593 -102.692106) (xy 36.400327 -102.769895)
			(xy 36.431719 -102.850927) (xy 36.4555 -102.934509) (xy 36.471468 -103.019929) (xy 36.479486 -103.106458)
			(xy 36.479988 -103.149908) (xy 36.479486 -103.193358) (xy 36.471468 -103.279887) (xy 36.4555 -103.365307)
			(xy 36.431719 -103.448889) (xy 36.402601 -103.52405) (xy 40.60774 -103.52405) (xy 40.611811 -103.468428)
			(xy 40.623937 -103.413991) (xy 40.64386 -103.3619) (xy 40.671156 -103.313265) (xy 40.705242 -103.269122)
			(xy 40.745391 -103.230413) (xy 40.790749 -103.197962) (xy 40.840349 -103.172461) (xy 40.893133 -103.154454)
			(xy 40.947976 -103.144324) (xy 41.00371 -103.142287) (xy 41.059147 -103.148387) (xy 41.113104 -103.162493)
			(xy 41.164433 -103.184305) (xy 41.212039 -103.213359) (xy 41.254907 -103.249034) (xy 41.292124 -103.290571)
			(xy 41.322897 -103.337084) (xy 41.346569 -103.387581) (xy 41.362637 -103.440988) (xy 41.370757 -103.496164)
			(xy 41.371266 -103.52405) (xy 41.370757 -103.551936) (xy 41.362637 -103.607112) (xy 41.346569 -103.660519)
			(xy 41.322897 -103.711016) (xy 41.292124 -103.757529) (xy 41.254907 -103.799066) (xy 41.212039 -103.834741)
			(xy 41.164433 -103.863795) (xy 41.113104 -103.885607) (xy 41.059147 -103.899713) (xy 41.00371 -103.905813)
			(xy 40.947976 -103.903776) (xy 40.893133 -103.893646) (xy 40.840349 -103.875639) (xy 40.790749 -103.850138)
			(xy 40.745391 -103.817687) (xy 40.705242 -103.778978) (xy 40.671156 -103.734835) (xy 40.64386 -103.6862)
			(xy 40.623937 -103.634109) (xy 40.611811 -103.579672) (xy 40.60774 -103.52405) (xy 36.402601 -103.52405)
			(xy 36.400327 -103.529921) (xy 36.361593 -103.60771) (xy 36.315846 -103.681594) (xy 36.263477 -103.750941)
			(xy 36.204933 -103.815161) (xy 36.140713 -103.873705) (xy 36.071366 -103.926074) (xy 35.997482 -103.971821)
			(xy 35.919693 -104.010555) (xy 35.838661 -104.041947) (xy 35.755079 -104.065728) (xy 35.669659 -104.081696)
			(xy 35.58313 -104.089714) (xy 35.49623 -104.089714) (xy 35.409701 -104.081696) (xy 35.324281 -104.065728)
			(xy 35.240699 -104.041947) (xy 35.159667 -104.010555) (xy 35.081878 -103.971821) (xy 35.007994 -103.926074)
			(xy 34.938647 -103.873705) (xy 34.874427 -103.815161) (xy 34.815883 -103.750941) (xy 34.763514 -103.681594)
			(xy 34.717767 -103.60771) (xy 34.679033 -103.529921) (xy 34.647641 -103.448889) (xy 34.62386 -103.365307)
			(xy 34.607892 -103.279887) (xy 34.599874 -103.193358) (xy 31.399495 -103.193358) (xy 31.399495 -103.193372)
			(xy 31.391467 -103.279956) (xy 31.375479 -103.365429) (xy 31.351668 -103.449061) (xy 31.320237 -103.530137)
			(xy 31.281455 -103.607964) (xy 31.235652 -103.681879) (xy 31.183221 -103.751249) (xy 31.124609 -103.815482)
			(xy 31.060317 -103.874029) (xy 30.990894 -103.92639) (xy 30.916933 -103.972117) (xy 30.839067 -104.010821)
			(xy 30.757959 -104.04217) (xy 30.674303 -104.065896) (xy 30.588814 -104.081798) (xy 30.502222 -104.089738)
			(xy 30.415267 -104.08965) (xy 30.328691 -104.081533) (xy 30.243235 -104.065458) (xy 30.159628 -104.041562)
			(xy 30.078584 -104.010048) (xy 30.000796 -103.971186) (xy 29.926928 -103.925308) (xy 29.857612 -103.872806)
			(xy 29.825188 -103.843836) (xy 29.808158 -103.829039) (xy 29.769927 -103.805096) (xy 29.728069 -103.788279)
			(xy 29.683899 -103.779117) (xy 29.638806 -103.777898) (xy 29.594205 -103.784659) (xy 29.551499 -103.799189)
			(xy 29.51203 -103.821031) (xy 29.477037 -103.849498) (xy 29.44762 -103.883697) (xy 29.424703 -103.922552)
			(xy 29.409007 -103.964843) (xy 29.401024 -104.009241) (xy 29.4005 -104.031796) (xy 29.4005 -104.648762)
			(xy 29.734764 -104.983026) (xy 29.831792 -104.988106) (xy 29.869638 -104.957626) (xy 29.903826 -104.930702)
			(xy 29.976343 -104.882588) (xy 30.052996 -104.841379) (xy 30.133129 -104.80743) (xy 30.216055 -104.78103)
			(xy 30.301067 -104.762405) (xy 30.387435 -104.751715) (xy 30.474422 -104.749051) (xy 30.561283 -104.754436)
			(xy 30.647274 -104.767823) (xy 30.731661 -104.789099) (xy 30.813721 -104.818081) (xy 30.892752 -104.854521)
			(xy 30.968078 -104.898107) (xy 31.039054 -104.948468) (xy 31.105074 -105.00517) (xy 31.165572 -105.067731)
			(xy 31.220031 -105.135613) (xy 31.267984 -105.208237) (xy 31.309022 -105.284982) (xy 31.342793 -105.36519)
			(xy 31.369009 -105.448175) (xy 31.387445 -105.533227) (xy 31.39313 -105.57637) (xy 31.397845 -105.619101)
			(xy 31.400393 -105.705038) (xy 31.398642 -105.733358) (xy 34.599874 -105.733358) (xy 34.599874 -105.646458)
			(xy 34.607892 -105.559929) (xy 34.62386 -105.474509) (xy 34.647641 -105.390927) (xy 34.679033 -105.309895)
			(xy 34.717767 -105.232106) (xy 34.763514 -105.158222) (xy 34.815883 -105.088875) (xy 34.874427 -105.024655)
			(xy 34.938647 -104.966111) (xy 35.007994 -104.913742) (xy 35.081878 -104.867995) (xy 35.159667 -104.829261)
			(xy 35.240699 -104.797869) (xy 35.324281 -104.774088) (xy 35.409701 -104.75812) (xy 35.49623 -104.750102)
			(xy 35.58313 -104.750102) (xy 35.669659 -104.75812) (xy 35.755079 -104.774088) (xy 35.838661 -104.797869)
			(xy 35.919693 -104.829261) (xy 35.997482 -104.867995) (xy 36.071366 -104.913742) (xy 36.140713 -104.966111)
			(xy 36.204933 -105.024655) (xy 36.263477 -105.088875) (xy 36.315846 -105.158222) (xy 36.361593 -105.232106)
			(xy 36.400327 -105.309895) (xy 36.431719 -105.390927) (xy 36.4555 -105.474509) (xy 36.471468 -105.559929)
			(xy 36.479486 -105.646458) (xy 36.479988 -105.689908) (xy 36.479486 -105.733358) (xy 36.471468 -105.819887)
			(xy 36.4555 -105.905307) (xy 36.431719 -105.988889) (xy 36.400327 -106.069921) (xy 36.369228 -106.132376)
			(xy 72.430892 -106.132376) (xy 72.434963 -106.076754) (xy 72.447089 -106.022317) (xy 72.467012 -105.970226)
			(xy 72.494308 -105.921591) (xy 72.528394 -105.877448) (xy 72.568543 -105.838739) (xy 72.613901 -105.806288)
			(xy 72.663501 -105.780787) (xy 72.716285 -105.76278) (xy 72.771128 -105.75265) (xy 72.826862 -105.750613)
			(xy 72.882299 -105.756713) (xy 72.936256 -105.770819) (xy 72.987585 -105.792631) (xy 73.035191 -105.821685)
			(xy 73.078059 -105.85736) (xy 73.115276 -105.898897) (xy 73.146049 -105.94541) (xy 73.169721 -105.995907)
			(xy 73.185789 -106.049314) (xy 73.193909 -106.10449) (xy 73.194418 -106.132376) (xy 73.53249 -106.132376)
			(xy 73.536561 -106.076754) (xy 73.548687 -106.022317) (xy 73.56861 -105.970226) (xy 73.595906 -105.921591)
			(xy 73.629992 -105.877448) (xy 73.670141 -105.838739) (xy 73.715499 -105.806288) (xy 73.765099 -105.780787)
			(xy 73.817883 -105.76278) (xy 73.872726 -105.75265) (xy 73.92846 -105.750613) (xy 73.983897 -105.756713)
			(xy 74.037854 -105.770819) (xy 74.089183 -105.792631) (xy 74.136789 -105.821685) (xy 74.179657 -105.85736)
			(xy 74.216874 -105.898897) (xy 74.247647 -105.94541) (xy 74.271319 -105.995907) (xy 74.287387 -106.049314)
			(xy 74.295507 -106.10449) (xy 74.296016 -106.132376) (xy 74.295507 -106.160262) (xy 74.287387 -106.215438)
			(xy 74.271319 -106.268845) (xy 74.247647 -106.319342) (xy 74.216874 -106.365855) (xy 74.179657 -106.407392)
			(xy 74.136789 -106.443067) (xy 74.089183 -106.472121) (xy 74.037854 -106.493933) (xy 73.983897 -106.508039)
			(xy 73.92846 -106.514139) (xy 73.872726 -106.512102) (xy 73.817883 -106.501972) (xy 73.765099 -106.483965)
			(xy 73.715499 -106.458464) (xy 73.670141 -106.426013) (xy 73.629992 -106.387304) (xy 73.595906 -106.343161)
			(xy 73.56861 -106.294526) (xy 73.548687 -106.242435) (xy 73.536561 -106.187998) (xy 73.53249 -106.132376)
			(xy 73.194418 -106.132376) (xy 73.193909 -106.160262) (xy 73.185789 -106.215438) (xy 73.169721 -106.268845)
			(xy 73.146049 -106.319342) (xy 73.115276 -106.365855) (xy 73.078059 -106.407392) (xy 73.035191 -106.443067)
			(xy 72.987585 -106.472121) (xy 72.936256 -106.493933) (xy 72.882299 -106.508039) (xy 72.826862 -106.514139)
			(xy 72.771128 -106.512102) (xy 72.716285 -106.501972) (xy 72.663501 -106.483965) (xy 72.613901 -106.458464)
			(xy 72.568543 -106.426013) (xy 72.528394 -106.387304) (xy 72.494308 -106.343161) (xy 72.467012 -106.294526)
			(xy 72.447089 -106.242435) (xy 72.434963 -106.187998) (xy 72.430892 -106.132376) (xy 36.369228 -106.132376)
			(xy 36.361593 -106.14771) (xy 36.315846 -106.221594) (xy 36.263477 -106.290941) (xy 36.204933 -106.355161)
			(xy 36.140713 -106.413705) (xy 36.071366 -106.466074) (xy 35.997482 -106.511821) (xy 35.919693 -106.550555)
			(xy 35.838661 -106.581947) (xy 35.755079 -106.605728) (xy 35.669659 -106.621696) (xy 35.58313 -106.629714)
			(xy 35.49623 -106.629714) (xy 35.409701 -106.621696) (xy 35.324281 -106.605728) (xy 35.240699 -106.581947)
			(xy 35.159667 -106.550555) (xy 35.081878 -106.511821) (xy 35.007994 -106.466074) (xy 34.938647 -106.413705)
			(xy 34.874427 -106.355161) (xy 34.815883 -106.290941) (xy 34.763514 -106.221594) (xy 34.717767 -106.14771)
			(xy 34.679033 -106.069921) (xy 34.647641 -105.988889) (xy 34.62386 -105.905307) (xy 34.607892 -105.819887)
			(xy 34.599874 -105.733358) (xy 31.398642 -105.733358) (xy 31.395086 -105.790849) (xy 31.381967 -105.875817)
			(xy 31.361146 -105.959233) (xy 31.332797 -106.040399) (xy 31.297156 -106.118639) (xy 31.254522 -106.193298)
			(xy 31.205249 -106.263753) (xy 31.149751 -106.329416) (xy 31.088489 -106.389738) (xy 31.021977 -106.444216)
			(xy 30.950769 -106.492393) (xy 30.87546 -106.533869) (xy 30.796679 -106.568297) (xy 30.715084 -106.595389)
			(xy 30.631357 -106.614919) (xy 30.546196 -106.626724) (xy 30.460314 -106.630705) (xy 30.374426 -106.626828)
			(xy 30.289251 -106.615128) (xy 30.2055 -106.5957) (xy 30.123872 -106.568707) (xy 30.084268 -106.551984)
			(xy 30.063448 -106.543735) (xy 30.019769 -106.533864) (xy 29.975036 -106.531798) (xy 29.930634 -106.5376)
			(xy 29.887934 -106.551092) (xy 29.848258 -106.571855) (xy 29.812834 -106.599247) (xy 29.782756 -106.632422)
			(xy 29.758954 -106.670353) (xy 29.742166 -106.711868) (xy 29.73291 -106.755681) (xy 29.731716 -106.778044)
			(xy 29.731716 -106.900726) (xy 40.57726 -106.900726) (xy 40.581331 -106.845104) (xy 40.593457 -106.790667)
			(xy 40.61338 -106.738576) (xy 40.640676 -106.689941) (xy 40.674762 -106.645798) (xy 40.714911 -106.607089)
			(xy 40.760269 -106.574638) (xy 40.809869 -106.549137) (xy 40.862653 -106.53113) (xy 40.917496 -106.521)
			(xy 40.97323 -106.518963) (xy 41.028667 -106.525063) (xy 41.082624 -106.539169) (xy 41.133953 -106.560981)
			(xy 41.181559 -106.590035) (xy 41.224427 -106.62571) (xy 41.261644 -106.667247) (xy 41.292417 -106.71376)
			(xy 41.316089 -106.764257) (xy 41.332157 -106.817664) (xy 41.340277 -106.87284) (xy 41.340786 -106.900726)
			(xy 41.340277 -106.928612) (xy 41.332157 -106.983788) (xy 41.316089 -107.037195) (xy 41.292417 -107.087692)
			(xy 41.261644 -107.134205) (xy 41.238099 -107.160483) (xy 47.373784 -107.160483) (xy 47.373784 -107.079373)
			(xy 47.381734 -106.998654) (xy 47.397557 -106.919103) (xy 47.421102 -106.841487) (xy 47.452141 -106.766551)
			(xy 47.490376 -106.695019) (xy 47.535438 -106.627579) (xy 47.586893 -106.56488) (xy 47.644246 -106.507527)
			(xy 47.706945 -106.456072) (xy 47.774385 -106.41101) (xy 47.845917 -106.372775) (xy 47.920853 -106.341736)
			(xy 47.998469 -106.318191) (xy 48.07802 -106.302368) (xy 48.158739 -106.294418) (xy 48.239849 -106.294418)
			(xy 48.320568 -106.302368) (xy 48.400119 -106.318191) (xy 48.477735 -106.341736) (xy 48.552671 -106.372775)
			(xy 48.624203 -106.41101) (xy 48.691643 -106.456072) (xy 48.754342 -106.507527) (xy 48.811695 -106.56488)
			(xy 48.86315 -106.627579) (xy 48.908212 -106.695019) (xy 48.946447 -106.766551) (xy 48.977486 -106.841487)
			(xy 49.001031 -106.919103) (xy 49.012532 -106.976926) (xy 71.136508 -106.976926) (xy 71.140579 -106.921304)
			(xy 71.152705 -106.866867) (xy 71.172628 -106.814776) (xy 71.199924 -106.766141) (xy 71.23401 -106.721998)
			(xy 71.274159 -106.683289) (xy 71.319517 -106.650838) (xy 71.369117 -106.625337) (xy 71.421901 -106.60733)
			(xy 71.476744 -106.5972) (xy 71.532478 -106.595163) (xy 71.587915 -106.601263) (xy 71.641872 -106.615369)
			(xy 71.693201 -106.637181) (xy 71.740807 -106.666235) (xy 71.783675 -106.70191) (xy 71.820892 -106.743447)
			(xy 71.851665 -106.78996) (xy 71.875337 -106.840457) (xy 71.891405 -106.893864) (xy 71.899525 -106.94904)
			(xy 71.900034 -106.976926) (xy 71.899525 -107.004812) (xy 71.891405 -107.059988) (xy 71.875337 -107.113395)
			(xy 71.851665 -107.163892) (xy 71.820892 -107.210405) (xy 71.783675 -107.251942) (xy 71.740807 -107.287617)
			(xy 71.693201 -107.316671) (xy 71.641872 -107.338483) (xy 71.587915 -107.352589) (xy 71.532478 -107.358689)
			(xy 71.476744 -107.356652) (xy 71.421901 -107.346522) (xy 71.369117 -107.328515) (xy 71.319517 -107.303014)
			(xy 71.274159 -107.270563) (xy 71.23401 -107.231854) (xy 71.199924 -107.187711) (xy 71.172628 -107.139076)
			(xy 71.152705 -107.086985) (xy 71.140579 -107.032548) (xy 71.136508 -106.976926) (xy 49.012532 -106.976926)
			(xy 49.016854 -106.998654) (xy 49.024804 -107.079373) (xy 49.025302 -107.119928) (xy 49.024804 -107.160483)
			(xy 49.016854 -107.241202) (xy 49.001031 -107.320753) (xy 48.977486 -107.398369) (xy 48.946447 -107.473305)
			(xy 48.908212 -107.544837) (xy 48.86315 -107.612277) (xy 48.811695 -107.674976) (xy 48.754342 -107.732329)
			(xy 48.691643 -107.783784) (xy 48.624203 -107.828846) (xy 48.552671 -107.867081) (xy 48.477735 -107.89812)
			(xy 48.400119 -107.921665) (xy 48.320568 -107.937488) (xy 48.239849 -107.945438) (xy 48.158739 -107.945438)
			(xy 48.07802 -107.937488) (xy 47.998469 -107.921665) (xy 47.920853 -107.89812) (xy 47.845917 -107.867081)
			(xy 47.774385 -107.828846) (xy 47.706945 -107.783784) (xy 47.644246 -107.732329) (xy 47.586893 -107.674976)
			(xy 47.535438 -107.612277) (xy 47.490376 -107.544837) (xy 47.452141 -107.473305) (xy 47.421102 -107.398369)
			(xy 47.397557 -107.320753) (xy 47.381734 -107.241202) (xy 47.373784 -107.160483) (xy 41.238099 -107.160483)
			(xy 41.224427 -107.175742) (xy 41.181559 -107.211417) (xy 41.133953 -107.240471) (xy 41.082624 -107.262283)
			(xy 41.028667 -107.276389) (xy 40.97323 -107.282489) (xy 40.917496 -107.280452) (xy 40.862653 -107.270322)
			(xy 40.809869 -107.252315) (xy 40.760269 -107.226814) (xy 40.714911 -107.194363) (xy 40.674762 -107.155654)
			(xy 40.640676 -107.111511) (xy 40.61338 -107.062876) (xy 40.593457 -107.010785) (xy 40.581331 -106.956348)
			(xy 40.57726 -106.900726) (xy 29.731716 -106.900726) (xy 29.731716 -107.141772) (xy 29.7329 -107.164141)
			(xy 29.742146 -107.207967) (xy 29.758928 -107.249496) (xy 29.782727 -107.287441) (xy 29.812807 -107.320628)
			(xy 29.848236 -107.348032) (xy 29.88792 -107.368803) (xy 29.930629 -107.382299) (xy 29.975042 -107.388103)
			(xy 30.019785 -107.386034) (xy 30.063474 -107.376157) (xy 30.084268 -107.367832) (xy 30.124199 -107.350984)
			(xy 30.206513 -107.323837) (xy 30.290976 -107.30438) (xy 30.376871 -107.29278) (xy 30.463469 -107.289134)
			(xy 30.550035 -107.293474) (xy 30.635834 -107.305762) (xy 30.720138 -107.325894) (xy 30.802232 -107.3537)
			(xy 30.881418 -107.388943) (xy 30.957024 -107.431324) (xy 31.028409 -107.480484) (xy 31.094967 -107.536005)
			(xy 31.156132 -107.597415) (xy 31.211386 -107.664195) (xy 31.26026 -107.735776) (xy 31.302338 -107.811552)
			(xy 31.337264 -107.890878) (xy 31.364741 -107.973082) (xy 31.384536 -108.057466) (xy 31.39648 -108.143314)
			(xy 31.400473 -108.229897) (xy 31.398469 -108.273358) (xy 34.599874 -108.273358) (xy 34.599874 -108.186458)
			(xy 34.607892 -108.099929) (xy 34.62386 -108.014509) (xy 34.647641 -107.930927) (xy 34.679033 -107.849895)
			(xy 34.717767 -107.772106) (xy 34.763514 -107.698222) (xy 34.815883 -107.628875) (xy 34.874427 -107.564655)
			(xy 34.938647 -107.506111) (xy 35.007994 -107.453742) (xy 35.081878 -107.407995) (xy 35.159667 -107.369261)
			(xy 35.240699 -107.337869) (xy 35.324281 -107.314088) (xy 35.409701 -107.29812) (xy 35.49623 -107.290102)
			(xy 35.58313 -107.290102) (xy 35.669659 -107.29812) (xy 35.755079 -107.314088) (xy 35.838661 -107.337869)
			(xy 35.919693 -107.369261) (xy 35.997482 -107.407995) (xy 36.071366 -107.453742) (xy 36.140713 -107.506111)
			(xy 36.204933 -107.564655) (xy 36.263477 -107.628875) (xy 36.315846 -107.698222) (xy 36.361593 -107.772106)
			(xy 36.400327 -107.849895) (xy 36.431719 -107.930927) (xy 36.4555 -108.014509) (xy 36.471468 -108.099929)
			(xy 36.479486 -108.186458) (xy 36.479988 -108.229908) (xy 36.479486 -108.273358) (xy 36.471468 -108.359887)
			(xy 36.4555 -108.445307) (xy 36.431719 -108.528889) (xy 36.400327 -108.609921) (xy 36.361593 -108.68771)
			(xy 36.315846 -108.761594) (xy 36.263477 -108.830941) (xy 36.204933 -108.895161) (xy 36.140713 -108.953705)
			(xy 36.071366 -109.006074) (xy 35.997482 -109.051821) (xy 35.919693 -109.090555) (xy 35.838661 -109.121947)
			(xy 35.755079 -109.145728) (xy 35.669659 -109.161696) (xy 35.58313 -109.169714) (xy 35.49623 -109.169714)
			(xy 35.409701 -109.161696) (xy 35.324281 -109.145728) (xy 35.240699 -109.121947) (xy 35.159667 -109.090555)
			(xy 35.081878 -109.051821) (xy 35.007994 -109.006074) (xy 34.938647 -108.953705) (xy 34.874427 -108.895161)
			(xy 34.815883 -108.830941) (xy 34.763514 -108.761594) (xy 34.717767 -108.68771) (xy 34.679033 -108.609921)
			(xy 34.647641 -108.528889) (xy 34.62386 -108.445307) (xy 34.607892 -108.359887) (xy 34.599874 -108.273358)
			(xy 31.398469 -108.273358) (xy 31.396481 -108.31648) (xy 31.384537 -108.402327) (xy 31.364743 -108.486712)
			(xy 31.337266 -108.568916) (xy 31.302341 -108.648243) (xy 31.260263 -108.724018) (xy 31.21139 -108.7956)
			(xy 31.156137 -108.86238) (xy 31.094972 -108.923791) (xy 31.028414 -108.979312) (xy 30.957029 -109.028473)
			(xy 30.881423 -109.070854) (xy 30.802238 -109.106098) (xy 30.720144 -109.133904) (xy 30.63584 -109.154037)
			(xy 30.550041 -109.166326) (xy 30.463475 -109.170666) (xy 30.376877 -109.167021) (xy 30.290982 -109.155421)
			(xy 30.206519 -109.135965) (xy 30.124205 -109.108819) (xy 30.084268 -109.091984) (xy 30.063448 -109.083735)
			(xy 30.019769 -109.073864) (xy 29.975036 -109.071798) (xy 29.930634 -109.0776) (xy 29.887934 -109.091092)
			(xy 29.848258 -109.111855) (xy 29.812834 -109.139247) (xy 29.782756 -109.172422) (xy 29.758954 -109.210353)
			(xy 29.742166 -109.251868) (xy 29.73291 -109.295681) (xy 29.731716 -109.318044) (xy 29.731716 -109.681772)
			(xy 29.7329 -109.704141) (xy 29.742146 -109.747967) (xy 29.758928 -109.789496) (xy 29.782727 -109.827441)
			(xy 29.812807 -109.860628) (xy 29.848236 -109.888032) (xy 29.88792 -109.908803) (xy 29.930629 -109.922299)
			(xy 29.975042 -109.928103) (xy 30.019785 -109.926034) (xy 30.063474 -109.916157) (xy 30.084268 -109.907832)
			(xy 30.123632 -109.891216) (xy 30.204747 -109.864347) (xy 30.287965 -109.844949) (xy 30.3726 -109.833182)
			(xy 30.457954 -109.829143) (xy 30.543322 -109.832865) (xy 30.628 -109.844318) (xy 30.71129 -109.863407)
			(xy 30.792504 -109.889974) (xy 30.870972 -109.923802) (xy 30.946048 -109.964609) (xy 31.01711 -110.01206)
			(xy 31.083575 -110.065764) (xy 31.144892 -110.125276) (xy 31.200556 -110.190107) (xy 31.250108 -110.259722)
			(xy 31.29314 -110.333545) (xy 31.329295 -110.410968) (xy 31.358276 -110.491353) (xy 31.379844 -110.574035)
			(xy 31.39382 -110.658333) (xy 31.40009 -110.743552) (xy 31.398873 -110.813358) (xy 34.599874 -110.813358)
			(xy 34.599874 -110.726458) (xy 34.607892 -110.639929) (xy 34.62386 -110.554509) (xy 34.647641 -110.470927)
			(xy 34.679033 -110.389895) (xy 34.717767 -110.312106) (xy 34.763514 -110.238222) (xy 34.815883 -110.168875)
			(xy 34.874427 -110.104655) (xy 34.938647 -110.046111) (xy 35.007994 -109.993742) (xy 35.081878 -109.947995)
			(xy 35.159667 -109.909261) (xy 35.240699 -109.877869) (xy 35.324281 -109.854088) (xy 35.409701 -109.83812)
			(xy 35.49623 -109.830102) (xy 35.58313 -109.830102) (xy 35.669659 -109.83812) (xy 35.755079 -109.854088)
			(xy 35.838661 -109.877869) (xy 35.919693 -109.909261) (xy 35.997482 -109.947995) (xy 36.039685 -109.974126)
			(xy 39.95496 -109.974126) (xy 39.959031 -109.918504) (xy 39.971157 -109.864067) (xy 39.99108 -109.811976)
			(xy 40.018376 -109.763341) (xy 40.052462 -109.719198) (xy 40.092611 -109.680489) (xy 40.137969 -109.648038)
			(xy 40.187569 -109.622537) (xy 40.240353 -109.60453) (xy 40.295196 -109.5944) (xy 40.35093 -109.592363)
			(xy 40.406367 -109.598463) (xy 40.460324 -109.612569) (xy 40.511653 -109.634381) (xy 40.559259 -109.663435)
			(xy 40.602127 -109.69911) (xy 40.639344 -109.740647) (xy 40.670117 -109.78716) (xy 40.693789 -109.837657)
			(xy 40.709857 -109.891064) (xy 40.717977 -109.94624) (xy 40.718486 -109.974126) (xy 40.717977 -110.002012)
			(xy 40.709857 -110.057188) (xy 40.693789 -110.110595) (xy 40.670117 -110.161092) (xy 40.639344 -110.207605)
			(xy 40.602127 -110.249142) (xy 40.559259 -110.284817) (xy 40.511653 -110.313871) (xy 40.460324 -110.335683)
			(xy 40.406367 -110.349789) (xy 40.35093 -110.355889) (xy 40.295196 -110.353852) (xy 40.240353 -110.343722)
			(xy 40.187569 -110.325715) (xy 40.137969 -110.300214) (xy 40.092611 -110.267763) (xy 40.052462 -110.229054)
			(xy 40.018376 -110.184911) (xy 39.99108 -110.136276) (xy 39.971157 -110.084185) (xy 39.959031 -110.029748)
			(xy 39.95496 -109.974126) (xy 36.039685 -109.974126) (xy 36.071366 -109.993742) (xy 36.140713 -110.046111)
			(xy 36.204933 -110.104655) (xy 36.263477 -110.168875) (xy 36.315846 -110.238222) (xy 36.361593 -110.312106)
			(xy 36.400327 -110.389895) (xy 36.431719 -110.470927) (xy 36.4555 -110.554509) (xy 36.471468 -110.639929)
			(xy 36.479486 -110.726458) (xy 36.479988 -110.769908) (xy 36.479486 -110.813358) (xy 36.471468 -110.899887)
			(xy 36.4555 -110.985307) (xy 36.431719 -111.068889) (xy 36.400327 -111.149921) (xy 36.361593 -111.22771)
			(xy 36.315846 -111.301594) (xy 36.263477 -111.370941) (xy 36.204933 -111.435161) (xy 36.140713 -111.493705)
			(xy 36.071366 -111.546074) (xy 36.026148 -111.574072) (xy 40.008808 -111.574072) (xy 40.012879 -111.51845)
			(xy 40.025005 -111.464013) (xy 40.044928 -111.411922) (xy 40.072224 -111.363287) (xy 40.10631 -111.319144)
			(xy 40.146459 -111.280435) (xy 40.191817 -111.247984) (xy 40.241417 -111.222483) (xy 40.294201 -111.204476)
			(xy 40.349044 -111.194346) (xy 40.404778 -111.192309) (xy 40.460215 -111.198409) (xy 40.514172 -111.212515)
			(xy 40.565501 -111.234327) (xy 40.613107 -111.263381) (xy 40.655975 -111.299056) (xy 40.693192 -111.340593)
			(xy 40.723965 -111.387106) (xy 40.747637 -111.437603) (xy 40.763705 -111.49101) (xy 40.771825 -111.546186)
			(xy 40.772334 -111.574072) (xy 40.771825 -111.601958) (xy 40.763705 -111.657134) (xy 40.747637 -111.710541)
			(xy 40.723965 -111.761038) (xy 40.693192 -111.807551) (xy 40.655975 -111.849088) (xy 40.613107 -111.884763)
			(xy 40.565501 -111.913817) (xy 40.514172 -111.935629) (xy 40.460215 -111.949735) (xy 40.404778 -111.955835)
			(xy 40.349044 -111.953798) (xy 40.294201 -111.943668) (xy 40.241417 -111.925661) (xy 40.191817 -111.90016)
			(xy 40.146459 -111.867709) (xy 40.10631 -111.829) (xy 40.072224 -111.784857) (xy 40.044928 -111.736222)
			(xy 40.025005 -111.684131) (xy 40.012879 -111.629694) (xy 40.008808 -111.574072) (xy 36.026148 -111.574072)
			(xy 35.997482 -111.591821) (xy 35.919693 -111.630555) (xy 35.838661 -111.661947) (xy 35.755079 -111.685728)
			(xy 35.669659 -111.701696) (xy 35.58313 -111.709714) (xy 35.49623 -111.709714) (xy 35.409701 -111.701696)
			(xy 35.324281 -111.685728) (xy 35.240699 -111.661947) (xy 35.159667 -111.630555) (xy 35.081878 -111.591821)
			(xy 35.007994 -111.546074) (xy 34.938647 -111.493705) (xy 34.874427 -111.435161) (xy 34.815883 -111.370941)
			(xy 34.763514 -111.301594) (xy 34.717767 -111.22771) (xy 34.679033 -111.149921) (xy 34.647641 -111.068889)
			(xy 34.62386 -110.985307) (xy 34.607892 -110.899887) (xy 34.599874 -110.813358) (xy 31.398873 -110.813358)
			(xy 31.398601 -110.828988) (xy 31.3944 -110.871508) (xy 31.389126 -110.915233) (xy 31.371455 -111.00152)
			(xy 31.345793 -111.085776) (xy 31.312365 -111.167264) (xy 31.271464 -111.245269) (xy 31.223448 -111.319108)
			(xy 31.168739 -111.388134) (xy 31.107815 -111.451741) (xy 31.04121 -111.509374) (xy 30.969508 -111.560526)
			(xy 30.893338 -111.60475) (xy 30.813366 -111.641657) (xy 30.730293 -111.670926) (xy 30.644848 -111.692298)
			(xy 30.557778 -111.705587) (xy 30.469848 -111.710677) (xy 30.381827 -111.707522) (xy 30.294486 -111.696151)
			(xy 30.208591 -111.676663) (xy 30.124895 -111.649229) (xy 30.044131 -111.614089) (xy 29.967006 -111.571552)
			(xy 29.930344 -111.547148) (xy 29.917425 -111.538877) (xy 29.888706 -111.528125) (xy 29.858251 -111.524543)
			(xy 29.827821 -111.528339) (xy 29.799178 -111.539294) (xy 29.773981 -111.556772) (xy 29.753689 -111.579763)
			(xy 29.739474 -111.606936) (xy 29.732162 -111.636717) (xy 29.731716 -111.65205) (xy 29.731716 -111.795052)
			(xy 29.290264 -112.236504) (xy 29.290264 -112.550702) (xy 29.29138 -112.572445) (xy 29.300112 -112.615094)
			(xy 29.315983 -112.655631) (xy 29.338531 -112.69287) (xy 29.367094 -112.725723) (xy 29.400837 -112.753229)
			(xy 29.438774 -112.774582) (xy 29.479795 -112.789158) (xy 29.5227 -112.796531) (xy 29.566233 -112.796485)
			(xy 29.609122 -112.789022) (xy 29.650112 -112.77436) (xy 29.688004 -112.752927) (xy 29.72169 -112.725351)
			(xy 29.736288 -112.709198) (xy 29.76442 -112.676081) (xy 29.825867 -112.614632) (xy 29.892723 -112.559115)
			(xy 29.964415 -112.510004) (xy 30.040333 -112.467717) (xy 30.119829 -112.432615) (xy 30.202225 -112.404998)
			(xy 30.286817 -112.385101) (xy 30.372884 -112.373095) (xy 30.459692 -112.369081) (xy 30.5465 -112.373093)
			(xy 30.632567 -112.385098) (xy 30.71716 -112.404994) (xy 30.799556 -112.432609) (xy 30.879053 -112.46771)
			(xy 30.954971 -112.509995) (xy 31.026665 -112.559105) (xy 31.093521 -112.614621) (xy 31.154969 -112.676069)
			(xy 31.210486 -112.742924) (xy 31.259597 -112.814617) (xy 31.301884 -112.890535) (xy 31.336986 -112.970031)
			(xy 31.364603 -113.052426) (xy 31.384499 -113.137019) (xy 31.396506 -113.223086) (xy 31.400519 -113.309894)
			(xy 31.39851 -113.353358) (xy 34.599874 -113.353358) (xy 34.599874 -113.266458) (xy 34.607892 -113.179929)
			(xy 34.62386 -113.094509) (xy 34.647641 -113.010927) (xy 34.679033 -112.929895) (xy 34.717767 -112.852106)
			(xy 34.763514 -112.778222) (xy 34.815883 -112.708875) (xy 34.874427 -112.644655) (xy 34.938647 -112.586111)
			(xy 35.007994 -112.533742) (xy 35.081878 -112.487995) (xy 35.159667 -112.449261) (xy 35.240699 -112.417869)
			(xy 35.324281 -112.394088) (xy 35.409701 -112.37812) (xy 35.49623 -112.370102) (xy 35.58313 -112.370102)
			(xy 35.669659 -112.37812) (xy 35.755079 -112.394088) (xy 35.838661 -112.417869) (xy 35.919693 -112.449261)
			(xy 35.997482 -112.487995) (xy 36.071366 -112.533742) (xy 36.140713 -112.586111) (xy 36.204933 -112.644655)
			(xy 36.263477 -112.708875) (xy 36.315846 -112.778222) (xy 36.361593 -112.852106) (xy 36.400327 -112.929895)
			(xy 36.431719 -113.010927) (xy 36.4555 -113.094509) (xy 36.471468 -113.179929) (xy 36.479486 -113.266458)
			(xy 36.479988 -113.309908) (xy 36.479486 -113.353358) (xy 36.471468 -113.439887) (xy 36.4555 -113.525307)
			(xy 36.431719 -113.608889) (xy 36.400327 -113.689921) (xy 36.361593 -113.76771) (xy 36.315846 -113.841594)
			(xy 36.263477 -113.910941) (xy 36.204933 -113.975161) (xy 36.140713 -114.033705) (xy 36.071366 -114.086074)
			(xy 35.997482 -114.131821) (xy 35.919693 -114.170555) (xy 35.838661 -114.201947) (xy 35.755079 -114.225728)
			(xy 35.669659 -114.241696) (xy 35.58313 -114.249714) (xy 35.49623 -114.249714) (xy 35.409701 -114.241696)
			(xy 35.324281 -114.225728) (xy 35.240699 -114.201947) (xy 35.159667 -114.170555) (xy 35.081878 -114.131821)
			(xy 35.007994 -114.086074) (xy 34.938647 -114.033705) (xy 34.874427 -113.975161) (xy 34.815883 -113.910941)
			(xy 34.763514 -113.841594) (xy 34.717767 -113.76771) (xy 34.679033 -113.689921) (xy 34.647641 -113.608889)
			(xy 34.62386 -113.525307) (xy 34.607892 -113.439887) (xy 34.599874 -113.353358) (xy 31.39851 -113.353358)
			(xy 31.396507 -113.396702) (xy 31.384501 -113.482769) (xy 31.364606 -113.567362) (xy 31.33699 -113.649758)
			(xy 31.30189 -113.729254) (xy 31.259604 -113.805173) (xy 31.210493 -113.876866) (xy 31.154978 -113.943722)
			(xy 31.09353 -114.00517) (xy 31.026674 -114.060687) (xy 30.954982 -114.109798) (xy 30.879064 -114.152085)
			(xy 30.799568 -114.187186) (xy 30.717172 -114.214803) (xy 30.63258 -114.234699) (xy 30.546512 -114.246706)
			(xy 30.459704 -114.250719) (xy 30.372896 -114.246707) (xy 30.286829 -114.234701) (xy 30.202236 -114.214805)
			(xy 30.11984 -114.187189) (xy 30.040344 -114.152089) (xy 29.964426 -114.109803) (xy 29.892732 -114.060692)
			(xy 29.825877 -114.005176) (xy 29.764428 -113.943728) (xy 29.736288 -113.910618) (xy 29.7217 -113.894467)
			(xy 29.688014 -113.866916) (xy 29.650127 -113.845506) (xy 29.609147 -113.830862) (xy 29.566272 -113.823413)
			(xy 29.522754 -113.823377) (xy 29.479866 -113.830754) (xy 29.438861 -113.845329) (xy 29.400938 -113.866675)
			(xy 29.367206 -113.89417) (xy 29.338651 -113.927009) (xy 29.316106 -113.964232) (xy 29.300232 -114.004751)
			(xy 29.291492 -114.047383) (xy 29.290264 -114.069114) (xy 29.290264 -115.090702) (xy 29.29138 -115.112445)
			(xy 29.300112 -115.155094) (xy 29.315983 -115.195631) (xy 29.338531 -115.23287) (xy 29.367094 -115.265723)
			(xy 29.400837 -115.293229) (xy 29.438774 -115.314582) (xy 29.479795 -115.329158) (xy 29.5227 -115.336531)
			(xy 29.566233 -115.336485) (xy 29.609122 -115.329022) (xy 29.650112 -115.31436) (xy 29.688004 -115.292927)
			(xy 29.72169 -115.265351) (xy 29.736288 -115.249198) (xy 29.76442 -115.216081) (xy 29.825867 -115.154632)
			(xy 29.892723 -115.099115) (xy 29.964415 -115.050004) (xy 30.040333 -115.007717) (xy 30.119829 -114.972615)
			(xy 30.202225 -114.944998) (xy 30.286817 -114.925101) (xy 30.372884 -114.913095) (xy 30.459692 -114.909081)
			(xy 30.5465 -114.913093) (xy 30.632567 -114.925098) (xy 30.71716 -114.944994) (xy 30.799556 -114.972609)
			(xy 30.879053 -115.00771) (xy 30.954971 -115.049995) (xy 31.026665 -115.099105) (xy 31.093521 -115.154621)
			(xy 31.154969 -115.216069) (xy 31.210486 -115.282924) (xy 31.259597 -115.354617) (xy 31.301884 -115.430535)
			(xy 31.336986 -115.510031) (xy 31.364603 -115.592426) (xy 31.384499 -115.677019) (xy 31.396506 -115.763086)
			(xy 31.400519 -115.849894) (xy 31.39851 -115.893358) (xy 34.599874 -115.893358) (xy 34.599874 -115.806458)
			(xy 34.607892 -115.719929) (xy 34.62386 -115.634509) (xy 34.647641 -115.550927) (xy 34.679033 -115.469895)
			(xy 34.717767 -115.392106) (xy 34.763514 -115.318222) (xy 34.815883 -115.248875) (xy 34.874427 -115.184655)
			(xy 34.938647 -115.126111) (xy 35.007994 -115.073742) (xy 35.081878 -115.027995) (xy 35.159667 -114.989261)
			(xy 35.240699 -114.957869) (xy 35.324281 -114.934088) (xy 35.409701 -114.91812) (xy 35.49623 -114.910102)
			(xy 35.58313 -114.910102) (xy 35.669659 -114.91812) (xy 35.755079 -114.934088) (xy 35.838661 -114.957869)
			(xy 35.919693 -114.989261) (xy 35.997482 -115.027995) (xy 36.071366 -115.073742) (xy 36.140713 -115.126111)
			(xy 36.204933 -115.184655) (xy 36.263477 -115.248875) (xy 36.315846 -115.318222) (xy 36.361593 -115.392106)
			(xy 36.400327 -115.469895) (xy 36.431719 -115.550927) (xy 36.4555 -115.634509) (xy 36.471468 -115.719929)
			(xy 36.479486 -115.806458) (xy 36.479988 -115.849908) (xy 36.479486 -115.893358) (xy 36.471468 -115.979887)
			(xy 36.4555 -116.065307) (xy 36.431719 -116.148889) (xy 36.400327 -116.229921) (xy 36.361593 -116.30771)
			(xy 36.315846 -116.381594) (xy 36.263477 -116.450941) (xy 36.204933 -116.515161) (xy 36.140713 -116.573705)
			(xy 36.071366 -116.626074) (xy 35.997482 -116.671821) (xy 35.919693 -116.710555) (xy 35.838661 -116.741947)
			(xy 35.755079 -116.765728) (xy 35.669659 -116.781696) (xy 35.58313 -116.789714) (xy 35.49623 -116.789714)
			(xy 35.409701 -116.781696) (xy 35.324281 -116.765728) (xy 35.240699 -116.741947) (xy 35.159667 -116.710555)
			(xy 35.081878 -116.671821) (xy 35.007994 -116.626074) (xy 34.938647 -116.573705) (xy 34.874427 -116.515161)
			(xy 34.815883 -116.450941) (xy 34.763514 -116.381594) (xy 34.717767 -116.30771) (xy 34.679033 -116.229921)
			(xy 34.647641 -116.148889) (xy 34.62386 -116.065307) (xy 34.607892 -115.979887) (xy 34.599874 -115.893358)
			(xy 31.39851 -115.893358) (xy 31.396507 -115.936702) (xy 31.384501 -116.022769) (xy 31.364606 -116.107362)
			(xy 31.33699 -116.189758) (xy 31.30189 -116.269254) (xy 31.259604 -116.345173) (xy 31.210493 -116.416866)
			(xy 31.154978 -116.483722) (xy 31.09353 -116.54517) (xy 31.026674 -116.600687) (xy 30.954982 -116.649798)
			(xy 30.879064 -116.692085) (xy 30.799568 -116.727186) (xy 30.717172 -116.754803) (xy 30.63258 -116.774699)
			(xy 30.546512 -116.786706) (xy 30.459704 -116.790719) (xy 30.372896 -116.786707) (xy 30.286829 -116.774701)
			(xy 30.202236 -116.754805) (xy 30.11984 -116.727189) (xy 30.040344 -116.692089) (xy 29.964426 -116.649803)
			(xy 29.892732 -116.600692) (xy 29.825877 -116.545176) (xy 29.764428 -116.483728) (xy 29.736288 -116.450618)
			(xy 29.7217 -116.434467) (xy 29.688014 -116.406916) (xy 29.650127 -116.385506) (xy 29.609147 -116.370862)
			(xy 29.566272 -116.363413) (xy 29.522754 -116.363377) (xy 29.479866 -116.370754) (xy 29.438861 -116.385329)
			(xy 29.400938 -116.406675) (xy 29.367206 -116.43417) (xy 29.338651 -116.467009) (xy 29.316106 -116.504232)
			(xy 29.300232 -116.544751) (xy 29.291492 -116.587383) (xy 29.290264 -116.609114) (xy 29.290264 -117.311017)
			(xy 39.098212 -117.311017) (xy 39.098212 -117.239695) (xy 39.106198 -117.168821) (xy 39.122068 -117.099286)
			(xy 39.145625 -117.031966) (xy 39.17657 -116.967707) (xy 39.214516 -116.907316) (xy 39.258985 -116.851554)
			(xy 39.309418 -116.801121) (xy 39.36518 -116.756652) (xy 39.425571 -116.718706) (xy 39.48983 -116.687761)
			(xy 39.55715 -116.664204) (xy 39.626685 -116.648334) (xy 39.697559 -116.640348) (xy 39.768881 -116.640348)
			(xy 39.839755 -116.648334) (xy 39.90929 -116.664204) (xy 39.97661 -116.687761) (xy 40.040869 -116.718706)
			(xy 40.10126 -116.756652) (xy 40.157022 -116.801121) (xy 40.207455 -116.851554) (xy 40.251924 -116.907316)
			(xy 40.28987 -116.967707) (xy 40.320815 -117.031966) (xy 40.344372 -117.099286) (xy 40.356116 -117.150743)
			(xy 58.432184 -117.150743) (xy 58.432184 -117.079421) (xy 58.44017 -117.008547) (xy 58.45604 -116.939012)
			(xy 58.479597 -116.871692) (xy 58.510542 -116.807433) (xy 58.548488 -116.747042) (xy 58.592957 -116.69128)
			(xy 58.64339 -116.640847) (xy 58.699152 -116.596378) (xy 58.759543 -116.558432) (xy 58.823802 -116.527487)
			(xy 58.891122 -116.50393) (xy 58.960657 -116.48806) (xy 59.031531 -116.480074) (xy 59.102853 -116.480074)
			(xy 59.173727 -116.48806) (xy 59.243262 -116.50393) (xy 59.310582 -116.527487) (xy 59.374841 -116.558432)
			(xy 59.435232 -116.596378) (xy 59.490994 -116.640847) (xy 59.541427 -116.69128) (xy 59.585896 -116.747042)
			(xy 59.623842 -116.807433) (xy 59.654787 -116.871692) (xy 59.678344 -116.939012) (xy 59.694214 -117.008547)
			(xy 59.7022 -117.079421) (xy 59.7027 -117.115082) (xy 59.7022 -117.150743) (xy 59.694214 -117.221617)
			(xy 59.678344 -117.291152) (xy 59.654787 -117.358472) (xy 59.623842 -117.422731) (xy 59.585896 -117.483122)
			(xy 59.541427 -117.538884) (xy 59.490994 -117.589317) (xy 59.442603 -117.627908) (xy 67.11137 -117.627908)
			(xy 67.115441 -117.572286) (xy 67.127567 -117.517849) (xy 67.14749 -117.465758) (xy 67.174786 -117.417123)
			(xy 67.208872 -117.37298) (xy 67.249021 -117.334271) (xy 67.294379 -117.30182) (xy 67.343979 -117.276319)
			(xy 67.396763 -117.258312) (xy 67.451606 -117.248182) (xy 67.50734 -117.246145) (xy 67.562777 -117.252245)
			(xy 67.616734 -117.266351) (xy 67.668063 -117.288163) (xy 67.715669 -117.317217) (xy 67.758537 -117.352892)
			(xy 67.795754 -117.394429) (xy 67.826527 -117.440942) (xy 67.850199 -117.491439) (xy 67.866267 -117.544846)
			(xy 67.874387 -117.600022) (xy 67.874882 -117.627146) (xy 69.465696 -117.627146) (xy 69.469767 -117.571524)
			(xy 69.481893 -117.517087) (xy 69.501816 -117.464996) (xy 69.529112 -117.416361) (xy 69.563198 -117.372218)
			(xy 69.603347 -117.333509) (xy 69.648705 -117.301058) (xy 69.698305 -117.275557) (xy 69.751089 -117.25755)
			(xy 69.805932 -117.24742) (xy 69.861666 -117.245383) (xy 69.917103 -117.251483) (xy 69.97106 -117.265589)
			(xy 70.022389 -117.287401) (xy 70.069995 -117.316455) (xy 70.112863 -117.35213) (xy 70.15008 -117.393667)
			(xy 70.180853 -117.44018) (xy 70.204525 -117.490677) (xy 70.220593 -117.544084) (xy 70.228713 -117.59926)
			(xy 70.229222 -117.627146) (xy 70.228713 -117.655032) (xy 70.220593 -117.710208) (xy 70.204525 -117.763615)
			(xy 70.180853 -117.814112) (xy 70.15008 -117.860625) (xy 70.112863 -117.902162) (xy 70.069995 -117.937837)
			(xy 70.022389 -117.966891) (xy 69.97106 -117.988703) (xy 69.917103 -118.002809) (xy 69.861666 -118.008909)
			(xy 69.805932 -118.006872) (xy 69.751089 -117.996742) (xy 69.698305 -117.978735) (xy 69.648705 -117.953234)
			(xy 69.603347 -117.920783) (xy 69.563198 -117.882074) (xy 69.529112 -117.837931) (xy 69.501816 -117.789296)
			(xy 69.481893 -117.737205) (xy 69.469767 -117.682768) (xy 69.465696 -117.627146) (xy 67.874882 -117.627146)
			(xy 67.874896 -117.627908) (xy 67.874387 -117.655794) (xy 67.866267 -117.71097) (xy 67.850199 -117.764377)
			(xy 67.826527 -117.814874) (xy 67.795754 -117.861387) (xy 67.758537 -117.902924) (xy 67.715669 -117.938599)
			(xy 67.668063 -117.967653) (xy 67.616734 -117.989465) (xy 67.562777 -118.003571) (xy 67.50734 -118.009671)
			(xy 67.451606 -118.007634) (xy 67.396763 -117.997504) (xy 67.343979 -117.979497) (xy 67.294379 -117.953996)
			(xy 67.249021 -117.921545) (xy 67.208872 -117.882836) (xy 67.174786 -117.838693) (xy 67.14749 -117.790058)
			(xy 67.127567 -117.737967) (xy 67.115441 -117.68353) (xy 67.11137 -117.627908) (xy 59.442603 -117.627908)
			(xy 59.435232 -117.633786) (xy 59.374841 -117.671732) (xy 59.310582 -117.702677) (xy 59.243262 -117.726234)
			(xy 59.173727 -117.742104) (xy 59.102853 -117.75009) (xy 59.031531 -117.75009) (xy 58.960657 -117.742104)
			(xy 58.891122 -117.726234) (xy 58.823802 -117.702677) (xy 58.759543 -117.671732) (xy 58.699152 -117.633786)
			(xy 58.64339 -117.589317) (xy 58.592957 -117.538884) (xy 58.548488 -117.483122) (xy 58.510542 -117.422731)
			(xy 58.479597 -117.358472) (xy 58.45604 -117.291152) (xy 58.44017 -117.221617) (xy 58.432184 -117.150743)
			(xy 40.356116 -117.150743) (xy 40.360242 -117.168821) (xy 40.368228 -117.239695) (xy 40.368728 -117.275356)
			(xy 40.368228 -117.311017) (xy 40.360242 -117.381891) (xy 40.344372 -117.451426) (xy 40.320815 -117.518746)
			(xy 40.28987 -117.583005) (xy 40.251924 -117.643396) (xy 40.207455 -117.699158) (xy 40.157022 -117.749591)
			(xy 40.10126 -117.79406) (xy 40.040869 -117.832006) (xy 39.97661 -117.862951) (xy 39.90929 -117.886508)
			(xy 39.839755 -117.902378) (xy 39.768881 -117.910364) (xy 39.697559 -117.910364) (xy 39.626685 -117.902378)
			(xy 39.55715 -117.886508) (xy 39.48983 -117.862951) (xy 39.425571 -117.832006) (xy 39.36518 -117.79406)
			(xy 39.309418 -117.749591) (xy 39.258985 -117.699158) (xy 39.214516 -117.643396) (xy 39.17657 -117.583005)
			(xy 39.145625 -117.518746) (xy 39.122068 -117.451426) (xy 39.106198 -117.381891) (xy 39.098212 -117.311017)
			(xy 29.290264 -117.311017) (xy 29.290264 -117.630702) (xy 29.29138 -117.652445) (xy 29.300112 -117.695094)
			(xy 29.315983 -117.735631) (xy 29.338531 -117.77287) (xy 29.367094 -117.805723) (xy 29.400837 -117.833229)
			(xy 29.438774 -117.854582) (xy 29.479795 -117.869158) (xy 29.5227 -117.876531) (xy 29.566233 -117.876485)
			(xy 29.609122 -117.869022) (xy 29.650112 -117.85436) (xy 29.688004 -117.832927) (xy 29.72169 -117.805351)
			(xy 29.736288 -117.789198) (xy 29.76442 -117.756081) (xy 29.825867 -117.694632) (xy 29.892723 -117.639115)
			(xy 29.964415 -117.590004) (xy 30.040333 -117.547717) (xy 30.119829 -117.512615) (xy 30.202225 -117.484998)
			(xy 30.286817 -117.465101) (xy 30.372884 -117.453095) (xy 30.459692 -117.449081) (xy 30.5465 -117.453093)
			(xy 30.632567 -117.465098) (xy 30.71716 -117.484994) (xy 30.799556 -117.512609) (xy 30.879053 -117.54771)
			(xy 30.954971 -117.589995) (xy 31.026665 -117.639105) (xy 31.093521 -117.694621) (xy 31.154969 -117.756069)
			(xy 31.210486 -117.822924) (xy 31.259597 -117.894617) (xy 31.301884 -117.970535) (xy 31.336986 -118.050031)
			(xy 31.364603 -118.132426) (xy 31.384499 -118.217019) (xy 31.396506 -118.303086) (xy 31.400519 -118.389894)
			(xy 31.39851 -118.433358) (xy 34.599874 -118.433358) (xy 34.599874 -118.346458) (xy 34.607892 -118.259929)
			(xy 34.62386 -118.174509) (xy 34.647641 -118.090927) (xy 34.679033 -118.009895) (xy 34.717767 -117.932106)
			(xy 34.763514 -117.858222) (xy 34.815883 -117.788875) (xy 34.874427 -117.724655) (xy 34.938647 -117.666111)
			(xy 35.007994 -117.613742) (xy 35.081878 -117.567995) (xy 35.159667 -117.529261) (xy 35.240699 -117.497869)
			(xy 35.324281 -117.474088) (xy 35.409701 -117.45812) (xy 35.49623 -117.450102) (xy 35.58313 -117.450102)
			(xy 35.669659 -117.45812) (xy 35.755079 -117.474088) (xy 35.838661 -117.497869) (xy 35.919693 -117.529261)
			(xy 35.997482 -117.567995) (xy 36.071366 -117.613742) (xy 36.140713 -117.666111) (xy 36.204933 -117.724655)
			(xy 36.263477 -117.788875) (xy 36.315846 -117.858222) (xy 36.361593 -117.932106) (xy 36.400327 -118.009895)
			(xy 36.431719 -118.090927) (xy 36.4555 -118.174509) (xy 36.471468 -118.259929) (xy 36.479486 -118.346458)
			(xy 36.479988 -118.389908) (xy 36.479486 -118.433358) (xy 36.471468 -118.519887) (xy 36.4555 -118.605307)
			(xy 36.431719 -118.688889) (xy 36.400327 -118.769921) (xy 36.361593 -118.84771) (xy 36.315846 -118.921594)
			(xy 36.263477 -118.990941) (xy 36.204933 -119.055161) (xy 36.140713 -119.113705) (xy 36.099745 -119.144643)
			(xy 39.098212 -119.144643) (xy 39.098212 -119.073321) (xy 39.106198 -119.002447) (xy 39.122068 -118.932912)
			(xy 39.145625 -118.865592) (xy 39.17657 -118.801333) (xy 39.214516 -118.740942) (xy 39.258985 -118.68518)
			(xy 39.309418 -118.634747) (xy 39.36518 -118.590278) (xy 39.425571 -118.552332) (xy 39.48983 -118.521387)
			(xy 39.55715 -118.49783) (xy 39.626685 -118.48196) (xy 39.697559 -118.473974) (xy 39.768881 -118.473974)
			(xy 39.839755 -118.48196) (xy 39.90929 -118.49783) (xy 39.97661 -118.521387) (xy 40.040869 -118.552332)
			(xy 40.10126 -118.590278) (xy 40.157022 -118.634747) (xy 40.207455 -118.68518) (xy 40.251924 -118.740942)
			(xy 40.28987 -118.801333) (xy 40.320815 -118.865592) (xy 40.344372 -118.932912) (xy 40.356116 -118.984369)
			(xy 58.432184 -118.984369) (xy 58.432184 -118.913047) (xy 58.44017 -118.842173) (xy 58.45604 -118.772638)
			(xy 58.479597 -118.705318) (xy 58.510542 -118.641059) (xy 58.548488 -118.580668) (xy 58.592957 -118.524906)
			(xy 58.64339 -118.474473) (xy 58.699152 -118.430004) (xy 58.759543 -118.392058) (xy 58.823802 -118.361113)
			(xy 58.891122 -118.337556) (xy 58.960657 -118.321686) (xy 59.031531 -118.3137) (xy 59.102853 -118.3137)
			(xy 59.173727 -118.321686) (xy 59.243262 -118.337556) (xy 59.310582 -118.361113) (xy 59.374841 -118.392058)
			(xy 59.435232 -118.430004) (xy 59.490994 -118.474473) (xy 59.541427 -118.524906) (xy 59.585896 -118.580668)
			(xy 59.623842 -118.641059) (xy 59.654787 -118.705318) (xy 59.678344 -118.772638) (xy 59.694214 -118.842173)
			(xy 59.7022 -118.913047) (xy 59.7027 -118.948708) (xy 59.7022 -118.984369) (xy 60.673226 -118.984369)
			(xy 60.673226 -118.913047) (xy 60.681212 -118.842173) (xy 60.697082 -118.772638) (xy 60.720639 -118.705318)
			(xy 60.751584 -118.641059) (xy 60.78953 -118.580668) (xy 60.833999 -118.524906) (xy 60.884432 -118.474473)
			(xy 60.940194 -118.430004) (xy 61.000585 -118.392058) (xy 61.064844 -118.361113) (xy 61.132164 -118.337556)
			(xy 61.201699 -118.321686) (xy 61.272573 -118.3137) (xy 61.343895 -118.3137) (xy 61.414769 -118.321686)
			(xy 61.484304 -118.337556) (xy 61.551624 -118.361113) (xy 61.615883 -118.392058) (xy 61.676274 -118.430004)
			(xy 61.732036 -118.474473) (xy 61.782469 -118.524906) (xy 61.826938 -118.580668) (xy 61.864884 -118.641059)
			(xy 61.895829 -118.705318) (xy 61.919386 -118.772638) (xy 61.935256 -118.842173) (xy 61.943242 -118.913047)
			(xy 61.943742 -118.948708) (xy 61.943242 -118.984369) (xy 62.57721 -118.984369) (xy 62.57721 -118.913047)
			(xy 62.585196 -118.842173) (xy 62.601066 -118.772638) (xy 62.624623 -118.705318) (xy 62.655568 -118.641059)
			(xy 62.693514 -118.580668) (xy 62.737983 -118.524906) (xy 62.788416 -118.474473) (xy 62.844178 -118.430004)
			(xy 62.904569 -118.392058) (xy 62.968828 -118.361113) (xy 63.036148 -118.337556) (xy 63.105683 -118.321686)
			(xy 63.176557 -118.3137) (xy 63.247879 -118.3137) (xy 63.318753 -118.321686) (xy 63.388288 -118.337556)
			(xy 63.455608 -118.361113) (xy 63.519867 -118.392058) (xy 63.580258 -118.430004) (xy 63.63602 -118.474473)
			(xy 63.686453 -118.524906) (xy 63.730922 -118.580668) (xy 63.768868 -118.641059) (xy 63.799813 -118.705318)
			(xy 63.82337 -118.772638) (xy 63.83924 -118.842173) (xy 63.847226 -118.913047) (xy 63.847726 -118.948708)
			(xy 63.847226 -118.984369) (xy 63.83924 -119.055243) (xy 63.82337 -119.124778) (xy 63.799813 -119.192098)
			(xy 63.768868 -119.256357) (xy 63.730922 -119.316748) (xy 63.686453 -119.37251) (xy 63.63602 -119.422943)
			(xy 63.580258 -119.467412) (xy 63.519867 -119.505358) (xy 63.455608 -119.536303) (xy 63.388288 -119.55986)
			(xy 63.318753 -119.57573) (xy 63.247879 -119.583716) (xy 63.176557 -119.583716) (xy 63.105683 -119.57573)
			(xy 63.036148 -119.55986) (xy 62.968828 -119.536303) (xy 62.904569 -119.505358) (xy 62.844178 -119.467412)
			(xy 62.788416 -119.422943) (xy 62.737983 -119.37251) (xy 62.693514 -119.316748) (xy 62.655568 -119.256357)
			(xy 62.624623 -119.192098) (xy 62.601066 -119.124778) (xy 62.585196 -119.055243) (xy 62.57721 -118.984369)
			(xy 61.943242 -118.984369) (xy 61.935256 -119.055243) (xy 61.919386 -119.124778) (xy 61.895829 -119.192098)
			(xy 61.864884 -119.256357) (xy 61.826938 -119.316748) (xy 61.782469 -119.37251) (xy 61.732036 -119.422943)
			(xy 61.676274 -119.467412) (xy 61.615883 -119.505358) (xy 61.551624 -119.536303) (xy 61.484304 -119.55986)
			(xy 61.414769 -119.57573) (xy 61.343895 -119.583716) (xy 61.272573 -119.583716) (xy 61.201699 -119.57573)
			(xy 61.132164 -119.55986) (xy 61.064844 -119.536303) (xy 61.000585 -119.505358) (xy 60.940194 -119.467412)
			(xy 60.884432 -119.422943) (xy 60.833999 -119.37251) (xy 60.78953 -119.316748) (xy 60.751584 -119.256357)
			(xy 60.720639 -119.192098) (xy 60.697082 -119.124778) (xy 60.681212 -119.055243) (xy 60.673226 -118.984369)
			(xy 59.7022 -118.984369) (xy 59.694214 -119.055243) (xy 59.678344 -119.124778) (xy 59.654787 -119.192098)
			(xy 59.623842 -119.256357) (xy 59.585896 -119.316748) (xy 59.541427 -119.37251) (xy 59.490994 -119.422943)
			(xy 59.435232 -119.467412) (xy 59.374841 -119.505358) (xy 59.310582 -119.536303) (xy 59.243262 -119.55986)
			(xy 59.173727 -119.57573) (xy 59.102853 -119.583716) (xy 59.031531 -119.583716) (xy 58.960657 -119.57573)
			(xy 58.891122 -119.55986) (xy 58.823802 -119.536303) (xy 58.759543 -119.505358) (xy 58.699152 -119.467412)
			(xy 58.64339 -119.422943) (xy 58.592957 -119.37251) (xy 58.548488 -119.316748) (xy 58.510542 -119.256357)
			(xy 58.479597 -119.192098) (xy 58.45604 -119.124778) (xy 58.44017 -119.055243) (xy 58.432184 -118.984369)
			(xy 40.356116 -118.984369) (xy 40.360242 -119.002447) (xy 40.368228 -119.073321) (xy 40.368728 -119.108982)
			(xy 40.368228 -119.144643) (xy 40.360242 -119.215517) (xy 40.344372 -119.285052) (xy 40.320815 -119.352372)
			(xy 40.28987 -119.416631) (xy 40.251924 -119.477022) (xy 40.207455 -119.532784) (xy 40.157022 -119.583217)
			(xy 40.10126 -119.627686) (xy 40.040869 -119.665632) (xy 39.97661 -119.696577) (xy 39.90929 -119.720134)
			(xy 39.839755 -119.736004) (xy 39.768881 -119.74399) (xy 39.697559 -119.74399) (xy 39.626685 -119.736004)
			(xy 39.55715 -119.720134) (xy 39.48983 -119.696577) (xy 39.425571 -119.665632) (xy 39.36518 -119.627686)
			(xy 39.309418 -119.583217) (xy 39.258985 -119.532784) (xy 39.214516 -119.477022) (xy 39.17657 -119.416631)
			(xy 39.145625 -119.352372) (xy 39.122068 -119.285052) (xy 39.106198 -119.215517) (xy 39.098212 -119.144643)
			(xy 36.099745 -119.144643) (xy 36.071366 -119.166074) (xy 35.997482 -119.211821) (xy 35.919693 -119.250555)
			(xy 35.838661 -119.281947) (xy 35.755079 -119.305728) (xy 35.669659 -119.321696) (xy 35.58313 -119.329714)
			(xy 35.49623 -119.329714) (xy 35.409701 -119.321696) (xy 35.324281 -119.305728) (xy 35.240699 -119.281947)
			(xy 35.159667 -119.250555) (xy 35.081878 -119.211821) (xy 35.007994 -119.166074) (xy 34.938647 -119.113705)
			(xy 34.874427 -119.055161) (xy 34.815883 -118.990941) (xy 34.763514 -118.921594) (xy 34.717767 -118.84771)
			(xy 34.679033 -118.769921) (xy 34.647641 -118.688889) (xy 34.62386 -118.605307) (xy 34.607892 -118.519887)
			(xy 34.599874 -118.433358) (xy 31.39851 -118.433358) (xy 31.396507 -118.476702) (xy 31.384501 -118.562769)
			(xy 31.364606 -118.647362) (xy 31.33699 -118.729758) (xy 31.30189 -118.809254) (xy 31.259604 -118.885173)
			(xy 31.210493 -118.956866) (xy 31.154978 -119.023722) (xy 31.09353 -119.08517) (xy 31.026674 -119.140687)
			(xy 30.954982 -119.189798) (xy 30.879064 -119.232085) (xy 30.799568 -119.267186) (xy 30.717172 -119.294803)
			(xy 30.63258 -119.314699) (xy 30.546512 -119.326706) (xy 30.459704 -119.330719) (xy 30.372896 -119.326707)
			(xy 30.286829 -119.314701) (xy 30.202236 -119.294805) (xy 30.11984 -119.267189) (xy 30.040344 -119.232089)
			(xy 29.964426 -119.189803) (xy 29.892732 -119.140692) (xy 29.825877 -119.085176) (xy 29.764428 -119.023728)
			(xy 29.736288 -118.990618) (xy 29.7217 -118.974467) (xy 29.688014 -118.946916) (xy 29.650127 -118.925506)
			(xy 29.609147 -118.910862) (xy 29.566272 -118.903413) (xy 29.522754 -118.903377) (xy 29.479866 -118.910754)
			(xy 29.438861 -118.925329) (xy 29.400938 -118.946675) (xy 29.367206 -118.97417) (xy 29.338651 -119.007009)
			(xy 29.316106 -119.044232) (xy 29.300232 -119.084751) (xy 29.291492 -119.127383) (xy 29.290264 -119.149114)
			(xy 29.290264 -120.170702) (xy 29.29138 -120.192445) (xy 29.300112 -120.235094) (xy 29.315983 -120.275631)
			(xy 29.338531 -120.31287) (xy 29.367094 -120.345723) (xy 29.400837 -120.373229) (xy 29.438774 -120.394582)
			(xy 29.479795 -120.409158) (xy 29.5227 -120.416531) (xy 29.566233 -120.416485) (xy 29.609122 -120.409022)
			(xy 29.650112 -120.39436) (xy 29.688004 -120.372927) (xy 29.72169 -120.345351) (xy 29.736288 -120.329198)
			(xy 29.76442 -120.296081) (xy 29.825867 -120.234632) (xy 29.892723 -120.179115) (xy 29.964415 -120.130004)
			(xy 30.040333 -120.087717) (xy 30.119829 -120.052615) (xy 30.202225 -120.024998) (xy 30.286817 -120.005101)
			(xy 30.372884 -119.993095) (xy 30.459692 -119.989081) (xy 30.5465 -119.993093) (xy 30.632567 -120.005098)
			(xy 30.71716 -120.024994) (xy 30.799556 -120.052609) (xy 30.879053 -120.08771) (xy 30.954971 -120.129995)
			(xy 31.026665 -120.179105) (xy 31.093521 -120.234621) (xy 31.154969 -120.296069) (xy 31.210486 -120.362924)
			(xy 31.259597 -120.434617) (xy 31.301884 -120.510535) (xy 31.336986 -120.590031) (xy 31.364603 -120.672426)
			(xy 31.384499 -120.757019) (xy 31.396506 -120.843086) (xy 31.400519 -120.929894) (xy 31.39851 -120.973358)
			(xy 34.599874 -120.973358) (xy 34.599874 -120.886458) (xy 34.607892 -120.799929) (xy 34.62386 -120.714509)
			(xy 34.647641 -120.630927) (xy 34.679033 -120.549895) (xy 34.717767 -120.472106) (xy 34.763514 -120.398222)
			(xy 34.815883 -120.328875) (xy 34.874427 -120.264655) (xy 34.938647 -120.206111) (xy 35.007994 -120.153742)
			(xy 35.081878 -120.107995) (xy 35.159667 -120.069261) (xy 35.240699 -120.037869) (xy 35.324281 -120.014088)
			(xy 35.409701 -119.99812) (xy 35.49623 -119.990102) (xy 35.58313 -119.990102) (xy 35.669659 -119.99812)
			(xy 35.755079 -120.014088) (xy 35.838661 -120.037869) (xy 35.919693 -120.069261) (xy 35.997482 -120.107995)
			(xy 36.071366 -120.153742) (xy 36.140713 -120.206111) (xy 36.204933 -120.264655) (xy 36.263477 -120.328875)
			(xy 36.315846 -120.398222) (xy 36.361593 -120.472106) (xy 36.400327 -120.549895) (xy 36.431719 -120.630927)
			(xy 36.4555 -120.714509) (xy 36.471468 -120.799929) (xy 36.479486 -120.886458) (xy 36.479988 -120.929908)
			(xy 36.479486 -120.973358) (xy 36.472794 -121.045579) (xy 39.098212 -121.045579) (xy 39.098212 -120.974257)
			(xy 39.106198 -120.903383) (xy 39.122068 -120.833848) (xy 39.145625 -120.766528) (xy 39.17657 -120.702269)
			(xy 39.214516 -120.641878) (xy 39.258985 -120.586116) (xy 39.309418 -120.535683) (xy 39.36518 -120.491214)
			(xy 39.425571 -120.453268) (xy 39.48983 -120.422323) (xy 39.55715 -120.398766) (xy 39.626685 -120.382896)
			(xy 39.697559 -120.37491) (xy 39.768881 -120.37491) (xy 39.839755 -120.382896) (xy 39.90929 -120.398766)
			(xy 39.97661 -120.422323) (xy 40.040869 -120.453268) (xy 40.10126 -120.491214) (xy 40.157022 -120.535683)
			(xy 40.207455 -120.586116) (xy 40.251924 -120.641878) (xy 40.28987 -120.702269) (xy 40.320815 -120.766528)
			(xy 40.344372 -120.833848) (xy 40.356116 -120.885305) (xy 58.432184 -120.885305) (xy 58.432184 -120.813983)
			(xy 58.44017 -120.743109) (xy 58.45604 -120.673574) (xy 58.479597 -120.606254) (xy 58.510542 -120.541995)
			(xy 58.548488 -120.481604) (xy 58.592957 -120.425842) (xy 58.64339 -120.375409) (xy 58.699152 -120.33094)
			(xy 58.759543 -120.292994) (xy 58.823802 -120.262049) (xy 58.891122 -120.238492) (xy 58.960657 -120.222622)
			(xy 59.031531 -120.214636) (xy 59.102853 -120.214636) (xy 59.173727 -120.222622) (xy 59.243262 -120.238492)
			(xy 59.310582 -120.262049) (xy 59.374841 -120.292994) (xy 59.435232 -120.33094) (xy 59.490994 -120.375409)
			(xy 59.541427 -120.425842) (xy 59.585896 -120.481604) (xy 59.623842 -120.541995) (xy 59.654787 -120.606254)
			(xy 59.678344 -120.673574) (xy 59.694214 -120.743109) (xy 59.7022 -120.813983) (xy 59.7027 -120.849644)
			(xy 59.7022 -120.885305) (xy 60.673226 -120.885305) (xy 60.673226 -120.813983) (xy 60.681212 -120.743109)
			(xy 60.697082 -120.673574) (xy 60.720639 -120.606254) (xy 60.751584 -120.541995) (xy 60.78953 -120.481604)
			(xy 60.833999 -120.425842) (xy 60.884432 -120.375409) (xy 60.940194 -120.33094) (xy 61.000585 -120.292994)
			(xy 61.064844 -120.262049) (xy 61.132164 -120.238492) (xy 61.201699 -120.222622) (xy 61.272573 -120.214636)
			(xy 61.343895 -120.214636) (xy 61.414769 -120.222622) (xy 61.484304 -120.238492) (xy 61.551624 -120.262049)
			(xy 61.615883 -120.292994) (xy 61.676274 -120.33094) (xy 61.732036 -120.375409) (xy 61.782469 -120.425842)
			(xy 61.826938 -120.481604) (xy 61.864884 -120.541995) (xy 61.895829 -120.606254) (xy 61.919386 -120.673574)
			(xy 61.935256 -120.743109) (xy 61.943242 -120.813983) (xy 61.943742 -120.849644) (xy 61.943242 -120.885305)
			(xy 62.57721 -120.885305) (xy 62.57721 -120.813983) (xy 62.585196 -120.743109) (xy 62.601066 -120.673574)
			(xy 62.624623 -120.606254) (xy 62.655568 -120.541995) (xy 62.693514 -120.481604) (xy 62.737983 -120.425842)
			(xy 62.788416 -120.375409) (xy 62.844178 -120.33094) (xy 62.904569 -120.292994) (xy 62.968828 -120.262049)
			(xy 63.036148 -120.238492) (xy 63.105683 -120.222622) (xy 63.176557 -120.214636) (xy 63.247879 -120.214636)
			(xy 63.318753 -120.222622) (xy 63.388288 -120.238492) (xy 63.455608 -120.262049) (xy 63.519867 -120.292994)
			(xy 63.554444 -120.31472) (xy 67.11518 -120.31472) (xy 67.119251 -120.259098) (xy 67.131377 -120.204661)
			(xy 67.1513 -120.15257) (xy 67.178596 -120.103935) (xy 67.212682 -120.059792) (xy 67.252831 -120.021083)
			(xy 67.298189 -119.988632) (xy 67.347789 -119.963131) (xy 67.400573 -119.945124) (xy 67.455416 -119.934994)
			(xy 67.51115 -119.932957) (xy 67.566587 -119.939057) (xy 67.620544 -119.953163) (xy 67.671873 -119.974975)
			(xy 67.719479 -120.004029) (xy 67.762347 -120.039704) (xy 67.799564 -120.081241) (xy 67.830337 -120.127754)
			(xy 67.854009 -120.178251) (xy 67.870077 -120.231658) (xy 67.878197 -120.286834) (xy 67.878706 -120.31472)
			(xy 67.878197 -120.342606) (xy 67.870077 -120.397782) (xy 67.854009 -120.451189) (xy 67.830337 -120.501686)
			(xy 67.799564 -120.548199) (xy 67.762347 -120.589736) (xy 67.719479 -120.625411) (xy 67.671873 -120.654465)
			(xy 67.620544 -120.676277) (xy 67.566587 -120.690383) (xy 67.51115 -120.696483) (xy 67.455416 -120.694446)
			(xy 67.400573 -120.684316) (xy 67.347789 -120.666309) (xy 67.298189 -120.640808) (xy 67.252831 -120.608357)
			(xy 67.212682 -120.569648) (xy 67.178596 -120.525505) (xy 67.1513 -120.47687) (xy 67.131377 -120.424779)
			(xy 67.119251 -120.370342) (xy 67.11518 -120.31472) (xy 63.554444 -120.31472) (xy 63.580258 -120.33094)
			(xy 63.63602 -120.375409) (xy 63.686453 -120.425842) (xy 63.730922 -120.481604) (xy 63.768868 -120.541995)
			(xy 63.799813 -120.606254) (xy 63.82337 -120.673574) (xy 63.83924 -120.743109) (xy 63.847226 -120.813983)
			(xy 63.847726 -120.849644) (xy 63.847226 -120.885305) (xy 63.83924 -120.956179) (xy 63.82337 -121.025714)
			(xy 63.799813 -121.093034) (xy 63.768868 -121.157293) (xy 63.74225 -121.199656) (xy 72.868035 -121.199656)
			(xy 72.872042 -120.996906) (xy 72.884055 -120.794472) (xy 72.904056 -120.592671) (xy 72.932015 -120.391817)
			(xy 72.967886 -120.192225) (xy 73.011615 -119.994206) (xy 73.063133 -119.798069) (xy 73.122359 -119.604121)
			(xy 73.189201 -119.412663) (xy 73.263555 -119.223996) (xy 73.345304 -119.038414) (xy 73.434322 -118.856206)
			(xy 73.530468 -118.677657) (xy 73.633593 -118.503046) (xy 73.743536 -118.332646) (xy 73.860125 -118.166722)
			(xy 73.983178 -118.005533) (xy 74.112503 -117.849332) (xy 74.247898 -117.698362) (xy 74.389151 -117.552858)
			(xy 74.536043 -117.413049) (xy 74.688343 -117.279152) (xy 74.845814 -117.151377) (xy 75.008211 -117.029922)
			(xy 75.175278 -116.914978) (xy 75.346757 -116.806724) (xy 75.522378 -116.705329) (xy 75.701868 -116.610951)
			(xy 75.884946 -116.523739) (xy 76.071327 -116.443827) (xy 76.26072 -116.37134) (xy 76.452828 -116.306393)
			(xy 76.647352 -116.249085) (xy 76.843988 -116.199508) (xy 77.04243 -116.157737) (xy 77.242367 -116.123839)
			(xy 77.443486 -116.097867) (xy 77.645475 -116.07986) (xy 77.848018 -116.069847) (xy 78.050798 -116.067843)
			(xy 78.253499 -116.073853) (xy 78.455804 -116.087865) (xy 78.657398 -116.10986) (xy 78.857965 -116.139801)
			(xy 79.057193 -116.177642) (xy 79.254771 -116.223325) (xy 79.450389 -116.276778) (xy 79.643743 -116.337917)
			(xy 79.834531 -116.406648) (xy 80.022454 -116.482862) (xy 80.20722 -116.566441) (xy 80.388539 -116.657254)
			(xy 80.56613 -116.755159) (xy 80.739713 -116.860004) (xy 80.909019 -116.971625) (xy 81.073784 -117.089847)
			(xy 81.233749 -117.214487) (xy 81.388665 -117.345348) (xy 81.53829 -117.482228) (xy 81.68239 -117.624912)
			(xy 81.820742 -117.773178) (xy 81.953127 -117.926794) (xy 82.079341 -118.085519) (xy 82.199185 -118.249108)
			(xy 82.312473 -118.417303) (xy 82.419028 -118.589842) (xy 82.518683 -118.766457) (xy 82.611283 -118.94687)
			(xy 82.696683 -119.130801) (xy 82.77475 -119.317962) (xy 82.845362 -119.508062) (xy 82.908408 -119.700802)
			(xy 82.963791 -119.895883) (xy 83.011423 -120.093) (xy 83.051231 -120.291844) (xy 83.083153 -120.492106)
			(xy 83.107137 -120.693472) (xy 83.123148 -120.895629) (xy 83.131159 -121.098261) (xy 83.13166 -121.199656)
			(xy 83.131159 -121.301051) (xy 83.123148 -121.503683) (xy 83.107137 -121.70584) (xy 83.083153 -121.907206)
			(xy 83.051231 -122.107468) (xy 83.011423 -122.306312) (xy 82.963791 -122.503429) (xy 82.908408 -122.69851)
			(xy 82.845362 -122.89125) (xy 82.77475 -123.08135) (xy 82.696683 -123.268511) (xy 82.611283 -123.452442)
			(xy 82.518683 -123.632855) (xy 82.419028 -123.80947) (xy 82.312473 -123.982009) (xy 82.199185 -124.150204)
			(xy 82.079341 -124.313793) (xy 81.953127 -124.472518) (xy 81.820742 -124.626134) (xy 81.68239 -124.7744)
			(xy 81.53829 -124.917084) (xy 81.388665 -125.053964) (xy 81.233749 -125.184825) (xy 81.073784 -125.309465)
			(xy 80.909019 -125.427687) (xy 80.739713 -125.539308) (xy 80.56613 -125.644153) (xy 80.388539 -125.742058)
			(xy 80.20722 -125.832871) (xy 80.022454 -125.91645) (xy 79.834531 -125.992664) (xy 79.643743 -126.061395)
			(xy 79.450389 -126.122534) (xy 79.254771 -126.175987) (xy 79.057193 -126.22167) (xy 78.857965 -126.259511)
			(xy 78.657398 -126.289452) (xy 78.455804 -126.311447) (xy 78.253499 -126.325459) (xy 78.050798 -126.331469)
			(xy 77.848018 -126.329465) (xy 77.645475 -126.319452) (xy 77.443486 -126.301445) (xy 77.242367 -126.275473)
			(xy 77.04243 -126.241575) (xy 76.843988 -126.199804) (xy 76.647352 -126.150227) (xy 76.452828 -126.092919)
			(xy 76.26072 -126.027972) (xy 76.071327 -125.955485) (xy 75.884946 -125.875573) (xy 75.701868 -125.788361)
			(xy 75.522378 -125.693983) (xy 75.346757 -125.592588) (xy 75.175278 -125.484334) (xy 75.008211 -125.36939)
			(xy 74.845814 -125.247935) (xy 74.688343 -125.12016) (xy 74.536043 -124.986263) (xy 74.389151 -124.846454)
			(xy 74.247898 -124.70095) (xy 74.112503 -124.54998) (xy 73.983178 -124.393779) (xy 73.860125 -124.23259)
			(xy 73.743536 -124.066666) (xy 73.633593 -123.896266) (xy 73.530468 -123.721655) (xy 73.434322 -123.543106)
			(xy 73.345304 -123.360898) (xy 73.263555 -123.175316) (xy 73.189201 -122.986649) (xy 73.122359 -122.795191)
			(xy 73.063133 -122.601243) (xy 73.011615 -122.405106) (xy 72.967886 -122.207087) (xy 72.932015 -122.007495)
			(xy 72.904056 -121.806641) (xy 72.884055 -121.60484) (xy 72.872042 -121.402406) (xy 72.868035 -121.199656)
			(xy 63.74225 -121.199656) (xy 63.730922 -121.217684) (xy 63.686453 -121.273446) (xy 63.63602 -121.323879)
			(xy 63.580258 -121.368348) (xy 63.519867 -121.406294) (xy 63.455608 -121.437239) (xy 63.388288 -121.460796)
			(xy 63.318753 -121.476666) (xy 63.247879 -121.484652) (xy 63.176557 -121.484652) (xy 63.105683 -121.476666)
			(xy 63.036148 -121.460796) (xy 62.968828 -121.437239) (xy 62.904569 -121.406294) (xy 62.844178 -121.368348)
			(xy 62.788416 -121.323879) (xy 62.737983 -121.273446) (xy 62.693514 -121.217684) (xy 62.655568 -121.157293)
			(xy 62.624623 -121.093034) (xy 62.601066 -121.025714) (xy 62.585196 -120.956179) (xy 62.57721 -120.885305)
			(xy 61.943242 -120.885305) (xy 61.935256 -120.956179) (xy 61.919386 -121.025714) (xy 61.895829 -121.093034)
			(xy 61.864884 -121.157293) (xy 61.826938 -121.217684) (xy 61.782469 -121.273446) (xy 61.732036 -121.323879)
			(xy 61.676274 -121.368348) (xy 61.615883 -121.406294) (xy 61.551624 -121.437239) (xy 61.484304 -121.460796)
			(xy 61.414769 -121.476666) (xy 61.343895 -121.484652) (xy 61.272573 -121.484652) (xy 61.201699 -121.476666)
			(xy 61.132164 -121.460796) (xy 61.064844 -121.437239) (xy 61.000585 -121.406294) (xy 60.940194 -121.368348)
			(xy 60.884432 -121.323879) (xy 60.833999 -121.273446) (xy 60.78953 -121.217684) (xy 60.751584 -121.157293)
			(xy 60.720639 -121.093034) (xy 60.697082 -121.025714) (xy 60.681212 -120.956179) (xy 60.673226 -120.885305)
			(xy 59.7022 -120.885305) (xy 59.694214 -120.956179) (xy 59.678344 -121.025714) (xy 59.654787 -121.093034)
			(xy 59.623842 -121.157293) (xy 59.585896 -121.217684) (xy 59.541427 -121.273446) (xy 59.490994 -121.323879)
			(xy 59.435232 -121.368348) (xy 59.374841 -121.406294) (xy 59.310582 -121.437239) (xy 59.243262 -121.460796)
			(xy 59.173727 -121.476666) (xy 59.102853 -121.484652) (xy 59.031531 -121.484652) (xy 58.960657 -121.476666)
			(xy 58.891122 -121.460796) (xy 58.823802 -121.437239) (xy 58.759543 -121.406294) (xy 58.699152 -121.368348)
			(xy 58.64339 -121.323879) (xy 58.592957 -121.273446) (xy 58.548488 -121.217684) (xy 58.510542 -121.157293)
			(xy 58.479597 -121.093034) (xy 58.45604 -121.025714) (xy 58.44017 -120.956179) (xy 58.432184 -120.885305)
			(xy 40.356116 -120.885305) (xy 40.360242 -120.903383) (xy 40.368228 -120.974257) (xy 40.368728 -121.009918)
			(xy 40.368228 -121.045579) (xy 40.360242 -121.116453) (xy 40.344372 -121.185988) (xy 40.320815 -121.253308)
			(xy 40.28987 -121.317567) (xy 40.251924 -121.377958) (xy 40.207455 -121.43372) (xy 40.157022 -121.484153)
			(xy 40.10126 -121.528622) (xy 40.040869 -121.566568) (xy 39.97661 -121.597513) (xy 39.90929 -121.62107)
			(xy 39.839755 -121.63694) (xy 39.768881 -121.644926) (xy 39.697559 -121.644926) (xy 39.626685 -121.63694)
			(xy 39.55715 -121.62107) (xy 39.48983 -121.597513) (xy 39.425571 -121.566568) (xy 39.36518 -121.528622)
			(xy 39.309418 -121.484153) (xy 39.258985 -121.43372) (xy 39.214516 -121.377958) (xy 39.17657 -121.317567)
			(xy 39.145625 -121.253308) (xy 39.122068 -121.185988) (xy 39.106198 -121.116453) (xy 39.098212 -121.045579)
			(xy 36.472794 -121.045579) (xy 36.471468 -121.059887) (xy 36.4555 -121.145307) (xy 36.431719 -121.228889)
			(xy 36.400327 -121.309921) (xy 36.361593 -121.38771) (xy 36.315846 -121.461594) (xy 36.263477 -121.530941)
			(xy 36.204933 -121.595161) (xy 36.140713 -121.653705) (xy 36.071366 -121.706074) (xy 35.997482 -121.751821)
			(xy 35.919693 -121.790555) (xy 35.838661 -121.821947) (xy 35.755079 -121.845728) (xy 35.669659 -121.861696)
			(xy 35.58313 -121.869714) (xy 35.49623 -121.869714) (xy 35.409701 -121.861696) (xy 35.324281 -121.845728)
			(xy 35.240699 -121.821947) (xy 35.159667 -121.790555) (xy 35.081878 -121.751821) (xy 35.007994 -121.706074)
			(xy 34.938647 -121.653705) (xy 34.874427 -121.595161) (xy 34.815883 -121.530941) (xy 34.763514 -121.461594)
			(xy 34.717767 -121.38771) (xy 34.679033 -121.309921) (xy 34.647641 -121.228889) (xy 34.62386 -121.145307)
			(xy 34.607892 -121.059887) (xy 34.599874 -120.973358) (xy 31.39851 -120.973358) (xy 31.396507 -121.016702)
			(xy 31.384501 -121.102769) (xy 31.364606 -121.187362) (xy 31.33699 -121.269758) (xy 31.30189 -121.349254)
			(xy 31.259604 -121.425173) (xy 31.210493 -121.496866) (xy 31.154978 -121.563722) (xy 31.09353 -121.62517)
			(xy 31.026674 -121.680687) (xy 30.954982 -121.729798) (xy 30.879064 -121.772085) (xy 30.799568 -121.807186)
			(xy 30.717172 -121.834803) (xy 30.63258 -121.854699) (xy 30.546512 -121.866706) (xy 30.459704 -121.870719)
			(xy 30.372896 -121.866707) (xy 30.286829 -121.854701) (xy 30.202236 -121.834805) (xy 30.11984 -121.807189)
			(xy 30.040344 -121.772089) (xy 29.964426 -121.729803) (xy 29.892732 -121.680692) (xy 29.825877 -121.625176)
			(xy 29.764428 -121.563728) (xy 29.736288 -121.530618) (xy 29.7217 -121.514467) (xy 29.688014 -121.486916)
			(xy 29.650127 -121.465506) (xy 29.609147 -121.450862) (xy 29.566272 -121.443413) (xy 29.522754 -121.443377)
			(xy 29.479866 -121.450754) (xy 29.438861 -121.465329) (xy 29.400938 -121.486675) (xy 29.367206 -121.51417)
			(xy 29.338651 -121.547009) (xy 29.316106 -121.584232) (xy 29.300232 -121.624751) (xy 29.291492 -121.667383)
			(xy 29.290264 -121.689114) (xy 29.290264 -122.710702) (xy 29.29138 -122.732445) (xy 29.300112 -122.775094)
			(xy 29.315983 -122.815631) (xy 29.338531 -122.85287) (xy 29.367094 -122.885723) (xy 29.400837 -122.913229)
			(xy 29.438774 -122.934582) (xy 29.479795 -122.949158) (xy 29.5227 -122.956531) (xy 29.566233 -122.956485)
			(xy 29.609122 -122.949022) (xy 29.650112 -122.93436) (xy 29.688004 -122.912927) (xy 29.72169 -122.885351)
			(xy 29.736288 -122.869198) (xy 29.76442 -122.836081) (xy 29.825867 -122.774632) (xy 29.892723 -122.719115)
			(xy 29.964415 -122.670004) (xy 30.040333 -122.627717) (xy 30.119829 -122.592615) (xy 30.202225 -122.564998)
			(xy 30.286817 -122.545101) (xy 30.372884 -122.533095) (xy 30.459692 -122.529081) (xy 30.5465 -122.533093)
			(xy 30.632567 -122.545098) (xy 30.71716 -122.564994) (xy 30.799556 -122.592609) (xy 30.879053 -122.62771)
			(xy 30.954971 -122.669995) (xy 31.026665 -122.719105) (xy 31.093521 -122.774621) (xy 31.154969 -122.836069)
			(xy 31.210486 -122.902924) (xy 31.259597 -122.974617) (xy 31.301884 -123.050535) (xy 31.336986 -123.130031)
			(xy 31.364603 -123.212426) (xy 31.384499 -123.297019) (xy 31.396506 -123.383086) (xy 31.400519 -123.469894)
			(xy 31.39851 -123.513358) (xy 34.599874 -123.513358) (xy 34.599874 -123.426458) (xy 34.607892 -123.339929)
			(xy 34.62386 -123.254509) (xy 34.647641 -123.170927) (xy 34.679033 -123.089895) (xy 34.717767 -123.012106)
			(xy 34.763514 -122.938222) (xy 34.815883 -122.868875) (xy 34.874427 -122.804655) (xy 34.938647 -122.746111)
			(xy 35.007994 -122.693742) (xy 35.081878 -122.647995) (xy 35.159667 -122.609261) (xy 35.240699 -122.577869)
			(xy 35.324281 -122.554088) (xy 35.409701 -122.53812) (xy 35.49623 -122.530102) (xy 35.58313 -122.530102)
			(xy 35.669659 -122.53812) (xy 35.755079 -122.554088) (xy 35.838661 -122.577869) (xy 35.919693 -122.609261)
			(xy 35.997482 -122.647995) (xy 36.071366 -122.693742) (xy 36.107076 -122.720709) (xy 39.098212 -122.720709)
			(xy 39.098212 -122.649387) (xy 39.106198 -122.578513) (xy 39.122068 -122.508978) (xy 39.145625 -122.441658)
			(xy 39.17657 -122.377399) (xy 39.214516 -122.317008) (xy 39.258985 -122.261246) (xy 39.309418 -122.210813)
			(xy 39.36518 -122.166344) (xy 39.425571 -122.128398) (xy 39.48983 -122.097453) (xy 39.55715 -122.073896)
			(xy 39.626685 -122.058026) (xy 39.697559 -122.05004) (xy 39.768881 -122.05004) (xy 39.839755 -122.058026)
			(xy 39.90929 -122.073896) (xy 39.97661 -122.097453) (xy 40.040869 -122.128398) (xy 40.10126 -122.166344)
			(xy 40.157022 -122.210813) (xy 40.207455 -122.261246) (xy 40.251924 -122.317008) (xy 40.28987 -122.377399)
			(xy 40.320815 -122.441658) (xy 40.344372 -122.508978) (xy 40.356116 -122.560435) (xy 58.432184 -122.560435)
			(xy 58.432184 -122.489113) (xy 58.44017 -122.418239) (xy 58.45604 -122.348704) (xy 58.479597 -122.281384)
			(xy 58.510542 -122.217125) (xy 58.548488 -122.156734) (xy 58.592957 -122.100972) (xy 58.64339 -122.050539)
			(xy 58.699152 -122.00607) (xy 58.759543 -121.968124) (xy 58.823802 -121.937179) (xy 58.891122 -121.913622)
			(xy 58.960657 -121.897752) (xy 59.031531 -121.889766) (xy 59.102853 -121.889766) (xy 59.173727 -121.897752)
			(xy 59.243262 -121.913622) (xy 59.310582 -121.937179) (xy 59.374841 -121.968124) (xy 59.435232 -122.00607)
			(xy 59.490994 -122.050539) (xy 59.541427 -122.100972) (xy 59.585896 -122.156734) (xy 59.623842 -122.217125)
			(xy 59.654787 -122.281384) (xy 59.678344 -122.348704) (xy 59.694214 -122.418239) (xy 59.7022 -122.489113)
			(xy 59.7027 -122.524774) (xy 59.7022 -122.560435) (xy 60.673226 -122.560435) (xy 60.673226 -122.489113)
			(xy 60.681212 -122.418239) (xy 60.697082 -122.348704) (xy 60.720639 -122.281384) (xy 60.751584 -122.217125)
			(xy 60.78953 -122.156734) (xy 60.833999 -122.100972) (xy 60.884432 -122.050539) (xy 60.940194 -122.00607)
			(xy 61.000585 -121.968124) (xy 61.064844 -121.937179) (xy 61.132164 -121.913622) (xy 61.201699 -121.897752)
			(xy 61.272573 -121.889766) (xy 61.343895 -121.889766) (xy 61.414769 -121.897752) (xy 61.484304 -121.913622)
			(xy 61.551624 -121.937179) (xy 61.615883 -121.968124) (xy 61.676274 -122.00607) (xy 61.732036 -122.050539)
			(xy 61.782469 -122.100972) (xy 61.826938 -122.156734) (xy 61.864884 -122.217125) (xy 61.895829 -122.281384)
			(xy 61.919386 -122.348704) (xy 61.935256 -122.418239) (xy 61.943242 -122.489113) (xy 61.943742 -122.524774)
			(xy 61.943242 -122.560435) (xy 62.57721 -122.560435) (xy 62.57721 -122.489113) (xy 62.585196 -122.418239)
			(xy 62.601066 -122.348704) (xy 62.624623 -122.281384) (xy 62.655568 -122.217125) (xy 62.693514 -122.156734)
			(xy 62.737983 -122.100972) (xy 62.788416 -122.050539) (xy 62.844178 -122.00607) (xy 62.904569 -121.968124)
			(xy 62.968828 -121.937179) (xy 63.036148 -121.913622) (xy 63.105683 -121.897752) (xy 63.176557 -121.889766)
			(xy 63.247879 -121.889766) (xy 63.318753 -121.897752) (xy 63.388288 -121.913622) (xy 63.455608 -121.937179)
			(xy 63.519867 -121.968124) (xy 63.580258 -122.00607) (xy 63.63602 -122.050539) (xy 63.686453 -122.100972)
			(xy 63.730922 -122.156734) (xy 63.768868 -122.217125) (xy 63.799813 -122.281384) (xy 63.82337 -122.348704)
			(xy 63.83924 -122.418239) (xy 63.847226 -122.489113) (xy 63.847726 -122.524774) (xy 63.847226 -122.560435)
			(xy 63.83924 -122.631309) (xy 63.82337 -122.700844) (xy 63.799813 -122.768164) (xy 63.768868 -122.832423)
			(xy 63.730922 -122.892814) (xy 63.686453 -122.948576) (xy 63.63602 -122.999009) (xy 63.580258 -123.043478)
			(xy 63.519867 -123.081424) (xy 63.455608 -123.112369) (xy 63.388288 -123.135926) (xy 63.318753 -123.151796)
			(xy 63.247879 -123.159782) (xy 63.176557 -123.159782) (xy 63.105683 -123.151796) (xy 63.036148 -123.135926)
			(xy 62.968828 -123.112369) (xy 62.904569 -123.081424) (xy 62.844178 -123.043478) (xy 62.788416 -122.999009)
			(xy 62.737983 -122.948576) (xy 62.693514 -122.892814) (xy 62.655568 -122.832423) (xy 62.624623 -122.768164)
			(xy 62.601066 -122.700844) (xy 62.585196 -122.631309) (xy 62.57721 -122.560435) (xy 61.943242 -122.560435)
			(xy 61.935256 -122.631309) (xy 61.919386 -122.700844) (xy 61.895829 -122.768164) (xy 61.864884 -122.832423)
			(xy 61.826938 -122.892814) (xy 61.782469 -122.948576) (xy 61.732036 -122.999009) (xy 61.676274 -123.043478)
			(xy 61.615883 -123.081424) (xy 61.551624 -123.112369) (xy 61.484304 -123.135926) (xy 61.414769 -123.151796)
			(xy 61.343895 -123.159782) (xy 61.272573 -123.159782) (xy 61.201699 -123.151796) (xy 61.132164 -123.135926)
			(xy 61.064844 -123.112369) (xy 61.000585 -123.081424) (xy 60.940194 -123.043478) (xy 60.884432 -122.999009)
			(xy 60.833999 -122.948576) (xy 60.78953 -122.892814) (xy 60.751584 -122.832423) (xy 60.720639 -122.768164)
			(xy 60.697082 -122.700844) (xy 60.681212 -122.631309) (xy 60.673226 -122.560435) (xy 59.7022 -122.560435)
			(xy 59.694214 -122.631309) (xy 59.678344 -122.700844) (xy 59.654787 -122.768164) (xy 59.623842 -122.832423)
			(xy 59.585896 -122.892814) (xy 59.541427 -122.948576) (xy 59.490994 -122.999009) (xy 59.435232 -123.043478)
			(xy 59.374841 -123.081424) (xy 59.310582 -123.112369) (xy 59.243262 -123.135926) (xy 59.173727 -123.151796)
			(xy 59.102853 -123.159782) (xy 59.031531 -123.159782) (xy 58.960657 -123.151796) (xy 58.891122 -123.135926)
			(xy 58.823802 -123.112369) (xy 58.759543 -123.081424) (xy 58.699152 -123.043478) (xy 58.64339 -122.999009)
			(xy 58.592957 -122.948576) (xy 58.548488 -122.892814) (xy 58.510542 -122.832423) (xy 58.479597 -122.768164)
			(xy 58.45604 -122.700844) (xy 58.44017 -122.631309) (xy 58.432184 -122.560435) (xy 40.356116 -122.560435)
			(xy 40.360242 -122.578513) (xy 40.368228 -122.649387) (xy 40.368728 -122.685048) (xy 40.368228 -122.720709)
			(xy 40.360242 -122.791583) (xy 40.344372 -122.861118) (xy 40.320815 -122.928438) (xy 40.28987 -122.992697)
			(xy 40.251924 -123.053088) (xy 40.207455 -123.10885) (xy 40.157022 -123.159283) (xy 40.10126 -123.203752)
			(xy 40.040869 -123.241698) (xy 39.97661 -123.272643) (xy 39.90929 -123.2962) (xy 39.839755 -123.31207)
			(xy 39.768881 -123.320056) (xy 39.697559 -123.320056) (xy 39.626685 -123.31207) (xy 39.55715 -123.2962)
			(xy 39.48983 -123.272643) (xy 39.425571 -123.241698) (xy 39.36518 -123.203752) (xy 39.309418 -123.159283)
			(xy 39.258985 -123.10885) (xy 39.214516 -123.053088) (xy 39.17657 -122.992697) (xy 39.145625 -122.928438)
			(xy 39.122068 -122.861118) (xy 39.106198 -122.791583) (xy 39.098212 -122.720709) (xy 36.107076 -122.720709)
			(xy 36.140713 -122.746111) (xy 36.204933 -122.804655) (xy 36.263477 -122.868875) (xy 36.315846 -122.938222)
			(xy 36.361593 -123.012106) (xy 36.400327 -123.089895) (xy 36.431719 -123.170927) (xy 36.4555 -123.254509)
			(xy 36.471468 -123.339929) (xy 36.479486 -123.426458) (xy 36.479988 -123.469908) (xy 36.479486 -123.513358)
			(xy 36.471468 -123.599887) (xy 36.4555 -123.685307) (xy 36.431719 -123.768889) (xy 36.400327 -123.849921)
			(xy 36.361593 -123.92771) (xy 36.315846 -124.001594) (xy 36.263477 -124.070941) (xy 36.204933 -124.135161)
			(xy 36.140713 -124.193705) (xy 36.071366 -124.246074) (xy 35.997482 -124.291821) (xy 35.919693 -124.330555)
			(xy 35.838661 -124.361947) (xy 35.755079 -124.385728) (xy 35.669659 -124.401696) (xy 35.58313 -124.409714)
			(xy 35.49623 -124.409714) (xy 35.409701 -124.401696) (xy 35.324281 -124.385728) (xy 35.240699 -124.361947)
			(xy 35.159667 -124.330555) (xy 35.081878 -124.291821) (xy 35.007994 -124.246074) (xy 34.938647 -124.193705)
			(xy 34.874427 -124.135161) (xy 34.815883 -124.070941) (xy 34.763514 -124.001594) (xy 34.717767 -123.92771)
			(xy 34.679033 -123.849921) (xy 34.647641 -123.768889) (xy 34.62386 -123.685307) (xy 34.607892 -123.599887)
			(xy 34.599874 -123.513358) (xy 31.39851 -123.513358) (xy 31.396507 -123.556702) (xy 31.384501 -123.642769)
			(xy 31.364606 -123.727362) (xy 31.33699 -123.809758) (xy 31.30189 -123.889254) (xy 31.259604 -123.965173)
			(xy 31.210493 -124.036866) (xy 31.154978 -124.103722) (xy 31.09353 -124.16517) (xy 31.026674 -124.220687)
			(xy 30.954982 -124.269798) (xy 30.879064 -124.312085) (xy 30.799568 -124.347186) (xy 30.717172 -124.374803)
			(xy 30.63258 -124.394699) (xy 30.546512 -124.406706) (xy 30.459704 -124.410719) (xy 30.372896 -124.406707)
			(xy 30.286829 -124.394701) (xy 30.202236 -124.374805) (xy 30.11984 -124.347189) (xy 30.040344 -124.312089)
			(xy 29.964426 -124.269803) (xy 29.892732 -124.220692) (xy 29.825877 -124.165176) (xy 29.764428 -124.103728)
			(xy 29.736288 -124.070618) (xy 29.7217 -124.054467) (xy 29.688014 -124.026916) (xy 29.650127 -124.005506)
			(xy 29.609147 -123.990862) (xy 29.566272 -123.983413) (xy 29.522754 -123.983377) (xy 29.479866 -123.990754)
			(xy 29.438861 -124.005329) (xy 29.400938 -124.026675) (xy 29.367206 -124.05417) (xy 29.338651 -124.087009)
			(xy 29.316106 -124.124232) (xy 29.300232 -124.164751) (xy 29.291492 -124.207383) (xy 29.290264 -124.229114)
			(xy 29.290264 -124.731881) (xy 39.054778 -124.731881) (xy 39.054778 -124.660559) (xy 39.062764 -124.589685)
			(xy 39.078634 -124.52015) (xy 39.102191 -124.45283) (xy 39.133136 -124.388571) (xy 39.171082 -124.32818)
			(xy 39.215551 -124.272418) (xy 39.265984 -124.221985) (xy 39.321746 -124.177516) (xy 39.382137 -124.13957)
			(xy 39.446396 -124.108625) (xy 39.513716 -124.085068) (xy 39.583251 -124.069198) (xy 39.654125 -124.061212)
			(xy 39.725447 -124.061212) (xy 39.796321 -124.069198) (xy 39.865856 -124.085068) (xy 39.933176 -124.108625)
			(xy 39.997435 -124.13957) (xy 40.057826 -124.177516) (xy 40.113588 -124.221985) (xy 40.164021 -124.272418)
			(xy 40.20849 -124.32818) (xy 40.246436 -124.388571) (xy 40.277381 -124.45283) (xy 40.300938 -124.52015)
			(xy 40.312682 -124.571607) (xy 58.38875 -124.571607) (xy 58.38875 -124.500285) (xy 58.396736 -124.429411)
			(xy 58.412606 -124.359876) (xy 58.436163 -124.292556) (xy 58.467108 -124.228297) (xy 58.505054 -124.167906)
			(xy 58.549523 -124.112144) (xy 58.599956 -124.061711) (xy 58.655718 -124.017242) (xy 58.716109 -123.979296)
			(xy 58.780368 -123.948351) (xy 58.847688 -123.924794) (xy 58.917223 -123.908924) (xy 58.988097 -123.900938)
			(xy 59.059419 -123.900938) (xy 59.130293 -123.908924) (xy 59.199828 -123.924794) (xy 59.267148 -123.948351)
			(xy 59.331407 -123.979296) (xy 59.391798 -124.017242) (xy 59.44756 -124.061711) (xy 59.497993 -124.112144)
			(xy 59.542462 -124.167906) (xy 59.580408 -124.228297) (xy 59.611353 -124.292556) (xy 59.63491 -124.359876)
			(xy 59.65078 -124.429411) (xy 59.658766 -124.500285) (xy 59.659266 -124.535946) (xy 59.658766 -124.571607)
			(xy 60.629792 -124.571607) (xy 60.629792 -124.500285) (xy 60.637778 -124.429411) (xy 60.653648 -124.359876)
			(xy 60.677205 -124.292556) (xy 60.70815 -124.228297) (xy 60.746096 -124.167906) (xy 60.790565 -124.112144)
			(xy 60.840998 -124.061711) (xy 60.89676 -124.017242) (xy 60.957151 -123.979296) (xy 61.02141 -123.948351)
			(xy 61.08873 -123.924794) (xy 61.158265 -123.908924) (xy 61.229139 -123.900938) (xy 61.300461 -123.900938)
			(xy 61.371335 -123.908924) (xy 61.44087 -123.924794) (xy 61.50819 -123.948351) (xy 61.572449 -123.979296)
			(xy 61.63284 -124.017242) (xy 61.688602 -124.061711) (xy 61.739035 -124.112144) (xy 61.783504 -124.167906)
			(xy 61.82145 -124.228297) (xy 61.852395 -124.292556) (xy 61.875952 -124.359876) (xy 61.891822 -124.429411)
			(xy 61.899808 -124.500285) (xy 61.900308 -124.535946) (xy 61.899808 -124.571607) (xy 62.533776 -124.571607)
			(xy 62.533776 -124.500285) (xy 62.541762 -124.429411) (xy 62.557632 -124.359876) (xy 62.581189 -124.292556)
			(xy 62.612134 -124.228297) (xy 62.65008 -124.167906) (xy 62.694549 -124.112144) (xy 62.744982 -124.061711)
			(xy 62.800744 -124.017242) (xy 62.861135 -123.979296) (xy 62.925394 -123.948351) (xy 62.992714 -123.924794)
			(xy 63.062249 -123.908924) (xy 63.133123 -123.900938) (xy 63.204445 -123.900938) (xy 63.275319 -123.908924)
			(xy 63.344854 -123.924794) (xy 63.412174 -123.948351) (xy 63.476433 -123.979296) (xy 63.536824 -124.017242)
			(xy 63.592586 -124.061711) (xy 63.643019 -124.112144) (xy 63.687488 -124.167906) (xy 63.725434 -124.228297)
			(xy 63.756379 -124.292556) (xy 63.779936 -124.359876) (xy 63.795806 -124.429411) (xy 63.803792 -124.500285)
			(xy 63.804292 -124.535946) (xy 63.803792 -124.571607) (xy 63.795806 -124.642481) (xy 63.779936 -124.712016)
			(xy 63.756379 -124.779336) (xy 63.725434 -124.843595) (xy 63.687488 -124.903986) (xy 63.643019 -124.959748)
			(xy 63.592586 -125.010181) (xy 63.536824 -125.05465) (xy 63.476433 -125.092596) (xy 63.412174 -125.123541)
			(xy 63.344854 -125.147098) (xy 63.275319 -125.162968) (xy 63.204445 -125.170954) (xy 63.133123 -125.170954)
			(xy 63.062249 -125.162968) (xy 62.992714 -125.147098) (xy 62.925394 -125.123541) (xy 62.861135 -125.092596)
			(xy 62.800744 -125.05465) (xy 62.744982 -125.010181) (xy 62.694549 -124.959748) (xy 62.65008 -124.903986)
			(xy 62.612134 -124.843595) (xy 62.581189 -124.779336) (xy 62.557632 -124.712016) (xy 62.541762 -124.642481)
			(xy 62.533776 -124.571607) (xy 61.899808 -124.571607) (xy 61.891822 -124.642481) (xy 61.875952 -124.712016)
			(xy 61.852395 -124.779336) (xy 61.82145 -124.843595) (xy 61.783504 -124.903986) (xy 61.739035 -124.959748)
			(xy 61.688602 -125.010181) (xy 61.63284 -125.05465) (xy 61.572449 -125.092596) (xy 61.50819 -125.123541)
			(xy 61.44087 -125.147098) (xy 61.371335 -125.162968) (xy 61.300461 -125.170954) (xy 61.229139 -125.170954)
			(xy 61.158265 -125.162968) (xy 61.08873 -125.147098) (xy 61.02141 -125.123541) (xy 60.957151 -125.092596)
			(xy 60.89676 -125.05465) (xy 60.840998 -125.010181) (xy 60.790565 -124.959748) (xy 60.746096 -124.903986)
			(xy 60.70815 -124.843595) (xy 60.677205 -124.779336) (xy 60.653648 -124.712016) (xy 60.637778 -124.642481)
			(xy 60.629792 -124.571607) (xy 59.658766 -124.571607) (xy 59.65078 -124.642481) (xy 59.63491 -124.712016)
			(xy 59.611353 -124.779336) (xy 59.580408 -124.843595) (xy 59.542462 -124.903986) (xy 59.497993 -124.959748)
			(xy 59.44756 -125.010181) (xy 59.391798 -125.05465) (xy 59.331407 -125.092596) (xy 59.267148 -125.123541)
			(xy 59.199828 -125.147098) (xy 59.130293 -125.162968) (xy 59.059419 -125.170954) (xy 58.988097 -125.170954)
			(xy 58.917223 -125.162968) (xy 58.847688 -125.147098) (xy 58.780368 -125.123541) (xy 58.716109 -125.092596)
			(xy 58.655718 -125.05465) (xy 58.599956 -125.010181) (xy 58.549523 -124.959748) (xy 58.505054 -124.903986)
			(xy 58.467108 -124.843595) (xy 58.436163 -124.779336) (xy 58.412606 -124.712016) (xy 58.396736 -124.642481)
			(xy 58.38875 -124.571607) (xy 40.312682 -124.571607) (xy 40.316808 -124.589685) (xy 40.324794 -124.660559)
			(xy 40.325294 -124.69622) (xy 40.324794 -124.731881) (xy 40.316808 -124.802755) (xy 40.300938 -124.87229)
			(xy 40.277381 -124.93961) (xy 40.246436 -125.003869) (xy 40.20849 -125.06426) (xy 40.164021 -125.120022)
			(xy 40.113588 -125.170455) (xy 40.057826 -125.214924) (xy 39.997435 -125.25287) (xy 39.933176 -125.283815)
			(xy 39.865856 -125.307372) (xy 39.796321 -125.323242) (xy 39.725447 -125.331228) (xy 39.654125 -125.331228)
			(xy 39.583251 -125.323242) (xy 39.513716 -125.307372) (xy 39.446396 -125.283815) (xy 39.382137 -125.25287)
			(xy 39.321746 -125.214924) (xy 39.265984 -125.170455) (xy 39.215551 -125.120022) (xy 39.171082 -125.06426)
			(xy 39.133136 -125.003869) (xy 39.102191 -124.93961) (xy 39.078634 -124.87229) (xy 39.062764 -124.802755)
			(xy 39.054778 -124.731881) (xy 29.290264 -124.731881) (xy 29.290264 -125.250702) (xy 29.29138 -125.272445)
			(xy 29.300112 -125.315094) (xy 29.315983 -125.355631) (xy 29.338531 -125.39287) (xy 29.367094 -125.425723)
			(xy 29.400837 -125.453229) (xy 29.438774 -125.474582) (xy 29.479795 -125.489158) (xy 29.5227 -125.496531)
			(xy 29.566233 -125.496485) (xy 29.609122 -125.489022) (xy 29.650112 -125.47436) (xy 29.688004 -125.452927)
			(xy 29.72169 -125.425351) (xy 29.736288 -125.409198) (xy 29.76442 -125.376081) (xy 29.825867 -125.314632)
			(xy 29.892723 -125.259115) (xy 29.964415 -125.210004) (xy 30.040333 -125.167717) (xy 30.119829 -125.132615)
			(xy 30.202225 -125.104998) (xy 30.286817 -125.085101) (xy 30.372884 -125.073095) (xy 30.459692 -125.069081)
			(xy 30.5465 -125.073093) (xy 30.632567 -125.085098) (xy 30.71716 -125.104994) (xy 30.799556 -125.132609)
			(xy 30.879053 -125.16771) (xy 30.954971 -125.209995) (xy 31.026665 -125.259105) (xy 31.093521 -125.314621)
			(xy 31.154969 -125.376069) (xy 31.210486 -125.442924) (xy 31.259597 -125.514617) (xy 31.301884 -125.590535)
			(xy 31.336986 -125.670031) (xy 31.364603 -125.752426) (xy 31.384499 -125.837019) (xy 31.396506 -125.923086)
			(xy 31.400519 -126.009894) (xy 31.39851 -126.053358) (xy 34.599874 -126.053358) (xy 34.599874 -125.966458)
			(xy 34.607892 -125.879929) (xy 34.62386 -125.794509) (xy 34.647641 -125.710927) (xy 34.679033 -125.629895)
			(xy 34.717767 -125.552106) (xy 34.763514 -125.478222) (xy 34.815883 -125.408875) (xy 34.874427 -125.344655)
			(xy 34.938647 -125.286111) (xy 35.007994 -125.233742) (xy 35.081878 -125.187995) (xy 35.159667 -125.149261)
			(xy 35.240699 -125.117869) (xy 35.324281 -125.094088) (xy 35.409701 -125.07812) (xy 35.49623 -125.070102)
			(xy 35.58313 -125.070102) (xy 35.669659 -125.07812) (xy 35.755079 -125.094088) (xy 35.838661 -125.117869)
			(xy 35.919693 -125.149261) (xy 35.997482 -125.187995) (xy 36.071366 -125.233742) (xy 36.140713 -125.286111)
			(xy 36.204933 -125.344655) (xy 36.263477 -125.408875) (xy 36.315846 -125.478222) (xy 36.361593 -125.552106)
			(xy 36.400327 -125.629895) (xy 36.431719 -125.710927) (xy 36.4555 -125.794509) (xy 36.471468 -125.879929)
			(xy 36.479486 -125.966458) (xy 36.479988 -126.009908) (xy 36.479486 -126.053358) (xy 36.471468 -126.139887)
			(xy 36.4555 -126.225307) (xy 36.431719 -126.308889) (xy 36.400327 -126.389921) (xy 36.361593 -126.46771)
			(xy 36.315846 -126.541594) (xy 36.263477 -126.610941) (xy 36.253028 -126.622403) (xy 39.054778 -126.622403)
			(xy 39.054778 -126.551081) (xy 39.062764 -126.480207) (xy 39.078634 -126.410672) (xy 39.102191 -126.343352)
			(xy 39.133136 -126.279093) (xy 39.171082 -126.218702) (xy 39.215551 -126.16294) (xy 39.265984 -126.112507)
			(xy 39.321746 -126.068038) (xy 39.382137 -126.030092) (xy 39.446396 -125.999147) (xy 39.513716 -125.97559)
			(xy 39.583251 -125.95972) (xy 39.654125 -125.951734) (xy 39.725447 -125.951734) (xy 39.796321 -125.95972)
			(xy 39.865856 -125.97559) (xy 39.933176 -125.999147) (xy 39.997435 -126.030092) (xy 40.057826 -126.068038)
			(xy 40.113588 -126.112507) (xy 40.164021 -126.16294) (xy 40.20849 -126.218702) (xy 40.246436 -126.279093)
			(xy 40.277381 -126.343352) (xy 40.300938 -126.410672) (xy 40.312682 -126.462129) (xy 58.38875 -126.462129)
			(xy 58.38875 -126.390807) (xy 58.396736 -126.319933) (xy 58.412606 -126.250398) (xy 58.436163 -126.183078)
			(xy 58.467108 -126.118819) (xy 58.505054 -126.058428) (xy 58.549523 -126.002666) (xy 58.599956 -125.952233)
			(xy 58.655718 -125.907764) (xy 58.716109 -125.869818) (xy 58.780368 -125.838873) (xy 58.847688 -125.815316)
			(xy 58.917223 -125.799446) (xy 58.988097 -125.79146) (xy 59.059419 -125.79146) (xy 59.130293 -125.799446)
			(xy 59.199828 -125.815316) (xy 59.267148 -125.838873) (xy 59.331407 -125.869818) (xy 59.391798 -125.907764)
			(xy 59.44756 -125.952233) (xy 59.497993 -126.002666) (xy 59.542462 -126.058428) (xy 59.580408 -126.118819)
			(xy 59.611353 -126.183078) (xy 59.63491 -126.250398) (xy 59.65078 -126.319933) (xy 59.658766 -126.390807)
			(xy 59.659266 -126.426468) (xy 59.658766 -126.462129) (xy 60.629792 -126.462129) (xy 60.629792 -126.390807)
			(xy 60.637778 -126.319933) (xy 60.653648 -126.250398) (xy 60.677205 -126.183078) (xy 60.70815 -126.118819)
			(xy 60.746096 -126.058428) (xy 60.790565 -126.002666) (xy 60.840998 -125.952233) (xy 60.89676 -125.907764)
			(xy 60.957151 -125.869818) (xy 61.02141 -125.838873) (xy 61.08873 -125.815316) (xy 61.158265 -125.799446)
			(xy 61.229139 -125.79146) (xy 61.300461 -125.79146) (xy 61.371335 -125.799446) (xy 61.44087 -125.815316)
			(xy 61.50819 -125.838873) (xy 61.572449 -125.869818) (xy 61.63284 -125.907764) (xy 61.688602 -125.952233)
			(xy 61.739035 -126.002666) (xy 61.783504 -126.058428) (xy 61.82145 -126.118819) (xy 61.852395 -126.183078)
			(xy 61.875952 -126.250398) (xy 61.891822 -126.319933) (xy 61.899808 -126.390807) (xy 61.900308 -126.426468)
			(xy 61.899808 -126.462129) (xy 62.533776 -126.462129) (xy 62.533776 -126.390807) (xy 62.541762 -126.319933)
			(xy 62.557632 -126.250398) (xy 62.581189 -126.183078) (xy 62.612134 -126.118819) (xy 62.65008 -126.058428)
			(xy 62.694549 -126.002666) (xy 62.744982 -125.952233) (xy 62.800744 -125.907764) (xy 62.861135 -125.869818)
			(xy 62.925394 -125.838873) (xy 62.992714 -125.815316) (xy 63.062249 -125.799446) (xy 63.133123 -125.79146)
			(xy 63.204445 -125.79146) (xy 63.275319 -125.799446) (xy 63.344854 -125.815316) (xy 63.412174 -125.838873)
			(xy 63.476433 -125.869818) (xy 63.536824 -125.907764) (xy 63.592586 -125.952233) (xy 63.643019 -126.002666)
			(xy 63.687488 -126.058428) (xy 63.725434 -126.118819) (xy 63.756379 -126.183078) (xy 63.779936 -126.250398)
			(xy 63.795806 -126.319933) (xy 63.803792 -126.390807) (xy 63.804292 -126.426468) (xy 63.803792 -126.462129)
			(xy 63.795806 -126.533003) (xy 63.779936 -126.602538) (xy 63.756379 -126.669858) (xy 63.725434 -126.734117)
			(xy 63.687488 -126.794508) (xy 63.643019 -126.85027) (xy 63.592586 -126.900703) (xy 63.536824 -126.945172)
			(xy 63.476433 -126.983118) (xy 63.412174 -127.014063) (xy 63.344854 -127.03762) (xy 63.275319 -127.05349)
			(xy 63.204445 -127.061476) (xy 63.133123 -127.061476) (xy 63.062249 -127.05349) (xy 62.992714 -127.03762)
			(xy 62.925394 -127.014063) (xy 62.861135 -126.983118) (xy 62.800744 -126.945172) (xy 62.744982 -126.900703)
			(xy 62.694549 -126.85027) (xy 62.65008 -126.794508) (xy 62.612134 -126.734117) (xy 62.581189 -126.669858)
			(xy 62.557632 -126.602538) (xy 62.541762 -126.533003) (xy 62.533776 -126.462129) (xy 61.899808 -126.462129)
			(xy 61.891822 -126.533003) (xy 61.875952 -126.602538) (xy 61.852395 -126.669858) (xy 61.82145 -126.734117)
			(xy 61.783504 -126.794508) (xy 61.739035 -126.85027) (xy 61.688602 -126.900703) (xy 61.63284 -126.945172)
			(xy 61.572449 -126.983118) (xy 61.50819 -127.014063) (xy 61.44087 -127.03762) (xy 61.371335 -127.05349)
			(xy 61.300461 -127.061476) (xy 61.229139 -127.061476) (xy 61.158265 -127.05349) (xy 61.08873 -127.03762)
			(xy 61.02141 -127.014063) (xy 60.957151 -126.983118) (xy 60.89676 -126.945172) (xy 60.840998 -126.900703)
			(xy 60.790565 -126.85027) (xy 60.746096 -126.794508) (xy 60.70815 -126.734117) (xy 60.677205 -126.669858)
			(xy 60.653648 -126.602538) (xy 60.637778 -126.533003) (xy 60.629792 -126.462129) (xy 59.658766 -126.462129)
			(xy 59.65078 -126.533003) (xy 59.63491 -126.602538) (xy 59.611353 -126.669858) (xy 59.580408 -126.734117)
			(xy 59.542462 -126.794508) (xy 59.497993 -126.85027) (xy 59.44756 -126.900703) (xy 59.391798 -126.945172)
			(xy 59.331407 -126.983118) (xy 59.267148 -127.014063) (xy 59.199828 -127.03762) (xy 59.130293 -127.05349)
			(xy 59.059419 -127.061476) (xy 58.988097 -127.061476) (xy 58.917223 -127.05349) (xy 58.847688 -127.03762)
			(xy 58.780368 -127.014063) (xy 58.716109 -126.983118) (xy 58.655718 -126.945172) (xy 58.599956 -126.900703)
			(xy 58.549523 -126.85027) (xy 58.505054 -126.794508) (xy 58.467108 -126.734117) (xy 58.436163 -126.669858)
			(xy 58.412606 -126.602538) (xy 58.396736 -126.533003) (xy 58.38875 -126.462129) (xy 40.312682 -126.462129)
			(xy 40.316808 -126.480207) (xy 40.324794 -126.551081) (xy 40.325294 -126.586742) (xy 40.324794 -126.622403)
			(xy 40.316808 -126.693277) (xy 40.300938 -126.762812) (xy 40.277381 -126.830132) (xy 40.246436 -126.894391)
			(xy 40.20849 -126.954782) (xy 40.164021 -127.010544) (xy 40.113588 -127.060977) (xy 40.057826 -127.105446)
			(xy 39.997435 -127.143392) (xy 39.933176 -127.174337) (xy 39.865856 -127.197894) (xy 39.796321 -127.213764)
			(xy 39.725447 -127.22175) (xy 39.654125 -127.22175) (xy 39.583251 -127.213764) (xy 39.513716 -127.197894)
			(xy 39.446396 -127.174337) (xy 39.382137 -127.143392) (xy 39.321746 -127.105446) (xy 39.265984 -127.060977)
			(xy 39.215551 -127.010544) (xy 39.171082 -126.954782) (xy 39.133136 -126.894391) (xy 39.102191 -126.830132)
			(xy 39.078634 -126.762812) (xy 39.062764 -126.693277) (xy 39.054778 -126.622403) (xy 36.253028 -126.622403)
			(xy 36.204933 -126.675161) (xy 36.140713 -126.733705) (xy 36.071366 -126.786074) (xy 35.997482 -126.831821)
			(xy 35.919693 -126.870555) (xy 35.838661 -126.901947) (xy 35.755079 -126.925728) (xy 35.669659 -126.941696)
			(xy 35.58313 -126.949714) (xy 35.49623 -126.949714) (xy 35.409701 -126.941696) (xy 35.324281 -126.925728)
			(xy 35.240699 -126.901947) (xy 35.159667 -126.870555) (xy 35.081878 -126.831821) (xy 35.007994 -126.786074)
			(xy 34.938647 -126.733705) (xy 34.874427 -126.675161) (xy 34.815883 -126.610941) (xy 34.763514 -126.541594)
			(xy 34.717767 -126.46771) (xy 34.679033 -126.389921) (xy 34.647641 -126.308889) (xy 34.62386 -126.225307)
			(xy 34.607892 -126.139887) (xy 34.599874 -126.053358) (xy 31.39851 -126.053358) (xy 31.396507 -126.096702)
			(xy 31.384501 -126.182769) (xy 31.364606 -126.267362) (xy 31.33699 -126.349758) (xy 31.30189 -126.429254)
			(xy 31.259604 -126.505173) (xy 31.210493 -126.576866) (xy 31.154978 -126.643722) (xy 31.09353 -126.70517)
			(xy 31.026674 -126.760687) (xy 30.954982 -126.809798) (xy 30.879064 -126.852085) (xy 30.799568 -126.887186)
			(xy 30.717172 -126.914803) (xy 30.63258 -126.934699) (xy 30.546512 -126.946706) (xy 30.459704 -126.950719)
			(xy 30.372896 -126.946707) (xy 30.286829 -126.934701) (xy 30.202236 -126.914805) (xy 30.11984 -126.887189)
			(xy 30.040344 -126.852089) (xy 29.964426 -126.809803) (xy 29.892732 -126.760692) (xy 29.825877 -126.705176)
			(xy 29.764428 -126.643728) (xy 29.736288 -126.610618) (xy 29.7217 -126.594467) (xy 29.688014 -126.566916)
			(xy 29.650127 -126.545506) (xy 29.609147 -126.530862) (xy 29.566272 -126.523413) (xy 29.522754 -126.523377)
			(xy 29.479866 -126.530754) (xy 29.438861 -126.545329) (xy 29.400938 -126.566675) (xy 29.367206 -126.59417)
			(xy 29.338651 -126.627009) (xy 29.316106 -126.664232) (xy 29.300232 -126.704751) (xy 29.291492 -126.747383)
			(xy 29.290264 -126.769114) (xy 29.290264 -127.790702) (xy 29.29138 -127.812445) (xy 29.300112 -127.855094)
			(xy 29.315983 -127.895631) (xy 29.338531 -127.93287) (xy 29.367094 -127.965723) (xy 29.400837 -127.993229)
			(xy 29.438774 -128.014582) (xy 29.479795 -128.029158) (xy 29.5227 -128.036531) (xy 29.566233 -128.036485)
			(xy 29.609122 -128.029022) (xy 29.650112 -128.01436) (xy 29.688004 -127.992927) (xy 29.72169 -127.965351)
			(xy 29.736288 -127.949198) (xy 29.76442 -127.916081) (xy 29.825867 -127.854632) (xy 29.892723 -127.799115)
			(xy 29.964415 -127.750004) (xy 30.040333 -127.707717) (xy 30.119829 -127.672615) (xy 30.202225 -127.644998)
			(xy 30.286817 -127.625101) (xy 30.372884 -127.613095) (xy 30.459692 -127.609081) (xy 30.5465 -127.613093)
			(xy 30.632567 -127.625098) (xy 30.71716 -127.644994) (xy 30.799556 -127.672609) (xy 30.879053 -127.70771)
			(xy 30.954971 -127.749995) (xy 31.026665 -127.799105) (xy 31.093521 -127.854621) (xy 31.154969 -127.916069)
			(xy 31.210486 -127.982924) (xy 31.259597 -128.054617) (xy 31.301884 -128.130535) (xy 31.336986 -128.210031)
			(xy 31.364603 -128.292426) (xy 31.384499 -128.377019) (xy 31.396506 -128.463086) (xy 31.400519 -128.549894)
			(xy 31.39851 -128.593358) (xy 34.599874 -128.593358) (xy 34.599874 -128.506458) (xy 34.607892 -128.419929)
			(xy 34.62386 -128.334509) (xy 34.647641 -128.250927) (xy 34.679033 -128.169895) (xy 34.717767 -128.092106)
			(xy 34.763514 -128.018222) (xy 34.815883 -127.948875) (xy 34.874427 -127.884655) (xy 34.938647 -127.826111)
			(xy 35.007994 -127.773742) (xy 35.081878 -127.727995) (xy 35.159667 -127.689261) (xy 35.240699 -127.657869)
			(xy 35.324281 -127.634088) (xy 35.409701 -127.61812) (xy 35.49623 -127.610102) (xy 35.58313 -127.610102)
			(xy 35.669659 -127.61812) (xy 35.755079 -127.634088) (xy 35.838661 -127.657869) (xy 35.919693 -127.689261)
			(xy 35.997482 -127.727995) (xy 36.071366 -127.773742) (xy 36.140713 -127.826111) (xy 36.204933 -127.884655)
			(xy 36.263477 -127.948875) (xy 36.315846 -128.018222) (xy 36.361593 -128.092106) (xy 36.400327 -128.169895)
			(xy 36.431719 -128.250927) (xy 36.4555 -128.334509) (xy 36.471468 -128.419929) (xy 36.479486 -128.506458)
			(xy 36.479988 -128.549908) (xy 36.479486 -128.593358) (xy 36.472982 -128.663547) (xy 39.054778 -128.663547)
			(xy 39.054778 -128.592225) (xy 39.062764 -128.521351) (xy 39.078634 -128.451816) (xy 39.102191 -128.384496)
			(xy 39.133136 -128.320237) (xy 39.171082 -128.259846) (xy 39.215551 -128.204084) (xy 39.265984 -128.153651)
			(xy 39.321746 -128.109182) (xy 39.382137 -128.071236) (xy 39.446396 -128.040291) (xy 39.513716 -128.016734)
			(xy 39.583251 -128.000864) (xy 39.654125 -127.992878) (xy 39.725447 -127.992878) (xy 39.796321 -128.000864)
			(xy 39.865856 -128.016734) (xy 39.933176 -128.040291) (xy 39.997435 -128.071236) (xy 40.057826 -128.109182)
			(xy 40.113588 -128.153651) (xy 40.164021 -128.204084) (xy 40.20849 -128.259846) (xy 40.246436 -128.320237)
			(xy 40.277381 -128.384496) (xy 40.300938 -128.451816) (xy 40.316808 -128.521351) (xy 40.324794 -128.592225)
			(xy 40.325294 -128.627886) (xy 40.324794 -128.663547) (xy 40.321152 -128.695873) (xy 47.574952 -128.695873)
			(xy 47.574952 -128.614763) (xy 47.582902 -128.534044) (xy 47.598725 -128.454493) (xy 47.62227 -128.376877)
			(xy 47.653309 -128.301941) (xy 47.691544 -128.230409) (xy 47.736606 -128.162969) (xy 47.788061 -128.10027)
			(xy 47.845414 -128.042917) (xy 47.908113 -127.991462) (xy 47.975553 -127.9464) (xy 48.047085 -127.908165)
			(xy 48.122021 -127.877126) (xy 48.199637 -127.853581) (xy 48.279188 -127.837758) (xy 48.359907 -127.829808)
			(xy 48.441017 -127.829808) (xy 48.521736 -127.837758) (xy 48.601287 -127.853581) (xy 48.678903 -127.877126)
			(xy 48.753839 -127.908165) (xy 48.825371 -127.9464) (xy 48.892811 -127.991462) (xy 48.95551 -128.042917)
			(xy 49.012863 -128.10027) (xy 49.064318 -128.162969) (xy 49.10938 -128.230409) (xy 49.147615 -128.301941)
			(xy 49.178654 -128.376877) (xy 49.202199 -128.454493) (xy 49.211902 -128.503273) (xy 58.38875 -128.503273)
			(xy 58.38875 -128.431951) (xy 58.396736 -128.361077) (xy 58.412606 -128.291542) (xy 58.436163 -128.224222)
			(xy 58.467108 -128.159963) (xy 58.505054 -128.099572) (xy 58.549523 -128.04381) (xy 58.599956 -127.993377)
			(xy 58.655718 -127.948908) (xy 58.716109 -127.910962) (xy 58.780368 -127.880017) (xy 58.847688 -127.85646)
			(xy 58.917223 -127.84059) (xy 58.988097 -127.832604) (xy 59.059419 -127.832604) (xy 59.130293 -127.84059)
			(xy 59.199828 -127.85646) (xy 59.267148 -127.880017) (xy 59.331407 -127.910962) (xy 59.391798 -127.948908)
			(xy 59.44756 -127.993377) (xy 59.497993 -128.04381) (xy 59.542462 -128.099572) (xy 59.580408 -128.159963)
			(xy 59.611353 -128.224222) (xy 59.63491 -128.291542) (xy 59.65078 -128.361077) (xy 59.658766 -128.431951)
			(xy 59.659266 -128.467612) (xy 59.658766 -128.503273) (xy 60.629792 -128.503273) (xy 60.629792 -128.431951)
			(xy 60.637778 -128.361077) (xy 60.653648 -128.291542) (xy 60.677205 -128.224222) (xy 60.70815 -128.159963)
			(xy 60.746096 -128.099572) (xy 60.790565 -128.04381) (xy 60.840998 -127.993377) (xy 60.89676 -127.948908)
			(xy 60.957151 -127.910962) (xy 61.02141 -127.880017) (xy 61.08873 -127.85646) (xy 61.158265 -127.84059)
			(xy 61.229139 -127.832604) (xy 61.300461 -127.832604) (xy 61.371335 -127.84059) (xy 61.44087 -127.85646)
			(xy 61.50819 -127.880017) (xy 61.572449 -127.910962) (xy 61.63284 -127.948908) (xy 61.688602 -127.993377)
			(xy 61.739035 -128.04381) (xy 61.783504 -128.099572) (xy 61.82145 -128.159963) (xy 61.852395 -128.224222)
			(xy 61.875952 -128.291542) (xy 61.891822 -128.361077) (xy 61.899808 -128.431951) (xy 61.900308 -128.467612)
			(xy 61.899808 -128.503273) (xy 62.533776 -128.503273) (xy 62.533776 -128.431951) (xy 62.541762 -128.361077)
			(xy 62.557632 -128.291542) (xy 62.581189 -128.224222) (xy 62.612134 -128.159963) (xy 62.65008 -128.099572)
			(xy 62.694549 -128.04381) (xy 62.744982 -127.993377) (xy 62.800744 -127.948908) (xy 62.861135 -127.910962)
			(xy 62.925394 -127.880017) (xy 62.992714 -127.85646) (xy 63.062249 -127.84059) (xy 63.133123 -127.832604)
			(xy 63.204445 -127.832604) (xy 63.275319 -127.84059) (xy 63.344854 -127.85646) (xy 63.412174 -127.880017)
			(xy 63.476433 -127.910962) (xy 63.536824 -127.948908) (xy 63.592586 -127.993377) (xy 63.643019 -128.04381)
			(xy 63.687488 -128.099572) (xy 63.725434 -128.159963) (xy 63.756379 -128.224222) (xy 63.779936 -128.291542)
			(xy 63.795806 -128.361077) (xy 63.803792 -128.431951) (xy 63.804292 -128.467612) (xy 63.803792 -128.503273)
			(xy 63.795806 -128.574147) (xy 63.779936 -128.643682) (xy 63.756379 -128.711002) (xy 63.725434 -128.775261)
			(xy 63.687488 -128.835652) (xy 63.643019 -128.891414) (xy 63.592586 -128.941847) (xy 63.536824 -128.986316)
			(xy 63.476433 -129.024262) (xy 63.412174 -129.055207) (xy 63.344854 -129.078764) (xy 63.275319 -129.094634)
			(xy 63.204445 -129.10262) (xy 63.133123 -129.10262) (xy 63.062249 -129.094634) (xy 62.992714 -129.078764)
			(xy 62.925394 -129.055207) (xy 62.861135 -129.024262) (xy 62.800744 -128.986316) (xy 62.744982 -128.941847)
			(xy 62.694549 -128.891414) (xy 62.65008 -128.835652) (xy 62.612134 -128.775261) (xy 62.581189 -128.711002)
			(xy 62.557632 -128.643682) (xy 62.541762 -128.574147) (xy 62.533776 -128.503273) (xy 61.899808 -128.503273)
			(xy 61.891822 -128.574147) (xy 61.875952 -128.643682) (xy 61.852395 -128.711002) (xy 61.82145 -128.775261)
			(xy 61.783504 -128.835652) (xy 61.739035 -128.891414) (xy 61.688602 -128.941847) (xy 61.63284 -128.986316)
			(xy 61.572449 -129.024262) (xy 61.50819 -129.055207) (xy 61.44087 -129.078764) (xy 61.371335 -129.094634)
			(xy 61.300461 -129.10262) (xy 61.229139 -129.10262) (xy 61.158265 -129.094634) (xy 61.08873 -129.078764)
			(xy 61.02141 -129.055207) (xy 60.957151 -129.024262) (xy 60.89676 -128.986316) (xy 60.840998 -128.941847)
			(xy 60.790565 -128.891414) (xy 60.746096 -128.835652) (xy 60.70815 -128.775261) (xy 60.677205 -128.711002)
			(xy 60.653648 -128.643682) (xy 60.637778 -128.574147) (xy 60.629792 -128.503273) (xy 59.658766 -128.503273)
			(xy 59.65078 -128.574147) (xy 59.63491 -128.643682) (xy 59.611353 -128.711002) (xy 59.580408 -128.775261)
			(xy 59.542462 -128.835652) (xy 59.497993 -128.891414) (xy 59.44756 -128.941847) (xy 59.391798 -128.986316)
			(xy 59.331407 -129.024262) (xy 59.267148 -129.055207) (xy 59.199828 -129.078764) (xy 59.130293 -129.094634)
			(xy 59.059419 -129.10262) (xy 58.988097 -129.10262) (xy 58.917223 -129.094634) (xy 58.847688 -129.078764)
			(xy 58.780368 -129.055207) (xy 58.716109 -129.024262) (xy 58.655718 -128.986316) (xy 58.599956 -128.941847)
			(xy 58.549523 -128.891414) (xy 58.505054 -128.835652) (xy 58.467108 -128.775261) (xy 58.436163 -128.711002)
			(xy 58.412606 -128.643682) (xy 58.396736 -128.574147) (xy 58.38875 -128.503273) (xy 49.211902 -128.503273)
			(xy 49.218022 -128.534044) (xy 49.225972 -128.614763) (xy 49.22647 -128.655318) (xy 49.225972 -128.695873)
			(xy 49.218022 -128.776592) (xy 49.202199 -128.856143) (xy 49.178654 -128.933759) (xy 49.147615 -129.008695)
			(xy 49.10938 -129.080227) (xy 49.064318 -129.147667) (xy 49.012863 -129.210366) (xy 48.95551 -129.267719)
			(xy 48.892811 -129.319174) (xy 48.825371 -129.364236) (xy 48.753839 -129.402471) (xy 48.678903 -129.43351)
			(xy 48.601287 -129.457055) (xy 48.521736 -129.472878) (xy 48.441017 -129.480828) (xy 48.359907 -129.480828)
			(xy 48.279188 -129.472878) (xy 48.199637 -129.457055) (xy 48.122021 -129.43351) (xy 48.047085 -129.402471)
			(xy 47.975553 -129.364236) (xy 47.908113 -129.319174) (xy 47.845414 -129.267719) (xy 47.788061 -129.210366)
			(xy 47.736606 -129.147667) (xy 47.691544 -129.080227) (xy 47.653309 -129.008695) (xy 47.62227 -128.933759)
			(xy 47.598725 -128.856143) (xy 47.582902 -128.776592) (xy 47.574952 -128.695873) (xy 40.321152 -128.695873)
			(xy 40.316808 -128.734421) (xy 40.300938 -128.803956) (xy 40.277381 -128.871276) (xy 40.246436 -128.935535)
			(xy 40.20849 -128.995926) (xy 40.164021 -129.051688) (xy 40.113588 -129.102121) (xy 40.057826 -129.14659)
			(xy 39.997435 -129.184536) (xy 39.933176 -129.215481) (xy 39.865856 -129.239038) (xy 39.796321 -129.254908)
			(xy 39.725447 -129.262894) (xy 39.654125 -129.262894) (xy 39.583251 -129.254908) (xy 39.513716 -129.239038)
			(xy 39.446396 -129.215481) (xy 39.382137 -129.184536) (xy 39.321746 -129.14659) (xy 39.265984 -129.102121)
			(xy 39.215551 -129.051688) (xy 39.171082 -128.995926) (xy 39.133136 -128.935535) (xy 39.102191 -128.871276)
			(xy 39.078634 -128.803956) (xy 39.062764 -128.734421) (xy 39.054778 -128.663547) (xy 36.472982 -128.663547)
			(xy 36.471468 -128.679887) (xy 36.4555 -128.765307) (xy 36.431719 -128.848889) (xy 36.400327 -128.929921)
			(xy 36.361593 -129.00771) (xy 36.315846 -129.081594) (xy 36.263477 -129.150941) (xy 36.204933 -129.215161)
			(xy 36.140713 -129.273705) (xy 36.071366 -129.326074) (xy 35.997482 -129.371821) (xy 35.919693 -129.410555)
			(xy 35.838661 -129.441947) (xy 35.755079 -129.465728) (xy 35.669659 -129.481696) (xy 35.58313 -129.489714)
			(xy 35.49623 -129.489714) (xy 35.409701 -129.481696) (xy 35.324281 -129.465728) (xy 35.240699 -129.441947)
			(xy 35.159667 -129.410555) (xy 35.081878 -129.371821) (xy 35.007994 -129.326074) (xy 34.938647 -129.273705)
			(xy 34.874427 -129.215161) (xy 34.815883 -129.150941) (xy 34.763514 -129.081594) (xy 34.717767 -129.00771)
			(xy 34.679033 -128.929921) (xy 34.647641 -128.848889) (xy 34.62386 -128.765307) (xy 34.607892 -128.679887)
			(xy 34.599874 -128.593358) (xy 31.39851 -128.593358) (xy 31.396507 -128.636702) (xy 31.384501 -128.722769)
			(xy 31.364606 -128.807362) (xy 31.33699 -128.889758) (xy 31.30189 -128.969254) (xy 31.259604 -129.045173)
			(xy 31.210493 -129.116866) (xy 31.154978 -129.183722) (xy 31.09353 -129.24517) (xy 31.026674 -129.300687)
			(xy 30.954982 -129.349798) (xy 30.879064 -129.392085) (xy 30.799568 -129.427186) (xy 30.717172 -129.454803)
			(xy 30.63258 -129.474699) (xy 30.546512 -129.486706) (xy 30.459704 -129.490719) (xy 30.372896 -129.486707)
			(xy 30.286829 -129.474701) (xy 30.202236 -129.454805) (xy 30.11984 -129.427189) (xy 30.040344 -129.392089)
			(xy 29.964426 -129.349803) (xy 29.892732 -129.300692) (xy 29.825877 -129.245176) (xy 29.764428 -129.183728)
			(xy 29.736288 -129.150618) (xy 29.7217 -129.134467) (xy 29.688014 -129.106916) (xy 29.650127 -129.085506)
			(xy 29.609147 -129.070862) (xy 29.566272 -129.063413) (xy 29.522754 -129.063377) (xy 29.479866 -129.070754)
			(xy 29.438861 -129.085329) (xy 29.400938 -129.106675) (xy 29.367206 -129.13417) (xy 29.338651 -129.167009)
			(xy 29.316106 -129.204232) (xy 29.300232 -129.244751) (xy 29.291492 -129.287383) (xy 29.290264 -129.309114)
			(xy 29.290264 -130.330702) (xy 29.29138 -130.352445) (xy 29.300112 -130.395094) (xy 29.315983 -130.435631)
			(xy 29.338531 -130.47287) (xy 29.367094 -130.505723) (xy 29.400837 -130.533229) (xy 29.438774 -130.554582)
			(xy 29.479795 -130.569158) (xy 29.5227 -130.576531) (xy 29.566233 -130.576485) (xy 29.609122 -130.569022)
			(xy 29.650112 -130.55436) (xy 29.688004 -130.532927) (xy 29.72169 -130.505351) (xy 29.736288 -130.489198)
			(xy 29.76442 -130.456081) (xy 29.825867 -130.394632) (xy 29.892723 -130.339115) (xy 29.964415 -130.290004)
			(xy 30.040333 -130.247717) (xy 30.119829 -130.212615) (xy 30.202225 -130.184998) (xy 30.286817 -130.165101)
			(xy 30.372884 -130.153095) (xy 30.459692 -130.149081) (xy 30.5465 -130.153093) (xy 30.632567 -130.165098)
			(xy 30.71716 -130.184994) (xy 30.799556 -130.212609) (xy 30.879053 -130.24771) (xy 30.954971 -130.289995)
			(xy 31.026665 -130.339105) (xy 31.093521 -130.394621) (xy 31.154969 -130.456069) (xy 31.210486 -130.522924)
			(xy 31.259597 -130.594617) (xy 31.301884 -130.670535) (xy 31.336986 -130.750031) (xy 31.364603 -130.832426)
			(xy 31.384499 -130.917019) (xy 31.396506 -131.003086) (xy 31.400519 -131.089894) (xy 31.39851 -131.133358)
			(xy 34.599874 -131.133358) (xy 34.599874 -131.046458) (xy 34.607892 -130.959929) (xy 34.62386 -130.874509)
			(xy 34.647641 -130.790927) (xy 34.679033 -130.709895) (xy 34.717767 -130.632106) (xy 34.763514 -130.558222)
			(xy 34.815883 -130.488875) (xy 34.874427 -130.424655) (xy 34.938647 -130.366111) (xy 35.007994 -130.313742)
			(xy 35.081878 -130.267995) (xy 35.159667 -130.229261) (xy 35.240699 -130.197869) (xy 35.324281 -130.174088)
			(xy 35.409701 -130.15812) (xy 35.49623 -130.150102) (xy 35.58313 -130.150102) (xy 35.669659 -130.15812)
			(xy 35.755079 -130.174088) (xy 35.838661 -130.197869) (xy 35.919693 -130.229261) (xy 35.997482 -130.267995)
			(xy 36.071366 -130.313742) (xy 36.140713 -130.366111) (xy 36.204933 -130.424655) (xy 36.263477 -130.488875)
			(xy 36.315846 -130.558222) (xy 36.325227 -130.573373) (xy 39.054778 -130.573373) (xy 39.054778 -130.502051)
			(xy 39.062764 -130.431177) (xy 39.078634 -130.361642) (xy 39.102191 -130.294322) (xy 39.133136 -130.230063)
			(xy 39.171082 -130.169672) (xy 39.215551 -130.11391) (xy 39.265984 -130.063477) (xy 39.321746 -130.019008)
			(xy 39.382137 -129.981062) (xy 39.446396 -129.950117) (xy 39.513716 -129.92656) (xy 39.583251 -129.91069)
			(xy 39.654125 -129.902704) (xy 39.725447 -129.902704) (xy 39.796321 -129.91069) (xy 39.865856 -129.92656)
			(xy 39.933176 -129.950117) (xy 39.997435 -129.981062) (xy 40.057826 -130.019008) (xy 40.113588 -130.063477)
			(xy 40.164021 -130.11391) (xy 40.20849 -130.169672) (xy 40.246436 -130.230063) (xy 40.277381 -130.294322)
			(xy 40.300938 -130.361642) (xy 40.312682 -130.413099) (xy 58.38875 -130.413099) (xy 58.38875 -130.341777)
			(xy 58.396736 -130.270903) (xy 58.412606 -130.201368) (xy 58.436163 -130.134048) (xy 58.467108 -130.069789)
			(xy 58.505054 -130.009398) (xy 58.549523 -129.953636) (xy 58.599956 -129.903203) (xy 58.655718 -129.858734)
			(xy 58.716109 -129.820788) (xy 58.780368 -129.789843) (xy 58.847688 -129.766286) (xy 58.917223 -129.750416)
			(xy 58.988097 -129.74243) (xy 59.059419 -129.74243) (xy 59.130293 -129.750416) (xy 59.199828 -129.766286)
			(xy 59.267148 -129.789843) (xy 59.331407 -129.820788) (xy 59.391798 -129.858734) (xy 59.44756 -129.903203)
			(xy 59.497993 -129.953636) (xy 59.542462 -130.009398) (xy 59.580408 -130.069789) (xy 59.611353 -130.134048)
			(xy 59.63491 -130.201368) (xy 59.65078 -130.270903) (xy 59.658766 -130.341777) (xy 59.659266 -130.377438)
			(xy 59.658766 -130.413099) (xy 60.629792 -130.413099) (xy 60.629792 -130.341777) (xy 60.637778 -130.270903)
			(xy 60.653648 -130.201368) (xy 60.677205 -130.134048) (xy 60.70815 -130.069789) (xy 60.746096 -130.009398)
			(xy 60.790565 -129.953636) (xy 60.840998 -129.903203) (xy 60.89676 -129.858734) (xy 60.957151 -129.820788)
			(xy 61.02141 -129.789843) (xy 61.08873 -129.766286) (xy 61.158265 -129.750416) (xy 61.229139 -129.74243)
			(xy 61.300461 -129.74243) (xy 61.371335 -129.750416) (xy 61.44087 -129.766286) (xy 61.50819 -129.789843)
			(xy 61.572449 -129.820788) (xy 61.63284 -129.858734) (xy 61.688602 -129.903203) (xy 61.739035 -129.953636)
			(xy 61.783504 -130.009398) (xy 61.82145 -130.069789) (xy 61.852395 -130.134048) (xy 61.875952 -130.201368)
			(xy 61.891822 -130.270903) (xy 61.899808 -130.341777) (xy 61.900308 -130.377438) (xy 61.899808 -130.413099)
			(xy 62.533776 -130.413099) (xy 62.533776 -130.341777) (xy 62.541762 -130.270903) (xy 62.557632 -130.201368)
			(xy 62.581189 -130.134048) (xy 62.612134 -130.069789) (xy 62.65008 -130.009398) (xy 62.694549 -129.953636)
			(xy 62.744982 -129.903203) (xy 62.800744 -129.858734) (xy 62.861135 -129.820788) (xy 62.925394 -129.789843)
			(xy 62.992714 -129.766286) (xy 63.062249 -129.750416) (xy 63.133123 -129.74243) (xy 63.204445 -129.74243)
			(xy 63.275319 -129.750416) (xy 63.344854 -129.766286) (xy 63.412174 -129.789843) (xy 63.476433 -129.820788)
			(xy 63.536824 -129.858734) (xy 63.592586 -129.903203) (xy 63.643019 -129.953636) (xy 63.687488 -130.009398)
			(xy 63.725434 -130.069789) (xy 63.756379 -130.134048) (xy 63.756577 -130.134614) (xy 68.075046 -130.134614)
			(xy 68.079117 -130.078992) (xy 68.091243 -130.024555) (xy 68.111166 -129.972464) (xy 68.138462 -129.923829)
			(xy 68.172548 -129.879686) (xy 68.212697 -129.840977) (xy 68.258055 -129.808526) (xy 68.307655 -129.783025)
			(xy 68.360439 -129.765018) (xy 68.415282 -129.754888) (xy 68.471016 -129.752851) (xy 68.526453 -129.758951)
			(xy 68.58041 -129.773057) (xy 68.631739 -129.794869) (xy 68.679345 -129.823923) (xy 68.722213 -129.859598)
			(xy 68.75943 -129.901135) (xy 68.790203 -129.947648) (xy 68.813875 -129.998145) (xy 68.829943 -130.051552)
			(xy 68.838063 -130.106728) (xy 68.838572 -130.134614) (xy 69.198234 -130.134614) (xy 69.202305 -130.078992)
			(xy 69.214431 -130.024555) (xy 69.234354 -129.972464) (xy 69.26165 -129.923829) (xy 69.295736 -129.879686)
			(xy 69.335885 -129.840977) (xy 69.381243 -129.808526) (xy 69.430843 -129.783025) (xy 69.483627 -129.765018)
			(xy 69.53847 -129.754888) (xy 69.594204 -129.752851) (xy 69.649641 -129.758951) (xy 69.703598 -129.773057)
			(xy 69.754927 -129.794869) (xy 69.802533 -129.823923) (xy 69.845401 -129.859598) (xy 69.882618 -129.901135)
			(xy 69.913391 -129.947648) (xy 69.937063 -129.998145) (xy 69.953131 -130.051552) (xy 69.961251 -130.106728)
			(xy 69.96176 -130.134614) (xy 70.332852 -130.134614) (xy 70.336923 -130.078992) (xy 70.349049 -130.024555)
			(xy 70.368972 -129.972464) (xy 70.396268 -129.923829) (xy 70.430354 -129.879686) (xy 70.470503 -129.840977)
			(xy 70.515861 -129.808526) (xy 70.565461 -129.783025) (xy 70.618245 -129.765018) (xy 70.673088 -129.754888)
			(xy 70.728822 -129.752851) (xy 70.784259 -129.758951) (xy 70.838216 -129.773057) (xy 70.889545 -129.794869)
			(xy 70.937151 -129.823923) (xy 70.980019 -129.859598) (xy 71.017236 -129.901135) (xy 71.048009 -129.947648)
			(xy 71.071681 -129.998145) (xy 71.087749 -130.051552) (xy 71.095869 -130.106728) (xy 71.096378 -130.134614)
			(xy 71.443086 -130.134614) (xy 71.447157 -130.078992) (xy 71.459283 -130.024555) (xy 71.479206 -129.972464)
			(xy 71.506502 -129.923829) (xy 71.540588 -129.879686) (xy 71.580737 -129.840977) (xy 71.626095 -129.808526)
			(xy 71.675695 -129.783025) (xy 71.728479 -129.765018) (xy 71.783322 -129.754888) (xy 71.839056 -129.752851)
			(xy 71.894493 -129.758951) (xy 71.94845 -129.773057) (xy 71.999779 -129.794869) (xy 72.047385 -129.823923)
			(xy 72.090253 -129.859598) (xy 72.12747 -129.901135) (xy 72.158243 -129.947648) (xy 72.181915 -129.998145)
			(xy 72.197983 -130.051552) (xy 72.206103 -130.106728) (xy 72.206612 -130.134614) (xy 72.206103 -130.1625)
			(xy 72.197983 -130.217676) (xy 72.181915 -130.271083) (xy 72.158243 -130.32158) (xy 72.12747 -130.368093)
			(xy 72.090253 -130.40963) (xy 72.047385 -130.445305) (xy 71.999779 -130.474359) (xy 71.94845 -130.496171)
			(xy 71.894493 -130.510277) (xy 71.839056 -130.516377) (xy 71.783322 -130.51434) (xy 71.728479 -130.50421)
			(xy 71.675695 -130.486203) (xy 71.626095 -130.460702) (xy 71.580737 -130.428251) (xy 71.540588 -130.389542)
			(xy 71.506502 -130.345399) (xy 71.479206 -130.296764) (xy 71.459283 -130.244673) (xy 71.447157 -130.190236)
			(xy 71.443086 -130.134614) (xy 71.096378 -130.134614) (xy 71.095869 -130.1625) (xy 71.087749 -130.217676)
			(xy 71.071681 -130.271083) (xy 71.048009 -130.32158) (xy 71.017236 -130.368093) (xy 70.980019 -130.40963)
			(xy 70.937151 -130.445305) (xy 70.889545 -130.474359) (xy 70.838216 -130.496171) (xy 70.784259 -130.510277)
			(xy 70.728822 -130.516377) (xy 70.673088 -130.51434) (xy 70.618245 -130.50421) (xy 70.565461 -130.486203)
			(xy 70.515861 -130.460702) (xy 70.470503 -130.428251) (xy 70.430354 -130.389542) (xy 70.396268 -130.345399)
			(xy 70.368972 -130.296764) (xy 70.349049 -130.244673) (xy 70.336923 -130.190236) (xy 70.332852 -130.134614)
			(xy 69.96176 -130.134614) (xy 69.961251 -130.1625) (xy 69.953131 -130.217676) (xy 69.937063 -130.271083)
			(xy 69.913391 -130.32158) (xy 69.882618 -130.368093) (xy 69.845401 -130.40963) (xy 69.802533 -130.445305)
			(xy 69.754927 -130.474359) (xy 69.703598 -130.496171) (xy 69.649641 -130.510277) (xy 69.594204 -130.516377)
			(xy 69.53847 -130.51434) (xy 69.483627 -130.50421) (xy 69.430843 -130.486203) (xy 69.381243 -130.460702)
			(xy 69.335885 -130.428251) (xy 69.295736 -130.389542) (xy 69.26165 -130.345399) (xy 69.234354 -130.296764)
			(xy 69.214431 -130.244673) (xy 69.202305 -130.190236) (xy 69.198234 -130.134614) (xy 68.838572 -130.134614)
			(xy 68.838063 -130.1625) (xy 68.829943 -130.217676) (xy 68.813875 -130.271083) (xy 68.790203 -130.32158)
			(xy 68.75943 -130.368093) (xy 68.722213 -130.40963) (xy 68.679345 -130.445305) (xy 68.631739 -130.474359)
			(xy 68.58041 -130.496171) (xy 68.526453 -130.510277) (xy 68.471016 -130.516377) (xy 68.415282 -130.51434)
			(xy 68.360439 -130.50421) (xy 68.307655 -130.486203) (xy 68.258055 -130.460702) (xy 68.212697 -130.428251)
			(xy 68.172548 -130.389542) (xy 68.138462 -130.345399) (xy 68.111166 -130.296764) (xy 68.091243 -130.244673)
			(xy 68.079117 -130.190236) (xy 68.075046 -130.134614) (xy 63.756577 -130.134614) (xy 63.779936 -130.201368)
			(xy 63.795806 -130.270903) (xy 63.803792 -130.341777) (xy 63.804292 -130.377438) (xy 63.803792 -130.413099)
			(xy 63.795806 -130.483973) (xy 63.779936 -130.553508) (xy 63.756379 -130.620828) (xy 63.725434 -130.685087)
			(xy 63.687488 -130.745478) (xy 63.643019 -130.80124) (xy 63.592586 -130.851673) (xy 63.536824 -130.896142)
			(xy 63.476433 -130.934088) (xy 63.412174 -130.965033) (xy 63.344854 -130.98859) (xy 63.275319 -131.00446)
			(xy 63.204445 -131.012446) (xy 63.133123 -131.012446) (xy 63.062249 -131.00446) (xy 62.992714 -130.98859)
			(xy 62.925394 -130.965033) (xy 62.861135 -130.934088) (xy 62.800744 -130.896142) (xy 62.744982 -130.851673)
			(xy 62.694549 -130.80124) (xy 62.65008 -130.745478) (xy 62.612134 -130.685087) (xy 62.581189 -130.620828)
			(xy 62.557632 -130.553508) (xy 62.541762 -130.483973) (xy 62.533776 -130.413099) (xy 61.899808 -130.413099)
			(xy 61.891822 -130.483973) (xy 61.875952 -130.553508) (xy 61.852395 -130.620828) (xy 61.82145 -130.685087)
			(xy 61.783504 -130.745478) (xy 61.739035 -130.80124) (xy 61.688602 -130.851673) (xy 61.63284 -130.896142)
			(xy 61.572449 -130.934088) (xy 61.50819 -130.965033) (xy 61.44087 -130.98859) (xy 61.371335 -131.00446)
			(xy 61.300461 -131.012446) (xy 61.229139 -131.012446) (xy 61.158265 -131.00446) (xy 61.08873 -130.98859)
			(xy 61.02141 -130.965033) (xy 60.957151 -130.934088) (xy 60.89676 -130.896142) (xy 60.840998 -130.851673)
			(xy 60.790565 -130.80124) (xy 60.746096 -130.745478) (xy 60.70815 -130.685087) (xy 60.677205 -130.620828)
			(xy 60.653648 -130.553508) (xy 60.637778 -130.483973) (xy 60.629792 -130.413099) (xy 59.658766 -130.413099)
			(xy 59.65078 -130.483973) (xy 59.63491 -130.553508) (xy 59.611353 -130.620828) (xy 59.580408 -130.685087)
			(xy 59.542462 -130.745478) (xy 59.497993 -130.80124) (xy 59.44756 -130.851673) (xy 59.391798 -130.896142)
			(xy 59.331407 -130.934088) (xy 59.267148 -130.965033) (xy 59.199828 -130.98859) (xy 59.130293 -131.00446)
			(xy 59.059419 -131.012446) (xy 58.988097 -131.012446) (xy 58.917223 -131.00446) (xy 58.847688 -130.98859)
			(xy 58.780368 -130.965033) (xy 58.716109 -130.934088) (xy 58.655718 -130.896142) (xy 58.599956 -130.851673)
			(xy 58.549523 -130.80124) (xy 58.505054 -130.745478) (xy 58.467108 -130.685087) (xy 58.436163 -130.620828)
			(xy 58.412606 -130.553508) (xy 58.396736 -130.483973) (xy 58.38875 -130.413099) (xy 40.312682 -130.413099)
			(xy 40.316808 -130.431177) (xy 40.324794 -130.502051) (xy 40.325294 -130.537712) (xy 40.324794 -130.573373)
			(xy 40.316808 -130.644247) (xy 40.300938 -130.713782) (xy 40.277381 -130.781102) (xy 40.246436 -130.845361)
			(xy 40.20849 -130.905752) (xy 40.164021 -130.961514) (xy 40.113588 -131.011947) (xy 40.057826 -131.056416)
			(xy 39.997435 -131.094362) (xy 39.933176 -131.125307) (xy 39.865856 -131.148864) (xy 39.796321 -131.164734)
			(xy 39.725447 -131.17272) (xy 39.654125 -131.17272) (xy 39.583251 -131.164734) (xy 39.513716 -131.148864)
			(xy 39.446396 -131.125307) (xy 39.382137 -131.094362) (xy 39.321746 -131.056416) (xy 39.265984 -131.011947)
			(xy 39.215551 -130.961514) (xy 39.171082 -130.905752) (xy 39.133136 -130.845361) (xy 39.102191 -130.781102)
			(xy 39.078634 -130.713782) (xy 39.062764 -130.644247) (xy 39.054778 -130.573373) (xy 36.325227 -130.573373)
			(xy 36.361593 -130.632106) (xy 36.400327 -130.709895) (xy 36.431719 -130.790927) (xy 36.4555 -130.874509)
			(xy 36.471468 -130.959929) (xy 36.479486 -131.046458) (xy 36.479988 -131.089908) (xy 36.479486 -131.133358)
			(xy 36.471468 -131.219887) (xy 36.4555 -131.305307) (xy 36.431719 -131.388889) (xy 36.400327 -131.469921)
			(xy 36.361593 -131.54771) (xy 36.315846 -131.621594) (xy 36.263477 -131.690941) (xy 36.204933 -131.755161)
			(xy 36.140713 -131.813705) (xy 36.071366 -131.866074) (xy 35.997482 -131.911821) (xy 35.919693 -131.950555)
			(xy 35.838661 -131.981947) (xy 35.755079 -132.005728) (xy 35.669659 -132.021696) (xy 35.58313 -132.029714)
			(xy 35.49623 -132.029714) (xy 35.409701 -132.021696) (xy 35.324281 -132.005728) (xy 35.240699 -131.981947)
			(xy 35.159667 -131.950555) (xy 35.081878 -131.911821) (xy 35.007994 -131.866074) (xy 34.938647 -131.813705)
			(xy 34.874427 -131.755161) (xy 34.815883 -131.690941) (xy 34.763514 -131.621594) (xy 34.717767 -131.54771)
			(xy 34.679033 -131.469921) (xy 34.647641 -131.388889) (xy 34.62386 -131.305307) (xy 34.607892 -131.219887)
			(xy 34.599874 -131.133358) (xy 31.39851 -131.133358) (xy 31.396507 -131.176702) (xy 31.384501 -131.262769)
			(xy 31.364606 -131.347362) (xy 31.33699 -131.429758) (xy 31.30189 -131.509254) (xy 31.259604 -131.585173)
			(xy 31.210493 -131.656866) (xy 31.154978 -131.723722) (xy 31.09353 -131.78517) (xy 31.026674 -131.840687)
			(xy 30.954982 -131.889798) (xy 30.879064 -131.932085) (xy 30.799568 -131.967186) (xy 30.717172 -131.994803)
			(xy 30.63258 -132.014699) (xy 30.546512 -132.026706) (xy 30.459704 -132.030719) (xy 30.372896 -132.026707)
			(xy 30.286829 -132.014701) (xy 30.202236 -131.994805) (xy 30.11984 -131.967189) (xy 30.040344 -131.932089)
			(xy 29.964426 -131.889803) (xy 29.892732 -131.840692) (xy 29.825877 -131.785176) (xy 29.764428 -131.723728)
			(xy 29.736288 -131.690618) (xy 29.7217 -131.674467) (xy 29.688014 -131.646916) (xy 29.650127 -131.625506)
			(xy 29.609147 -131.610862) (xy 29.566272 -131.603413) (xy 29.522754 -131.603377) (xy 29.479866 -131.610754)
			(xy 29.438861 -131.625329) (xy 29.400938 -131.646675) (xy 29.367206 -131.67417) (xy 29.338651 -131.707009)
			(xy 29.316106 -131.744232) (xy 29.300232 -131.784751) (xy 29.291492 -131.827383) (xy 29.290264 -131.849114)
			(xy 29.290264 -132.870702) (xy 29.29138 -132.892445) (xy 29.300112 -132.935094) (xy 29.315983 -132.975631)
			(xy 29.338531 -133.01287) (xy 29.367094 -133.045723) (xy 29.400837 -133.073229) (xy 29.438774 -133.094582)
			(xy 29.479795 -133.109158) (xy 29.5227 -133.116531) (xy 29.566233 -133.116485) (xy 29.609122 -133.109022)
			(xy 29.650112 -133.09436) (xy 29.688004 -133.072927) (xy 29.72169 -133.045351) (xy 29.736288 -133.029198)
			(xy 29.76442 -132.996081) (xy 29.825867 -132.934632) (xy 29.892723 -132.879115) (xy 29.964415 -132.830004)
			(xy 30.040333 -132.787717) (xy 30.119829 -132.752615) (xy 30.202225 -132.724998) (xy 30.286817 -132.705101)
			(xy 30.372884 -132.693095) (xy 30.459692 -132.689081) (xy 30.5465 -132.693093) (xy 30.632567 -132.705098)
			(xy 30.71716 -132.724994) (xy 30.799556 -132.752609) (xy 30.879053 -132.78771) (xy 30.954971 -132.829995)
			(xy 31.026665 -132.879105) (xy 31.093521 -132.934621) (xy 31.154969 -132.996069) (xy 31.210486 -133.062924)
			(xy 31.259597 -133.134617) (xy 31.301884 -133.210535) (xy 31.336986 -133.290031) (xy 31.364603 -133.372426)
			(xy 31.384499 -133.457019) (xy 31.396506 -133.543086) (xy 31.400519 -133.629894) (xy 31.39851 -133.673358)
			(xy 34.599874 -133.673358) (xy 34.599874 -133.586458) (xy 34.607892 -133.499929) (xy 34.62386 -133.414509)
			(xy 34.647641 -133.330927) (xy 34.679033 -133.249895) (xy 34.717767 -133.172106) (xy 34.763514 -133.098222)
			(xy 34.815883 -133.028875) (xy 34.874427 -132.964655) (xy 34.938647 -132.906111) (xy 35.007994 -132.853742)
			(xy 35.081878 -132.807995) (xy 35.159667 -132.769261) (xy 35.240699 -132.737869) (xy 35.324281 -132.714088)
			(xy 35.409701 -132.69812) (xy 35.49623 -132.690102) (xy 35.58313 -132.690102) (xy 35.669659 -132.69812)
			(xy 35.755079 -132.714088) (xy 35.838661 -132.737869) (xy 35.919693 -132.769261) (xy 35.997482 -132.807995)
			(xy 36.071366 -132.853742) (xy 36.140713 -132.906111) (xy 36.204933 -132.964655) (xy 36.263477 -133.028875)
			(xy 36.315846 -133.098222) (xy 36.361593 -133.172106) (xy 36.400327 -133.249895) (xy 36.431719 -133.330927)
			(xy 36.4555 -133.414509) (xy 36.471468 -133.499929) (xy 36.479486 -133.586458) (xy 36.479988 -133.629908)
			(xy 36.479486 -133.673358) (xy 36.471468 -133.759887) (xy 36.4555 -133.845307) (xy 36.431719 -133.928889)
			(xy 36.400327 -134.009921) (xy 36.361593 -134.08771) (xy 36.315846 -134.161594) (xy 36.263477 -134.230941)
			(xy 36.204933 -134.295161) (xy 36.140713 -134.353705) (xy 36.071366 -134.406074) (xy 35.997482 -134.451821)
			(xy 35.919693 -134.490555) (xy 35.838661 -134.521947) (xy 35.755079 -134.545728) (xy 35.669659 -134.561696)
			(xy 35.58313 -134.569714) (xy 35.49623 -134.569714) (xy 35.409701 -134.561696) (xy 35.324281 -134.545728)
			(xy 35.240699 -134.521947) (xy 35.159667 -134.490555) (xy 35.081878 -134.451821) (xy 35.007994 -134.406074)
			(xy 34.938647 -134.353705) (xy 34.874427 -134.295161) (xy 34.815883 -134.230941) (xy 34.763514 -134.161594)
			(xy 34.717767 -134.08771) (xy 34.679033 -134.009921) (xy 34.647641 -133.928889) (xy 34.62386 -133.845307)
			(xy 34.607892 -133.759887) (xy 34.599874 -133.673358) (xy 31.39851 -133.673358) (xy 31.396507 -133.716702)
			(xy 31.384501 -133.802769) (xy 31.364606 -133.887362) (xy 31.33699 -133.969758) (xy 31.30189 -134.049254)
			(xy 31.259604 -134.125173) (xy 31.210493 -134.196866) (xy 31.154978 -134.263722) (xy 31.09353 -134.32517)
			(xy 31.026674 -134.380687) (xy 30.954982 -134.429798) (xy 30.879064 -134.472085) (xy 30.799568 -134.507186)
			(xy 30.717172 -134.534803) (xy 30.63258 -134.554699) (xy 30.546512 -134.566706) (xy 30.459704 -134.570719)
			(xy 30.372896 -134.566707) (xy 30.286829 -134.554701) (xy 30.202236 -134.534805) (xy 30.11984 -134.507189)
			(xy 30.040344 -134.472089) (xy 29.964426 -134.429803) (xy 29.892732 -134.380692) (xy 29.825877 -134.325176)
			(xy 29.764428 -134.263728) (xy 29.736288 -134.230618) (xy 29.7217 -134.214467) (xy 29.688014 -134.186916)
			(xy 29.650127 -134.165506) (xy 29.609147 -134.150862) (xy 29.566272 -134.143413) (xy 29.522754 -134.143377)
			(xy 29.479866 -134.150754) (xy 29.438861 -134.165329) (xy 29.400938 -134.186675) (xy 29.367206 -134.21417)
			(xy 29.338651 -134.247009) (xy 29.316106 -134.284232) (xy 29.300232 -134.324751) (xy 29.291492 -134.367383)
			(xy 29.290264 -134.389114) (xy 29.290264 -135.410702) (xy 29.29138 -135.432445) (xy 29.300112 -135.475094)
			(xy 29.315983 -135.515631) (xy 29.338531 -135.55287) (xy 29.367094 -135.585723) (xy 29.400837 -135.613229)
			(xy 29.438774 -135.634582) (xy 29.479795 -135.649158) (xy 29.5227 -135.656531) (xy 29.566233 -135.656485)
			(xy 29.609122 -135.649022) (xy 29.650112 -135.63436) (xy 29.688004 -135.612927) (xy 29.72169 -135.585351)
			(xy 29.736288 -135.569198) (xy 29.76442 -135.536081) (xy 29.825867 -135.474632) (xy 29.892723 -135.419115)
			(xy 29.964415 -135.370004) (xy 30.040333 -135.327717) (xy 30.119829 -135.292615) (xy 30.202225 -135.264998)
			(xy 30.286817 -135.245101) (xy 30.372884 -135.233095) (xy 30.459692 -135.229081) (xy 30.5465 -135.233093)
			(xy 30.632567 -135.245098) (xy 30.71716 -135.264994) (xy 30.799556 -135.292609) (xy 30.879053 -135.32771)
			(xy 30.954971 -135.369995) (xy 31.026665 -135.419105) (xy 31.093521 -135.474621) (xy 31.154969 -135.536069)
			(xy 31.210486 -135.602924) (xy 31.259597 -135.674617) (xy 31.301884 -135.750535) (xy 31.336986 -135.830031)
			(xy 31.364603 -135.912426) (xy 31.384499 -135.997019) (xy 31.396506 -136.083086) (xy 31.400519 -136.169894)
			(xy 31.39851 -136.213358) (xy 34.599874 -136.213358) (xy 34.599874 -136.126458) (xy 34.607892 -136.039929)
			(xy 34.62386 -135.954509) (xy 34.647641 -135.870927) (xy 34.679033 -135.789895) (xy 34.717767 -135.712106)
			(xy 34.763514 -135.638222) (xy 34.815883 -135.568875) (xy 34.874427 -135.504655) (xy 34.938647 -135.446111)
			(xy 35.007994 -135.393742) (xy 35.081878 -135.347995) (xy 35.159667 -135.309261) (xy 35.240699 -135.277869)
			(xy 35.324281 -135.254088) (xy 35.409701 -135.23812) (xy 35.49623 -135.230102) (xy 35.58313 -135.230102)
			(xy 35.669659 -135.23812) (xy 35.755079 -135.254088) (xy 35.838661 -135.277869) (xy 35.919693 -135.309261)
			(xy 35.997482 -135.347995) (xy 36.071366 -135.393742) (xy 36.140713 -135.446111) (xy 36.204933 -135.504655)
			(xy 36.263477 -135.568875) (xy 36.315846 -135.638222) (xy 36.361593 -135.712106) (xy 36.400327 -135.789895)
			(xy 36.431719 -135.870927) (xy 36.4555 -135.954509) (xy 36.471468 -136.039929) (xy 36.479486 -136.126458)
			(xy 36.479988 -136.169908) (xy 36.479486 -136.213358) (xy 36.471468 -136.299887) (xy 36.4555 -136.385307)
			(xy 36.431719 -136.468889) (xy 36.400327 -136.549921) (xy 36.361593 -136.62771) (xy 36.315846 -136.701594)
			(xy 36.263477 -136.770941) (xy 36.204933 -136.835161) (xy 36.140713 -136.893705) (xy 36.071366 -136.946074)
			(xy 35.997482 -136.991821) (xy 35.919693 -137.030555) (xy 35.838661 -137.061947) (xy 35.755079 -137.085728)
			(xy 35.669659 -137.101696) (xy 35.58313 -137.109714) (xy 35.49623 -137.109714) (xy 35.409701 -137.101696)
			(xy 35.324281 -137.085728) (xy 35.240699 -137.061947) (xy 35.159667 -137.030555) (xy 35.081878 -136.991821)
			(xy 35.007994 -136.946074) (xy 34.938647 -136.893705) (xy 34.874427 -136.835161) (xy 34.815883 -136.770941)
			(xy 34.763514 -136.701594) (xy 34.717767 -136.62771) (xy 34.679033 -136.549921) (xy 34.647641 -136.468889)
			(xy 34.62386 -136.385307) (xy 34.607892 -136.299887) (xy 34.599874 -136.213358) (xy 31.39851 -136.213358)
			(xy 31.396507 -136.256702) (xy 31.384501 -136.342769) (xy 31.364606 -136.427362) (xy 31.33699 -136.509758)
			(xy 31.30189 -136.589254) (xy 31.259604 -136.665173) (xy 31.210493 -136.736866) (xy 31.154978 -136.803722)
			(xy 31.09353 -136.86517) (xy 31.026674 -136.920687) (xy 30.954982 -136.969798) (xy 30.879064 -137.012085)
			(xy 30.799568 -137.047186) (xy 30.717172 -137.074803) (xy 30.63258 -137.094699) (xy 30.546512 -137.106706)
			(xy 30.459704 -137.110719) (xy 30.372896 -137.106707) (xy 30.286829 -137.094701) (xy 30.202236 -137.074805)
			(xy 30.11984 -137.047189) (xy 30.040344 -137.012089) (xy 29.964426 -136.969803) (xy 29.892732 -136.920692)
			(xy 29.825877 -136.865176) (xy 29.764428 -136.803728) (xy 29.736288 -136.770618) (xy 29.7217 -136.754467)
			(xy 29.688014 -136.726916) (xy 29.650127 -136.705506) (xy 29.609147 -136.690862) (xy 29.566272 -136.683413)
			(xy 29.522754 -136.683377) (xy 29.479866 -136.690754) (xy 29.438861 -136.705329) (xy 29.400938 -136.726675)
			(xy 29.367206 -136.75417) (xy 29.338651 -136.787009) (xy 29.316106 -136.824232) (xy 29.300232 -136.864751)
			(xy 29.291492 -136.907383) (xy 29.290264 -136.929114) (xy 29.290264 -137.950702) (xy 29.29138 -137.972445)
			(xy 29.300112 -138.015094) (xy 29.315983 -138.055631) (xy 29.338531 -138.09287) (xy 29.367094 -138.125723)
			(xy 29.400837 -138.153229) (xy 29.438774 -138.174582) (xy 29.479795 -138.189158) (xy 29.5227 -138.196531)
			(xy 29.566233 -138.196485) (xy 29.609122 -138.189022) (xy 29.650112 -138.17436) (xy 29.688004 -138.152927)
			(xy 29.72169 -138.125351) (xy 29.736288 -138.109198) (xy 29.76442 -138.076081) (xy 29.825867 -138.014632)
			(xy 29.892723 -137.959115) (xy 29.964415 -137.910004) (xy 30.040333 -137.867717) (xy 30.119829 -137.832615)
			(xy 30.202225 -137.804998) (xy 30.286817 -137.785101) (xy 30.372884 -137.773095) (xy 30.459692 -137.769081)
			(xy 30.5465 -137.773093) (xy 30.632567 -137.785098) (xy 30.71716 -137.804994) (xy 30.799556 -137.832609)
			(xy 30.879053 -137.86771) (xy 30.954971 -137.909995) (xy 31.026665 -137.959105) (xy 31.093521 -138.014621)
			(xy 31.154969 -138.076069) (xy 31.210486 -138.142924) (xy 31.259597 -138.214617) (xy 31.301884 -138.290535)
			(xy 31.336986 -138.370031) (xy 31.364603 -138.452426) (xy 31.384499 -138.537019) (xy 31.396506 -138.623086)
			(xy 31.400519 -138.709894) (xy 31.39851 -138.753358) (xy 34.599874 -138.753358) (xy 34.599874 -138.666458)
			(xy 34.607892 -138.579929) (xy 34.62386 -138.494509) (xy 34.647641 -138.410927) (xy 34.679033 -138.329895)
			(xy 34.717767 -138.252106) (xy 34.763514 -138.178222) (xy 34.815883 -138.108875) (xy 34.874427 -138.044655)
			(xy 34.938647 -137.986111) (xy 35.007994 -137.933742) (xy 35.081878 -137.887995) (xy 35.159667 -137.849261)
			(xy 35.240699 -137.817869) (xy 35.324281 -137.794088) (xy 35.409701 -137.77812) (xy 35.49623 -137.770102)
			(xy 35.58313 -137.770102) (xy 35.669659 -137.77812) (xy 35.755079 -137.794088) (xy 35.838661 -137.817869)
			(xy 35.919693 -137.849261) (xy 35.997482 -137.887995) (xy 36.071366 -137.933742) (xy 36.140713 -137.986111)
			(xy 36.204933 -138.044655) (xy 36.263477 -138.108875) (xy 36.315846 -138.178222) (xy 36.361593 -138.252106)
			(xy 36.400327 -138.329895) (xy 36.431719 -138.410927) (xy 36.4555 -138.494509) (xy 36.471468 -138.579929)
			(xy 36.479486 -138.666458) (xy 36.479988 -138.709908) (xy 36.479486 -138.753358) (xy 36.471468 -138.839887)
			(xy 36.4555 -138.925307) (xy 36.431719 -139.008889) (xy 36.400327 -139.089921) (xy 36.361593 -139.16771)
			(xy 36.315846 -139.241594) (xy 36.263477 -139.310941) (xy 36.204933 -139.375161) (xy 36.140713 -139.433705)
			(xy 36.071366 -139.486074) (xy 35.997482 -139.531821) (xy 35.919693 -139.570555) (xy 35.838661 -139.601947)
			(xy 35.755079 -139.625728) (xy 35.669659 -139.641696) (xy 35.58313 -139.649714) (xy 35.49623 -139.649714)
			(xy 35.409701 -139.641696) (xy 35.324281 -139.625728) (xy 35.240699 -139.601947) (xy 35.159667 -139.570555)
			(xy 35.081878 -139.531821) (xy 35.007994 -139.486074) (xy 34.938647 -139.433705) (xy 34.874427 -139.375161)
			(xy 34.815883 -139.310941) (xy 34.763514 -139.241594) (xy 34.717767 -139.16771) (xy 34.679033 -139.089921)
			(xy 34.647641 -139.008889) (xy 34.62386 -138.925307) (xy 34.607892 -138.839887) (xy 34.599874 -138.753358)
			(xy 31.39851 -138.753358) (xy 31.396507 -138.796702) (xy 31.384501 -138.882769) (xy 31.364606 -138.967362)
			(xy 31.33699 -139.049758) (xy 31.30189 -139.129254) (xy 31.259604 -139.205173) (xy 31.210493 -139.276866)
			(xy 31.154978 -139.343722) (xy 31.09353 -139.40517) (xy 31.026674 -139.460687) (xy 30.954982 -139.509798)
			(xy 30.879064 -139.552085) (xy 30.799568 -139.587186) (xy 30.717172 -139.614803) (xy 30.63258 -139.634699)
			(xy 30.546512 -139.646706) (xy 30.459704 -139.650719) (xy 30.372896 -139.646707) (xy 30.286829 -139.634701)
			(xy 30.202236 -139.614805) (xy 30.11984 -139.587189) (xy 30.040344 -139.552089) (xy 29.964426 -139.509803)
			(xy 29.892732 -139.460692) (xy 29.825877 -139.405176) (xy 29.764428 -139.343728) (xy 29.736288 -139.310618)
			(xy 29.7217 -139.294467) (xy 29.688014 -139.266916) (xy 29.650127 -139.245506) (xy 29.609147 -139.230862)
			(xy 29.566272 -139.223413) (xy 29.522754 -139.223377) (xy 29.479866 -139.230754) (xy 29.438861 -139.245329)
			(xy 29.400938 -139.266675) (xy 29.367206 -139.29417) (xy 29.338651 -139.327009) (xy 29.316106 -139.364232)
			(xy 29.300232 -139.404751) (xy 29.291492 -139.447383) (xy 29.290264 -139.469114) (xy 29.290264 -140.26007)
			(xy 39.818317 -140.26007) (xy 39.822324 -140.144046) (xy 39.834326 -140.028574) (xy 39.854266 -139.914206)
			(xy 39.882049 -139.801486) (xy 39.917543 -139.690952) (xy 39.960578 -139.583129) (xy 40.010949 -139.478532)
			(xy 40.068416 -139.37766) (xy 40.132706 -139.280993) (xy 40.203511 -139.188992) (xy 40.280495 -139.102095)
			(xy 40.363291 -139.020716) (xy 40.451504 -138.945243) (xy 40.544714 -138.876036) (xy 40.642477 -138.813424)
			(xy 40.744326 -138.757707) (xy 40.849776 -138.709149) (xy 40.958325 -138.667981) (xy 41.069456 -138.634401)
			(xy 41.182639 -138.608568) (xy 41.297334 -138.590605) (xy 41.412996 -138.580597) (xy 41.529072 -138.578594)
			(xy 41.64501 -138.584603) (xy 41.760257 -138.598596) (xy 41.874263 -138.620507) (xy 41.986487 -138.650232)
			(xy 42.096393 -138.687628) (xy 42.203456 -138.732517) (xy 42.307168 -138.784686) (xy 42.407033 -138.843886)
			(xy 42.502576 -138.909835) (xy 42.502858 -138.91006) (xy 43.327831 -138.91006) (xy 43.331866 -138.834356)
			(xy 43.343925 -138.759511) (xy 43.363871 -138.68637) (xy 43.391478 -138.615765) (xy 43.426434 -138.548494)
			(xy 43.468342 -138.485319) (xy 43.516728 -138.426957) (xy 43.571044 -138.374069) (xy 43.630673 -138.327254)
			(xy 43.694941 -138.287042) (xy 43.763118 -138.25389) (xy 43.834434 -138.228172) (xy 43.908079 -138.21018)
			(xy 43.983219 -138.200118) (xy 44.059003 -138.198099) (xy 44.134573 -138.204148) (xy 44.209071 -138.218195)
			(xy 44.281654 -138.240081) (xy 44.3515 -138.269558) (xy 44.417817 -138.306293) (xy 44.479853 -138.349868)
			(xy 44.536906 -138.39979) (xy 44.58833 -138.455494) (xy 44.633541 -138.516349) (xy 44.672028 -138.581664)
			(xy 44.703354 -138.6507) (xy 44.727164 -138.722675) (xy 44.743189 -138.796773) (xy 44.751248 -138.872154)
			(xy 44.751752 -138.91006) (xy 45.867831 -138.91006) (xy 45.871866 -138.834356) (xy 45.883925 -138.759511)
			(xy 45.903871 -138.68637) (xy 45.931478 -138.615765) (xy 45.966434 -138.548494) (xy 46.008342 -138.485319)
			(xy 46.056728 -138.426957) (xy 46.111044 -138.374069) (xy 46.170673 -138.327254) (xy 46.234941 -138.287042)
			(xy 46.303118 -138.25389) (xy 46.374434 -138.228172) (xy 46.448079 -138.21018) (xy 46.523219 -138.200118)
			(xy 46.599003 -138.198099) (xy 46.674573 -138.204148) (xy 46.749071 -138.218195) (xy 46.821654 -138.240081)
			(xy 46.8915 -138.269558) (xy 46.957817 -138.306293) (xy 47.019853 -138.349868) (xy 47.076906 -138.39979)
			(xy 47.12833 -138.455494) (xy 47.173541 -138.516349) (xy 47.212028 -138.581664) (xy 47.243354 -138.6507)
			(xy 47.267164 -138.722675) (xy 47.283189 -138.796773) (xy 47.291248 -138.872154) (xy 47.291752 -138.91006)
			(xy 48.407831 -138.91006) (xy 48.411866 -138.834356) (xy 48.423925 -138.759511) (xy 48.443871 -138.68637)
			(xy 48.471478 -138.615765) (xy 48.506434 -138.548494) (xy 48.548342 -138.485319) (xy 48.596728 -138.426957)
			(xy 48.651044 -138.374069) (xy 48.710673 -138.327254) (xy 48.774941 -138.287042) (xy 48.843118 -138.25389)
			(xy 48.914434 -138.228172) (xy 48.988079 -138.21018) (xy 49.063219 -138.200118) (xy 49.139003 -138.198099)
			(xy 49.214573 -138.204148) (xy 49.289071 -138.218195) (xy 49.361654 -138.240081) (xy 49.4315 -138.269558)
			(xy 49.497817 -138.306293) (xy 49.559853 -138.349868) (xy 49.616906 -138.39979) (xy 49.66833 -138.455494)
			(xy 49.713541 -138.516349) (xy 49.752028 -138.581664) (xy 49.783354 -138.6507) (xy 49.807164 -138.722675)
			(xy 49.823189 -138.796773) (xy 49.831248 -138.872154) (xy 49.831752 -138.91006) (xy 50.947831 -138.91006)
			(xy 50.951866 -138.834356) (xy 50.963925 -138.759511) (xy 50.983871 -138.68637) (xy 51.011478 -138.615765)
			(xy 51.046434 -138.548494) (xy 51.088342 -138.485319) (xy 51.136728 -138.426957) (xy 51.191044 -138.374069)
			(xy 51.250673 -138.327254) (xy 51.314941 -138.287042) (xy 51.383118 -138.25389) (xy 51.454434 -138.228172)
			(xy 51.528079 -138.21018) (xy 51.603219 -138.200118) (xy 51.679003 -138.198099) (xy 51.754573 -138.204148)
			(xy 51.829071 -138.218195) (xy 51.901654 -138.240081) (xy 51.9715 -138.269558) (xy 52.037817 -138.306293)
			(xy 52.099853 -138.349868) (xy 52.156906 -138.39979) (xy 52.20833 -138.455494) (xy 52.253541 -138.516349)
			(xy 52.292028 -138.581664) (xy 52.323354 -138.6507) (xy 52.347164 -138.722675) (xy 52.363189 -138.796773)
			(xy 52.371248 -138.872154) (xy 52.371752 -138.91006) (xy 53.487831 -138.91006) (xy 53.491866 -138.834356)
			(xy 53.503925 -138.759511) (xy 53.523871 -138.68637) (xy 53.551478 -138.615765) (xy 53.586434 -138.548494)
			(xy 53.628342 -138.485319) (xy 53.676728 -138.426957) (xy 53.731044 -138.374069) (xy 53.790673 -138.327254)
			(xy 53.854941 -138.287042) (xy 53.923118 -138.25389) (xy 53.994434 -138.228172) (xy 54.068079 -138.21018)
			(xy 54.143219 -138.200118) (xy 54.219003 -138.198099) (xy 54.294573 -138.204148) (xy 54.369071 -138.218195)
			(xy 54.441654 -138.240081) (xy 54.5115 -138.269558) (xy 54.577817 -138.306293) (xy 54.639853 -138.349868)
			(xy 54.696906 -138.39979) (xy 54.74833 -138.455494) (xy 54.793541 -138.516349) (xy 54.832028 -138.581664)
			(xy 54.863354 -138.6507) (xy 54.887164 -138.722675) (xy 54.903189 -138.796773) (xy 54.911248 -138.872154)
			(xy 54.911752 -138.91006) (xy 56.027831 -138.91006) (xy 56.031866 -138.834356) (xy 56.043925 -138.759511)
			(xy 56.063871 -138.68637) (xy 56.091478 -138.615765) (xy 56.126434 -138.548494) (xy 56.168342 -138.485319)
			(xy 56.216728 -138.426957) (xy 56.271044 -138.374069) (xy 56.330673 -138.327254) (xy 56.394941 -138.287042)
			(xy 56.463118 -138.25389) (xy 56.534434 -138.228172) (xy 56.608079 -138.21018) (xy 56.683219 -138.200118)
			(xy 56.759003 -138.198099) (xy 56.834573 -138.204148) (xy 56.909071 -138.218195) (xy 56.981654 -138.240081)
			(xy 57.0515 -138.269558) (xy 57.117817 -138.306293) (xy 57.179853 -138.349868) (xy 57.236906 -138.39979)
			(xy 57.28833 -138.455494) (xy 57.333541 -138.516349) (xy 57.372028 -138.581664) (xy 57.403354 -138.6507)
			(xy 57.427164 -138.722675) (xy 57.443189 -138.796773) (xy 57.451248 -138.872154) (xy 57.451752 -138.91006)
			(xy 58.567831 -138.91006) (xy 58.571866 -138.834356) (xy 58.583925 -138.759511) (xy 58.603871 -138.68637)
			(xy 58.631478 -138.615765) (xy 58.666434 -138.548494) (xy 58.708342 -138.485319) (xy 58.756728 -138.426957)
			(xy 58.811044 -138.374069) (xy 58.870673 -138.327254) (xy 58.934941 -138.287042) (xy 59.003118 -138.25389)
			(xy 59.074434 -138.228172) (xy 59.148079 -138.21018) (xy 59.223219 -138.200118) (xy 59.299003 -138.198099)
			(xy 59.374573 -138.204148) (xy 59.449071 -138.218195) (xy 59.521654 -138.240081) (xy 59.5915 -138.269558)
			(xy 59.657817 -138.306293) (xy 59.719853 -138.349868) (xy 59.776906 -138.39979) (xy 59.82833 -138.455494)
			(xy 59.873541 -138.516349) (xy 59.912028 -138.581664) (xy 59.943354 -138.6507) (xy 59.967164 -138.722675)
			(xy 59.983189 -138.796773) (xy 59.991248 -138.872154) (xy 59.991752 -138.91006) (xy 61.107831 -138.91006)
			(xy 61.111866 -138.834356) (xy 61.123925 -138.759511) (xy 61.143871 -138.68637) (xy 61.171478 -138.615765)
			(xy 61.206434 -138.548494) (xy 61.248342 -138.485319) (xy 61.296728 -138.426957) (xy 61.351044 -138.374069)
			(xy 61.410673 -138.327254) (xy 61.474941 -138.287042) (xy 61.543118 -138.25389) (xy 61.614434 -138.228172)
			(xy 61.688079 -138.21018) (xy 61.763219 -138.200118) (xy 61.839003 -138.198099) (xy 61.914573 -138.204148)
			(xy 61.989071 -138.218195) (xy 62.061654 -138.240081) (xy 62.1315 -138.269558) (xy 62.197817 -138.306293)
			(xy 62.259853 -138.349868) (xy 62.316906 -138.39979) (xy 62.36833 -138.455494) (xy 62.413541 -138.516349)
			(xy 62.452028 -138.581664) (xy 62.483354 -138.6507) (xy 62.507164 -138.722675) (xy 62.523189 -138.796773)
			(xy 62.531248 -138.872154) (xy 62.531752 -138.91006) (xy 62.531248 -138.947966) (xy 62.523189 -139.023347)
			(xy 62.507164 -139.097445) (xy 62.483354 -139.16942) (xy 62.452028 -139.238456) (xy 62.413541 -139.303771)
			(xy 62.36833 -139.364626) (xy 62.316906 -139.42033) (xy 62.259853 -139.470252) (xy 62.197817 -139.513827)
			(xy 62.1315 -139.550562) (xy 62.061654 -139.580039) (xy 61.989071 -139.601925) (xy 61.914573 -139.615972)
			(xy 61.839003 -139.622021) (xy 61.763219 -139.620002) (xy 61.688079 -139.60994) (xy 61.614434 -139.591948)
			(xy 61.543118 -139.56623) (xy 61.474941 -139.533078) (xy 61.410673 -139.492866) (xy 61.351044 -139.446051)
			(xy 61.296728 -139.393163) (xy 61.248342 -139.334801) (xy 61.206434 -139.271626) (xy 61.171478 -139.204355)
			(xy 61.143871 -139.13375) (xy 61.123925 -139.060609) (xy 61.111866 -138.985764) (xy 61.107831 -138.91006)
			(xy 59.991752 -138.91006) (xy 59.991248 -138.947966) (xy 59.983189 -139.023347) (xy 59.967164 -139.097445)
			(xy 59.943354 -139.16942) (xy 59.912028 -139.238456) (xy 59.873541 -139.303771) (xy 59.82833 -139.364626)
			(xy 59.776906 -139.42033) (xy 59.719853 -139.470252) (xy 59.657817 -139.513827) (xy 59.5915 -139.550562)
			(xy 59.521654 -139.580039) (xy 59.449071 -139.601925) (xy 59.374573 -139.615972) (xy 59.299003 -139.622021)
			(xy 59.223219 -139.620002) (xy 59.148079 -139.60994) (xy 59.074434 -139.591948) (xy 59.003118 -139.56623)
			(xy 58.934941 -139.533078) (xy 58.870673 -139.492866) (xy 58.811044 -139.446051) (xy 58.756728 -139.393163)
			(xy 58.708342 -139.334801) (xy 58.666434 -139.271626) (xy 58.631478 -139.204355) (xy 58.603871 -139.13375)
			(xy 58.583925 -139.060609) (xy 58.571866 -138.985764) (xy 58.567831 -138.91006) (xy 57.451752 -138.91006)
			(xy 57.451248 -138.947966) (xy 57.443189 -139.023347) (xy 57.427164 -139.097445) (xy 57.403354 -139.16942)
			(xy 57.372028 -139.238456) (xy 57.333541 -139.303771) (xy 57.28833 -139.364626) (xy 57.236906 -139.42033)
			(xy 57.179853 -139.470252) (xy 57.117817 -139.513827) (xy 57.0515 -139.550562) (xy 56.981654 -139.580039)
			(xy 56.909071 -139.601925) (xy 56.834573 -139.615972) (xy 56.759003 -139.622021) (xy 56.683219 -139.620002)
			(xy 56.608079 -139.60994) (xy 56.534434 -139.591948) (xy 56.463118 -139.56623) (xy 56.394941 -139.533078)
			(xy 56.330673 -139.492866) (xy 56.271044 -139.446051) (xy 56.216728 -139.393163) (xy 56.168342 -139.334801)
			(xy 56.126434 -139.271626) (xy 56.091478 -139.204355) (xy 56.063871 -139.13375) (xy 56.043925 -139.060609)
			(xy 56.031866 -138.985764) (xy 56.027831 -138.91006) (xy 54.911752 -138.91006) (xy 54.911248 -138.947966)
			(xy 54.903189 -139.023347) (xy 54.887164 -139.097445) (xy 54.863354 -139.16942) (xy 54.832028 -139.238456)
			(xy 54.793541 -139.303771) (xy 54.74833 -139.364626) (xy 54.696906 -139.42033) (xy 54.639853 -139.470252)
			(xy 54.577817 -139.513827) (xy 54.5115 -139.550562) (xy 54.441654 -139.580039) (xy 54.369071 -139.601925)
			(xy 54.294573 -139.615972) (xy 54.219003 -139.622021) (xy 54.143219 -139.620002) (xy 54.068079 -139.60994)
			(xy 53.994434 -139.591948) (xy 53.923118 -139.56623) (xy 53.854941 -139.533078) (xy 53.790673 -139.492866)
			(xy 53.731044 -139.446051) (xy 53.676728 -139.393163) (xy 53.628342 -139.334801) (xy 53.586434 -139.271626)
			(xy 53.551478 -139.204355) (xy 53.523871 -139.13375) (xy 53.503925 -139.060609) (xy 53.491866 -138.985764)
			(xy 53.487831 -138.91006) (xy 52.371752 -138.91006) (xy 52.371248 -138.947966) (xy 52.363189 -139.023347)
			(xy 52.347164 -139.097445) (xy 52.323354 -139.16942) (xy 52.292028 -139.238456) (xy 52.253541 -139.303771)
			(xy 52.20833 -139.364626) (xy 52.156906 -139.42033) (xy 52.099853 -139.470252) (xy 52.037817 -139.513827)
			(xy 51.9715 -139.550562) (xy 51.901654 -139.580039) (xy 51.829071 -139.601925) (xy 51.754573 -139.615972)
			(xy 51.679003 -139.622021) (xy 51.603219 -139.620002) (xy 51.528079 -139.60994) (xy 51.454434 -139.591948)
			(xy 51.383118 -139.56623) (xy 51.314941 -139.533078) (xy 51.250673 -139.492866) (xy 51.191044 -139.446051)
			(xy 51.136728 -139.393163) (xy 51.088342 -139.334801) (xy 51.046434 -139.271626) (xy 51.011478 -139.204355)
			(xy 50.983871 -139.13375) (xy 50.963925 -139.060609) (xy 50.951866 -138.985764) (xy 50.947831 -138.91006)
			(xy 49.831752 -138.91006) (xy 49.831248 -138.947966) (xy 49.823189 -139.023347) (xy 49.807164 -139.097445)
			(xy 49.783354 -139.16942) (xy 49.752028 -139.238456) (xy 49.713541 -139.303771) (xy 49.66833 -139.364626)
			(xy 49.616906 -139.42033) (xy 49.559853 -139.470252) (xy 49.497817 -139.513827) (xy 49.4315 -139.550562)
			(xy 49.361654 -139.580039) (xy 49.289071 -139.601925) (xy 49.214573 -139.615972) (xy 49.139003 -139.622021)
			(xy 49.063219 -139.620002) (xy 48.988079 -139.60994) (xy 48.914434 -139.591948) (xy 48.843118 -139.56623)
			(xy 48.774941 -139.533078) (xy 48.710673 -139.492866) (xy 48.651044 -139.446051) (xy 48.596728 -139.393163)
			(xy 48.548342 -139.334801) (xy 48.506434 -139.271626) (xy 48.471478 -139.204355) (xy 48.443871 -139.13375)
			(xy 48.423925 -139.060609) (xy 48.411866 -138.985764) (xy 48.407831 -138.91006) (xy 47.291752 -138.91006)
			(xy 47.291248 -138.947966) (xy 47.283189 -139.023347) (xy 47.267164 -139.097445) (xy 47.243354 -139.16942)
			(xy 47.212028 -139.238456) (xy 47.173541 -139.303771) (xy 47.12833 -139.364626) (xy 47.076906 -139.42033)
			(xy 47.019853 -139.470252) (xy 46.957817 -139.513827) (xy 46.8915 -139.550562) (xy 46.821654 -139.580039)
			(xy 46.749071 -139.601925) (xy 46.674573 -139.615972) (xy 46.599003 -139.622021) (xy 46.523219 -139.620002)
			(xy 46.448079 -139.60994) (xy 46.374434 -139.591948) (xy 46.303118 -139.56623) (xy 46.234941 -139.533078)
			(xy 46.170673 -139.492866) (xy 46.111044 -139.446051) (xy 46.056728 -139.393163) (xy 46.008342 -139.334801)
			(xy 45.966434 -139.271626) (xy 45.931478 -139.204355) (xy 45.903871 -139.13375) (xy 45.883925 -139.060609)
			(xy 45.871866 -138.985764) (xy 45.867831 -138.91006) (xy 44.751752 -138.91006) (xy 44.751248 -138.947966)
			(xy 44.743189 -139.023347) (xy 44.727164 -139.097445) (xy 44.703354 -139.16942) (xy 44.672028 -139.238456)
			(xy 44.633541 -139.303771) (xy 44.58833 -139.364626) (xy 44.536906 -139.42033) (xy 44.479853 -139.470252)
			(xy 44.417817 -139.513827) (xy 44.3515 -139.550562) (xy 44.281654 -139.580039) (xy 44.209071 -139.601925)
			(xy 44.134573 -139.615972) (xy 44.059003 -139.622021) (xy 43.983219 -139.620002) (xy 43.908079 -139.60994)
			(xy 43.834434 -139.591948) (xy 43.763118 -139.56623) (xy 43.694941 -139.533078) (xy 43.630673 -139.492866)
			(xy 43.571044 -139.446051) (xy 43.516728 -139.393163) (xy 43.468342 -139.334801) (xy 43.426434 -139.271626)
			(xy 43.391478 -139.204355) (xy 43.363871 -139.13375) (xy 43.343925 -139.060609) (xy 43.331866 -138.985764)
			(xy 43.327831 -138.91006) (xy 42.502858 -138.91006) (xy 42.593342 -138.982218) (xy 42.678897 -139.060691)
			(xy 42.758835 -139.144879) (xy 42.832774 -139.234381) (xy 42.900362 -139.328772) (xy 42.961276 -139.4276)
			(xy 43.015228 -139.530396) (xy 43.061958 -139.636669) (xy 43.101246 -139.745913) (xy 43.132903 -139.857606)
			(xy 43.156779 -139.971218) (xy 43.17276 -140.086206) (xy 43.180769 -140.202023) (xy 43.18127 -140.26007)
			(xy 43.180769 -140.318117) (xy 43.17276 -140.433934) (xy 43.156779 -140.548922) (xy 43.132903 -140.662534)
			(xy 43.101246 -140.774227) (xy 43.061958 -140.883471) (xy 43.015228 -140.989744) (xy 42.961276 -141.09254)
			(xy 42.900362 -141.191368) (xy 42.832774 -141.285759) (xy 42.758835 -141.375261) (xy 42.678897 -141.459449)
			(xy 42.593342 -141.537922) (xy 42.502858 -141.61008) (xy 43.327831 -141.61008) (xy 43.331866 -141.534376)
			(xy 43.343925 -141.459531) (xy 43.363871 -141.38639) (xy 43.391478 -141.315785) (xy 43.426434 -141.248514)
			(xy 43.468342 -141.185339) (xy 43.516728 -141.126977) (xy 43.571044 -141.074089) (xy 43.630673 -141.027274)
			(xy 43.694941 -140.987062) (xy 43.763118 -140.95391) (xy 43.834434 -140.928192) (xy 43.908079 -140.9102)
			(xy 43.983219 -140.900138) (xy 44.059003 -140.898119) (xy 44.134573 -140.904168) (xy 44.209071 -140.918215)
			(xy 44.281654 -140.940101) (xy 44.3515 -140.969578) (xy 44.417817 -141.006313) (xy 44.479853 -141.049888)
			(xy 44.536906 -141.09981) (xy 44.58833 -141.155514) (xy 44.633541 -141.216369) (xy 44.672028 -141.281684)
			(xy 44.703354 -141.35072) (xy 44.727164 -141.422695) (xy 44.743189 -141.496793) (xy 44.751248 -141.572174)
			(xy 44.751752 -141.61008) (xy 45.867831 -141.61008) (xy 45.871866 -141.534376) (xy 45.883925 -141.459531)
			(xy 45.903871 -141.38639) (xy 45.931478 -141.315785) (xy 45.966434 -141.248514) (xy 46.008342 -141.185339)
			(xy 46.056728 -141.126977) (xy 46.111044 -141.074089) (xy 46.170673 -141.027274) (xy 46.234941 -140.987062)
			(xy 46.303118 -140.95391) (xy 46.374434 -140.928192) (xy 46.448079 -140.9102) (xy 46.523219 -140.900138)
			(xy 46.599003 -140.898119) (xy 46.674573 -140.904168) (xy 46.749071 -140.918215) (xy 46.821654 -140.940101)
			(xy 46.8915 -140.969578) (xy 46.957817 -141.006313) (xy 47.019853 -141.049888) (xy 47.076906 -141.09981)
			(xy 47.12833 -141.155514) (xy 47.173541 -141.216369) (xy 47.212028 -141.281684) (xy 47.243354 -141.35072)
			(xy 47.267164 -141.422695) (xy 47.283189 -141.496793) (xy 47.291248 -141.572174) (xy 47.291752 -141.61008)
			(xy 48.407831 -141.61008) (xy 48.411866 -141.534376) (xy 48.423925 -141.459531) (xy 48.443871 -141.38639)
			(xy 48.471478 -141.315785) (xy 48.506434 -141.248514) (xy 48.548342 -141.185339) (xy 48.596728 -141.126977)
			(xy 48.651044 -141.074089) (xy 48.710673 -141.027274) (xy 48.774941 -140.987062) (xy 48.843118 -140.95391)
			(xy 48.914434 -140.928192) (xy 48.988079 -140.9102) (xy 49.063219 -140.900138) (xy 49.139003 -140.898119)
			(xy 49.214573 -140.904168) (xy 49.289071 -140.918215) (xy 49.361654 -140.940101) (xy 49.4315 -140.969578)
			(xy 49.497817 -141.006313) (xy 49.559853 -141.049888) (xy 49.616906 -141.09981) (xy 49.66833 -141.155514)
			(xy 49.713541 -141.216369) (xy 49.752028 -141.281684) (xy 49.783354 -141.35072) (xy 49.807164 -141.422695)
			(xy 49.823189 -141.496793) (xy 49.831248 -141.572174) (xy 49.831752 -141.61008) (xy 50.947831 -141.61008)
			(xy 50.951866 -141.534376) (xy 50.963925 -141.459531) (xy 50.983871 -141.38639) (xy 51.011478 -141.315785)
			(xy 51.046434 -141.248514) (xy 51.088342 -141.185339) (xy 51.136728 -141.126977) (xy 51.191044 -141.074089)
			(xy 51.250673 -141.027274) (xy 51.314941 -140.987062) (xy 51.383118 -140.95391) (xy 51.454434 -140.928192)
			(xy 51.528079 -140.9102) (xy 51.603219 -140.900138) (xy 51.679003 -140.898119) (xy 51.754573 -140.904168)
			(xy 51.829071 -140.918215) (xy 51.901654 -140.940101) (xy 51.9715 -140.969578) (xy 52.037817 -141.006313)
			(xy 52.099853 -141.049888) (xy 52.156906 -141.09981) (xy 52.20833 -141.155514) (xy 52.253541 -141.216369)
			(xy 52.292028 -141.281684) (xy 52.323354 -141.35072) (xy 52.347164 -141.422695) (xy 52.363189 -141.496793)
			(xy 52.371248 -141.572174) (xy 52.371752 -141.61008) (xy 53.487831 -141.61008) (xy 53.491866 -141.534376)
			(xy 53.503925 -141.459531) (xy 53.523871 -141.38639) (xy 53.551478 -141.315785) (xy 53.586434 -141.248514)
			(xy 53.628342 -141.185339) (xy 53.676728 -141.126977) (xy 53.731044 -141.074089) (xy 53.790673 -141.027274)
			(xy 53.854941 -140.987062) (xy 53.923118 -140.95391) (xy 53.994434 -140.928192) (xy 54.068079 -140.9102)
			(xy 54.143219 -140.900138) (xy 54.219003 -140.898119) (xy 54.294573 -140.904168) (xy 54.369071 -140.918215)
			(xy 54.441654 -140.940101) (xy 54.5115 -140.969578) (xy 54.577817 -141.006313) (xy 54.639853 -141.049888)
			(xy 54.696906 -141.09981) (xy 54.74833 -141.155514) (xy 54.793541 -141.216369) (xy 54.832028 -141.281684)
			(xy 54.863354 -141.35072) (xy 54.887164 -141.422695) (xy 54.903189 -141.496793) (xy 54.911248 -141.572174)
			(xy 54.911752 -141.61008) (xy 56.027831 -141.61008) (xy 56.031866 -141.534376) (xy 56.043925 -141.459531)
			(xy 56.063871 -141.38639) (xy 56.091478 -141.315785) (xy 56.126434 -141.248514) (xy 56.168342 -141.185339)
			(xy 56.216728 -141.126977) (xy 56.271044 -141.074089) (xy 56.330673 -141.027274) (xy 56.394941 -140.987062)
			(xy 56.463118 -140.95391) (xy 56.534434 -140.928192) (xy 56.608079 -140.9102) (xy 56.683219 -140.900138)
			(xy 56.759003 -140.898119) (xy 56.834573 -140.904168) (xy 56.909071 -140.918215) (xy 56.981654 -140.940101)
			(xy 57.0515 -140.969578) (xy 57.117817 -141.006313) (xy 57.179853 -141.049888) (xy 57.236906 -141.09981)
			(xy 57.28833 -141.155514) (xy 57.333541 -141.216369) (xy 57.372028 -141.281684) (xy 57.403354 -141.35072)
			(xy 57.427164 -141.422695) (xy 57.443189 -141.496793) (xy 57.451248 -141.572174) (xy 57.451752 -141.61008)
			(xy 58.567831 -141.61008) (xy 58.571866 -141.534376) (xy 58.583925 -141.459531) (xy 58.603871 -141.38639)
			(xy 58.631478 -141.315785) (xy 58.666434 -141.248514) (xy 58.708342 -141.185339) (xy 58.756728 -141.126977)
			(xy 58.811044 -141.074089) (xy 58.870673 -141.027274) (xy 58.934941 -140.987062) (xy 59.003118 -140.95391)
			(xy 59.074434 -140.928192) (xy 59.148079 -140.9102) (xy 59.223219 -140.900138) (xy 59.299003 -140.898119)
			(xy 59.374573 -140.904168) (xy 59.449071 -140.918215) (xy 59.521654 -140.940101) (xy 59.5915 -140.969578)
			(xy 59.657817 -141.006313) (xy 59.719853 -141.049888) (xy 59.776906 -141.09981) (xy 59.82833 -141.155514)
			(xy 59.873541 -141.216369) (xy 59.912028 -141.281684) (xy 59.943354 -141.35072) (xy 59.967164 -141.422695)
			(xy 59.983189 -141.496793) (xy 59.991248 -141.572174) (xy 59.991752 -141.61008) (xy 61.107831 -141.61008)
			(xy 61.111866 -141.534376) (xy 61.123925 -141.459531) (xy 61.143871 -141.38639) (xy 61.171478 -141.315785)
			(xy 61.206434 -141.248514) (xy 61.248342 -141.185339) (xy 61.296728 -141.126977) (xy 61.351044 -141.074089)
			(xy 61.410673 -141.027274) (xy 61.474941 -140.987062) (xy 61.543118 -140.95391) (xy 61.614434 -140.928192)
			(xy 61.688079 -140.9102) (xy 61.763219 -140.900138) (xy 61.839003 -140.898119) (xy 61.914573 -140.904168)
			(xy 61.989071 -140.918215) (xy 62.061654 -140.940101) (xy 62.1315 -140.969578) (xy 62.197817 -141.006313)
			(xy 62.259853 -141.049888) (xy 62.316906 -141.09981) (xy 62.36833 -141.155514) (xy 62.413541 -141.216369)
			(xy 62.452028 -141.281684) (xy 62.483354 -141.35072) (xy 62.507164 -141.422695) (xy 62.523189 -141.496793)
			(xy 62.531248 -141.572174) (xy 62.531752 -141.61008) (xy 62.531248 -141.647986) (xy 62.523189 -141.723367)
			(xy 62.507164 -141.797465) (xy 62.483354 -141.86944) (xy 62.452028 -141.938476) (xy 62.413541 -142.003791)
			(xy 62.36833 -142.064646) (xy 62.316906 -142.12035) (xy 62.259853 -142.170272) (xy 62.197817 -142.213847)
			(xy 62.1315 -142.250582) (xy 62.061654 -142.280059) (xy 61.989071 -142.301945) (xy 61.914573 -142.315992)
			(xy 61.839003 -142.322041) (xy 61.763219 -142.320022) (xy 61.688079 -142.30996) (xy 61.614434 -142.291968)
			(xy 61.543118 -142.26625) (xy 61.474941 -142.233098) (xy 61.410673 -142.192886) (xy 61.351044 -142.146071)
			(xy 61.296728 -142.093183) (xy 61.248342 -142.034821) (xy 61.206434 -141.971646) (xy 61.171478 -141.904375)
			(xy 61.143871 -141.83377) (xy 61.123925 -141.760629) (xy 61.111866 -141.685784) (xy 61.107831 -141.61008)
			(xy 59.991752 -141.61008) (xy 59.991248 -141.647986) (xy 59.983189 -141.723367) (xy 59.967164 -141.797465)
			(xy 59.943354 -141.86944) (xy 59.912028 -141.938476) (xy 59.873541 -142.003791) (xy 59.82833 -142.064646)
			(xy 59.776906 -142.12035) (xy 59.719853 -142.170272) (xy 59.657817 -142.213847) (xy 59.5915 -142.250582)
			(xy 59.521654 -142.280059) (xy 59.449071 -142.301945) (xy 59.374573 -142.315992) (xy 59.299003 -142.322041)
			(xy 59.223219 -142.320022) (xy 59.148079 -142.30996) (xy 59.074434 -142.291968) (xy 59.003118 -142.26625)
			(xy 58.934941 -142.233098) (xy 58.870673 -142.192886) (xy 58.811044 -142.146071) (xy 58.756728 -142.093183)
			(xy 58.708342 -142.034821) (xy 58.666434 -141.971646) (xy 58.631478 -141.904375) (xy 58.603871 -141.83377)
			(xy 58.583925 -141.760629) (xy 58.571866 -141.685784) (xy 58.567831 -141.61008) (xy 57.451752 -141.61008)
			(xy 57.451248 -141.647986) (xy 57.443189 -141.723367) (xy 57.427164 -141.797465) (xy 57.403354 -141.86944)
			(xy 57.372028 -141.938476) (xy 57.333541 -142.003791) (xy 57.28833 -142.064646) (xy 57.236906 -142.12035)
			(xy 57.179853 -142.170272) (xy 57.117817 -142.213847) (xy 57.0515 -142.250582) (xy 56.981654 -142.280059)
			(xy 56.909071 -142.301945) (xy 56.834573 -142.315992) (xy 56.759003 -142.322041) (xy 56.683219 -142.320022)
			(xy 56.608079 -142.30996) (xy 56.534434 -142.291968) (xy 56.463118 -142.26625) (xy 56.394941 -142.233098)
			(xy 56.330673 -142.192886) (xy 56.271044 -142.146071) (xy 56.216728 -142.093183) (xy 56.168342 -142.034821)
			(xy 56.126434 -141.971646) (xy 56.091478 -141.904375) (xy 56.063871 -141.83377) (xy 56.043925 -141.760629)
			(xy 56.031866 -141.685784) (xy 56.027831 -141.61008) (xy 54.911752 -141.61008) (xy 54.911248 -141.647986)
			(xy 54.903189 -141.723367) (xy 54.887164 -141.797465) (xy 54.863354 -141.86944) (xy 54.832028 -141.938476)
			(xy 54.793541 -142.003791) (xy 54.74833 -142.064646) (xy 54.696906 -142.12035) (xy 54.639853 -142.170272)
			(xy 54.577817 -142.213847) (xy 54.5115 -142.250582) (xy 54.441654 -142.280059) (xy 54.369071 -142.301945)
			(xy 54.294573 -142.315992) (xy 54.219003 -142.322041) (xy 54.143219 -142.320022) (xy 54.068079 -142.30996)
			(xy 53.994434 -142.291968) (xy 53.923118 -142.26625) (xy 53.854941 -142.233098) (xy 53.790673 -142.192886)
			(xy 53.731044 -142.146071) (xy 53.676728 -142.093183) (xy 53.628342 -142.034821) (xy 53.586434 -141.971646)
			(xy 53.551478 -141.904375) (xy 53.523871 -141.83377) (xy 53.503925 -141.760629) (xy 53.491866 -141.685784)
			(xy 53.487831 -141.61008) (xy 52.371752 -141.61008) (xy 52.371248 -141.647986) (xy 52.363189 -141.723367)
			(xy 52.347164 -141.797465) (xy 52.323354 -141.86944) (xy 52.292028 -141.938476) (xy 52.253541 -142.003791)
			(xy 52.20833 -142.064646) (xy 52.156906 -142.12035) (xy 52.099853 -142.170272) (xy 52.037817 -142.213847)
			(xy 51.9715 -142.250582) (xy 51.901654 -142.280059) (xy 51.829071 -142.301945) (xy 51.754573 -142.315992)
			(xy 51.679003 -142.322041) (xy 51.603219 -142.320022) (xy 51.528079 -142.30996) (xy 51.454434 -142.291968)
			(xy 51.383118 -142.26625) (xy 51.314941 -142.233098) (xy 51.250673 -142.192886) (xy 51.191044 -142.146071)
			(xy 51.136728 -142.093183) (xy 51.088342 -142.034821) (xy 51.046434 -141.971646) (xy 51.011478 -141.904375)
			(xy 50.983871 -141.83377) (xy 50.963925 -141.760629) (xy 50.951866 -141.685784) (xy 50.947831 -141.61008)
			(xy 49.831752 -141.61008) (xy 49.831248 -141.647986) (xy 49.823189 -141.723367) (xy 49.807164 -141.797465)
			(xy 49.783354 -141.86944) (xy 49.752028 -141.938476) (xy 49.713541 -142.003791) (xy 49.66833 -142.064646)
			(xy 49.616906 -142.12035) (xy 49.559853 -142.170272) (xy 49.497817 -142.213847) (xy 49.4315 -142.250582)
			(xy 49.361654 -142.280059) (xy 49.289071 -142.301945) (xy 49.214573 -142.315992) (xy 49.139003 -142.322041)
			(xy 49.063219 -142.320022) (xy 48.988079 -142.30996) (xy 48.914434 -142.291968) (xy 48.843118 -142.26625)
			(xy 48.774941 -142.233098) (xy 48.710673 -142.192886) (xy 48.651044 -142.146071) (xy 48.596728 -142.093183)
			(xy 48.548342 -142.034821) (xy 48.506434 -141.971646) (xy 48.471478 -141.904375) (xy 48.443871 -141.83377)
			(xy 48.423925 -141.760629) (xy 48.411866 -141.685784) (xy 48.407831 -141.61008) (xy 47.291752 -141.61008)
			(xy 47.291248 -141.647986) (xy 47.283189 -141.723367) (xy 47.267164 -141.797465) (xy 47.243354 -141.86944)
			(xy 47.212028 -141.938476) (xy 47.173541 -142.003791) (xy 47.12833 -142.064646) (xy 47.076906 -142.12035)
			(xy 47.019853 -142.170272) (xy 46.957817 -142.213847) (xy 46.8915 -142.250582) (xy 46.821654 -142.280059)
			(xy 46.749071 -142.301945) (xy 46.674573 -142.315992) (xy 46.599003 -142.322041) (xy 46.523219 -142.320022)
			(xy 46.448079 -142.30996) (xy 46.374434 -142.291968) (xy 46.303118 -142.26625) (xy 46.234941 -142.233098)
			(xy 46.170673 -142.192886) (xy 46.111044 -142.146071) (xy 46.056728 -142.093183) (xy 46.008342 -142.034821)
			(xy 45.966434 -141.971646) (xy 45.931478 -141.904375) (xy 45.903871 -141.83377) (xy 45.883925 -141.760629)
			(xy 45.871866 -141.685784) (xy 45.867831 -141.61008) (xy 44.751752 -141.61008) (xy 44.751248 -141.647986)
			(xy 44.743189 -141.723367) (xy 44.727164 -141.797465) (xy 44.703354 -141.86944) (xy 44.672028 -141.938476)
			(xy 44.633541 -142.003791) (xy 44.58833 -142.064646) (xy 44.536906 -142.12035) (xy 44.479853 -142.170272)
			(xy 44.417817 -142.213847) (xy 44.3515 -142.250582) (xy 44.281654 -142.280059) (xy 44.209071 -142.301945)
			(xy 44.134573 -142.315992) (xy 44.059003 -142.322041) (xy 43.983219 -142.320022) (xy 43.908079 -142.30996)
			(xy 43.834434 -142.291968) (xy 43.763118 -142.26625) (xy 43.694941 -142.233098) (xy 43.630673 -142.192886)
			(xy 43.571044 -142.146071) (xy 43.516728 -142.093183) (xy 43.468342 -142.034821) (xy 43.426434 -141.971646)
			(xy 43.391478 -141.904375) (xy 43.363871 -141.83377) (xy 43.343925 -141.760629) (xy 43.331866 -141.685784)
			(xy 43.327831 -141.61008) (xy 42.502858 -141.61008) (xy 42.502576 -141.610305) (xy 42.407033 -141.676254)
			(xy 42.307168 -141.735454) (xy 42.203456 -141.787623) (xy 42.096393 -141.832512) (xy 41.986487 -141.869908)
			(xy 41.874263 -141.899633) (xy 41.760257 -141.921544) (xy 41.64501 -141.935537) (xy 41.529072 -141.941546)
			(xy 41.412996 -141.939543) (xy 41.297334 -141.929535) (xy 41.182639 -141.911572) (xy 41.069456 -141.885739)
			(xy 40.958325 -141.852159) (xy 40.849776 -141.810991) (xy 40.744326 -141.762433) (xy 40.642477 -141.706716)
			(xy 40.544714 -141.644104) (xy 40.451504 -141.574897) (xy 40.363291 -141.499424) (xy 40.280495 -141.418045)
			(xy 40.203511 -141.331148) (xy 40.132706 -141.239147) (xy 40.068416 -141.14248) (xy 40.010949 -141.041608)
			(xy 39.960578 -140.937011) (xy 39.917543 -140.829188) (xy 39.882049 -140.718654) (xy 39.854266 -140.605934)
			(xy 39.834326 -140.491566) (xy 39.822324 -140.376094) (xy 39.818317 -140.26007) (xy 29.290264 -140.26007)
			(xy 29.290264 -140.490702) (xy 29.29138 -140.512445) (xy 29.300112 -140.555094) (xy 29.315983 -140.595631)
			(xy 29.338531 -140.63287) (xy 29.367094 -140.665723) (xy 29.400837 -140.693229) (xy 29.438774 -140.714582)
			(xy 29.479795 -140.729158) (xy 29.5227 -140.736531) (xy 29.566233 -140.736485) (xy 29.609122 -140.729022)
			(xy 29.650112 -140.71436) (xy 29.688004 -140.692927) (xy 29.72169 -140.665351) (xy 29.736288 -140.649198)
			(xy 29.76442 -140.616081) (xy 29.825867 -140.554632) (xy 29.892723 -140.499115) (xy 29.964415 -140.450004)
			(xy 30.040333 -140.407717) (xy 30.119829 -140.372615) (xy 30.202225 -140.344998) (xy 30.286817 -140.325101)
			(xy 30.372884 -140.313095) (xy 30.459692 -140.309081) (xy 30.5465 -140.313093) (xy 30.632567 -140.325098)
			(xy 30.71716 -140.344994) (xy 30.799556 -140.372609) (xy 30.879053 -140.40771) (xy 30.954971 -140.449995)
			(xy 31.026665 -140.499105) (xy 31.093521 -140.554621) (xy 31.154969 -140.616069) (xy 31.210486 -140.682924)
			(xy 31.259597 -140.754617) (xy 31.301884 -140.830535) (xy 31.336986 -140.910031) (xy 31.364603 -140.992426)
			(xy 31.384499 -141.077019) (xy 31.396506 -141.163086) (xy 31.400519 -141.249894) (xy 31.39851 -141.293358)
			(xy 34.599874 -141.293358) (xy 34.599874 -141.206458) (xy 34.607892 -141.119929) (xy 34.62386 -141.034509)
			(xy 34.647641 -140.950927) (xy 34.679033 -140.869895) (xy 34.717767 -140.792106) (xy 34.763514 -140.718222)
			(xy 34.815883 -140.648875) (xy 34.874427 -140.584655) (xy 34.938647 -140.526111) (xy 35.007994 -140.473742)
			(xy 35.081878 -140.427995) (xy 35.159667 -140.389261) (xy 35.240699 -140.357869) (xy 35.324281 -140.334088)
			(xy 35.409701 -140.31812) (xy 35.49623 -140.310102) (xy 35.58313 -140.310102) (xy 35.669659 -140.31812)
			(xy 35.755079 -140.334088) (xy 35.838661 -140.357869) (xy 35.919693 -140.389261) (xy 35.997482 -140.427995)
			(xy 36.071366 -140.473742) (xy 36.140713 -140.526111) (xy 36.204933 -140.584655) (xy 36.263477 -140.648875)
			(xy 36.315846 -140.718222) (xy 36.361593 -140.792106) (xy 36.400327 -140.869895) (xy 36.431719 -140.950927)
			(xy 36.4555 -141.034509) (xy 36.471468 -141.119929) (xy 36.479486 -141.206458) (xy 36.479988 -141.249908)
			(xy 36.479486 -141.293358) (xy 36.471468 -141.379887) (xy 36.4555 -141.465307) (xy 36.431719 -141.548889)
			(xy 36.400327 -141.629921) (xy 36.361593 -141.70771) (xy 36.315846 -141.781594) (xy 36.263477 -141.850941)
			(xy 36.204933 -141.915161) (xy 36.140713 -141.973705) (xy 36.071366 -142.026074) (xy 35.997482 -142.071821)
			(xy 35.919693 -142.110555) (xy 35.838661 -142.141947) (xy 35.755079 -142.165728) (xy 35.669659 -142.181696)
			(xy 35.58313 -142.189714) (xy 35.49623 -142.189714) (xy 35.409701 -142.181696) (xy 35.324281 -142.165728)
			(xy 35.240699 -142.141947) (xy 35.159667 -142.110555) (xy 35.081878 -142.071821) (xy 35.007994 -142.026074)
			(xy 34.938647 -141.973705) (xy 34.874427 -141.915161) (xy 34.815883 -141.850941) (xy 34.763514 -141.781594)
			(xy 34.717767 -141.70771) (xy 34.679033 -141.629921) (xy 34.647641 -141.548889) (xy 34.62386 -141.465307)
			(xy 34.607892 -141.379887) (xy 34.599874 -141.293358) (xy 31.39851 -141.293358) (xy 31.396507 -141.336702)
			(xy 31.384501 -141.422769) (xy 31.364606 -141.507362) (xy 31.33699 -141.589758) (xy 31.30189 -141.669254)
			(xy 31.259604 -141.745173) (xy 31.210493 -141.816866) (xy 31.154978 -141.883722) (xy 31.09353 -141.94517)
			(xy 31.026674 -142.000687) (xy 30.954982 -142.049798) (xy 30.879064 -142.092085) (xy 30.799568 -142.127186)
			(xy 30.717172 -142.154803) (xy 30.63258 -142.174699) (xy 30.546512 -142.186706) (xy 30.459704 -142.190719)
			(xy 30.372896 -142.186707) (xy 30.286829 -142.174701) (xy 30.202236 -142.154805) (xy 30.11984 -142.127189)
			(xy 30.040344 -142.092089) (xy 29.964426 -142.049803) (xy 29.892732 -142.000692) (xy 29.825877 -141.945176)
			(xy 29.764428 -141.883728) (xy 29.736288 -141.850618) (xy 29.7217 -141.834467) (xy 29.688014 -141.806916)
			(xy 29.650127 -141.785506) (xy 29.609147 -141.770862) (xy 29.566272 -141.763413) (xy 29.522754 -141.763377)
			(xy 29.479866 -141.770754) (xy 29.438861 -141.785329) (xy 29.400938 -141.806675) (xy 29.367206 -141.83417)
			(xy 29.338651 -141.867009) (xy 29.316106 -141.904232) (xy 29.300232 -141.944751) (xy 29.291492 -141.987383)
			(xy 29.290264 -142.009114) (xy 29.290264 -150.919027) (xy 58.029594 -150.919027) (xy 58.029594 -150.847705)
			(xy 58.03758 -150.776831) (xy 58.05345 -150.707296) (xy 58.077007 -150.639976) (xy 58.107952 -150.575717)
			(xy 58.145898 -150.515326) (xy 58.190367 -150.459564) (xy 58.2408 -150.409131) (xy 58.296562 -150.364662)
			(xy 58.356953 -150.326716) (xy 58.421212 -150.295771) (xy 58.488532 -150.272214) (xy 58.558067 -150.256344)
			(xy 58.628941 -150.248358) (xy 58.700263 -150.248358) (xy 58.771137 -150.256344) (xy 58.840672 -150.272214)
			(xy 58.907992 -150.295771) (xy 58.972251 -150.326716) (xy 59.032642 -150.364662) (xy 59.088404 -150.409131)
			(xy 59.138837 -150.459564) (xy 59.183306 -150.515326) (xy 59.221252 -150.575717) (xy 59.252197 -150.639976)
			(xy 59.275754 -150.707296) (xy 59.291624 -150.776831) (xy 59.29961 -150.847705) (xy 59.30011 -150.883366)
			(xy 59.29961 -150.919027) (xy 59.916306 -150.919027) (xy 59.916306 -150.847705) (xy 59.924292 -150.776831)
			(xy 59.940162 -150.707296) (xy 59.963719 -150.639976) (xy 59.994664 -150.575717) (xy 60.03261 -150.515326)
			(xy 60.077079 -150.459564) (xy 60.127512 -150.409131) (xy 60.183274 -150.364662) (xy 60.243665 -150.326716)
			(xy 60.307924 -150.295771) (xy 60.375244 -150.272214) (xy 60.444779 -150.256344) (xy 60.515653 -150.248358)
			(xy 60.586975 -150.248358) (xy 60.657849 -150.256344) (xy 60.727384 -150.272214) (xy 60.794704 -150.295771)
			(xy 60.858963 -150.326716) (xy 60.919354 -150.364662) (xy 60.975116 -150.409131) (xy 61.025549 -150.459564)
			(xy 61.070018 -150.515326) (xy 61.107964 -150.575717) (xy 61.138909 -150.639976) (xy 61.162466 -150.707296)
			(xy 61.178336 -150.776831) (xy 61.186322 -150.847705) (xy 61.186822 -150.883366) (xy 61.186322 -150.919027)
			(xy 62.157348 -150.919027) (xy 62.157348 -150.847705) (xy 62.165334 -150.776831) (xy 62.181204 -150.707296)
			(xy 62.204761 -150.639976) (xy 62.235706 -150.575717) (xy 62.273652 -150.515326) (xy 62.318121 -150.459564)
			(xy 62.368554 -150.409131) (xy 62.424316 -150.364662) (xy 62.484707 -150.326716) (xy 62.548966 -150.295771)
			(xy 62.616286 -150.272214) (xy 62.685821 -150.256344) (xy 62.756695 -150.248358) (xy 62.828017 -150.248358)
			(xy 62.898891 -150.256344) (xy 62.968426 -150.272214) (xy 63.035746 -150.295771) (xy 63.100005 -150.326716)
			(xy 63.160396 -150.364662) (xy 63.216158 -150.409131) (xy 63.266591 -150.459564) (xy 63.31106 -150.515326)
			(xy 63.349006 -150.575717) (xy 63.379951 -150.639976) (xy 63.403508 -150.707296) (xy 63.419378 -150.776831)
			(xy 63.427364 -150.847705) (xy 63.427864 -150.883366) (xy 63.427364 -150.919027) (xy 64.061332 -150.919027)
			(xy 64.061332 -150.847705) (xy 64.069318 -150.776831) (xy 64.085188 -150.707296) (xy 64.108745 -150.639976)
			(xy 64.13969 -150.575717) (xy 64.177636 -150.515326) (xy 64.222105 -150.459564) (xy 64.272538 -150.409131)
			(xy 64.3283 -150.364662) (xy 64.388691 -150.326716) (xy 64.45295 -150.295771) (xy 64.52027 -150.272214)
			(xy 64.589805 -150.256344) (xy 64.660679 -150.248358) (xy 64.732001 -150.248358) (xy 64.802875 -150.256344)
			(xy 64.87241 -150.272214) (xy 64.93973 -150.295771) (xy 65.003989 -150.326716) (xy 65.06438 -150.364662)
			(xy 65.120142 -150.409131) (xy 65.133621 -150.42261) (xy 73.527918 -150.42261) (xy 73.531989 -150.366988)
			(xy 73.544115 -150.312551) (xy 73.564038 -150.26046) (xy 73.591334 -150.211825) (xy 73.62542 -150.167682)
			(xy 73.665569 -150.128973) (xy 73.710927 -150.096522) (xy 73.760527 -150.071021) (xy 73.813311 -150.053014)
			(xy 73.868154 -150.042884) (xy 73.923888 -150.040847) (xy 73.979325 -150.046947) (xy 74.033282 -150.061053)
			(xy 74.084611 -150.082865) (xy 74.132217 -150.111919) (xy 74.175085 -150.147594) (xy 74.212302 -150.189131)
			(xy 74.243075 -150.235644) (xy 74.266747 -150.286141) (xy 74.282815 -150.339548) (xy 74.290935 -150.394724)
			(xy 74.291444 -150.42261) (xy 74.677268 -150.42261) (xy 74.681339 -150.366988) (xy 74.693465 -150.312551)
			(xy 74.713388 -150.26046) (xy 74.740684 -150.211825) (xy 74.77477 -150.167682) (xy 74.814919 -150.128973)
			(xy 74.860277 -150.096522) (xy 74.909877 -150.071021) (xy 74.962661 -150.053014) (xy 75.017504 -150.042884)
			(xy 75.073238 -150.040847) (xy 75.128675 -150.046947) (xy 75.182632 -150.061053) (xy 75.233961 -150.082865)
			(xy 75.281567 -150.111919) (xy 75.324435 -150.147594) (xy 75.361652 -150.189131) (xy 75.392425 -150.235644)
			(xy 75.416097 -150.286141) (xy 75.432165 -150.339548) (xy 75.440285 -150.394724) (xy 75.440794 -150.42261)
			(xy 75.440285 -150.450496) (xy 75.432165 -150.505672) (xy 75.416097 -150.559079) (xy 75.392425 -150.609576)
			(xy 75.361652 -150.656089) (xy 75.324435 -150.697626) (xy 75.281567 -150.733301) (xy 75.233961 -150.762355)
			(xy 75.182632 -150.784167) (xy 75.128675 -150.798273) (xy 75.073238 -150.804373) (xy 75.017504 -150.802336)
			(xy 74.962661 -150.792206) (xy 74.909877 -150.774199) (xy 74.860277 -150.748698) (xy 74.814919 -150.716247)
			(xy 74.77477 -150.677538) (xy 74.740684 -150.633395) (xy 74.713388 -150.58476) (xy 74.693465 -150.532669)
			(xy 74.681339 -150.478232) (xy 74.677268 -150.42261) (xy 74.291444 -150.42261) (xy 74.290935 -150.450496)
			(xy 74.282815 -150.505672) (xy 74.266747 -150.559079) (xy 74.243075 -150.609576) (xy 74.212302 -150.656089)
			(xy 74.175085 -150.697626) (xy 74.132217 -150.733301) (xy 74.084611 -150.762355) (xy 74.033282 -150.784167)
			(xy 73.979325 -150.798273) (xy 73.923888 -150.804373) (xy 73.868154 -150.802336) (xy 73.813311 -150.792206)
			(xy 73.760527 -150.774199) (xy 73.710927 -150.748698) (xy 73.665569 -150.716247) (xy 73.62542 -150.677538)
			(xy 73.591334 -150.633395) (xy 73.564038 -150.58476) (xy 73.544115 -150.532669) (xy 73.531989 -150.478232)
			(xy 73.527918 -150.42261) (xy 65.133621 -150.42261) (xy 65.170575 -150.459564) (xy 65.215044 -150.515326)
			(xy 65.25299 -150.575717) (xy 65.283935 -150.639976) (xy 65.307492 -150.707296) (xy 65.323362 -150.776831)
			(xy 65.331348 -150.847705) (xy 65.331848 -150.883366) (xy 65.331348 -150.919027) (xy 65.323362 -150.989901)
			(xy 65.307492 -151.059436) (xy 65.283935 -151.126756) (xy 65.25299 -151.191015) (xy 65.215044 -151.251406)
			(xy 65.202481 -151.26716) (xy 72.096374 -151.26716) (xy 72.100445 -151.211538) (xy 72.112571 -151.157101)
			(xy 72.132494 -151.10501) (xy 72.15979 -151.056375) (xy 72.193876 -151.012232) (xy 72.234025 -150.973523)
			(xy 72.279383 -150.941072) (xy 72.328983 -150.915571) (xy 72.381767 -150.897564) (xy 72.43661 -150.887434)
			(xy 72.492344 -150.885397) (xy 72.547781 -150.891497) (xy 72.601738 -150.905603) (xy 72.653067 -150.927415)
			(xy 72.700673 -150.956469) (xy 72.743541 -150.992144) (xy 72.780758 -151.033681) (xy 72.811531 -151.080194)
			(xy 72.835203 -151.130691) (xy 72.851271 -151.184098) (xy 72.859391 -151.239274) (xy 72.8599 -151.26716)
			(xy 72.859391 -151.295046) (xy 72.851271 -151.350222) (xy 72.835203 -151.403629) (xy 72.811531 -151.454126)
			(xy 72.780758 -151.500639) (xy 72.743541 -151.542176) (xy 72.700673 -151.577851) (xy 72.653067 -151.606905)
			(xy 72.601738 -151.628717) (xy 72.547781 -151.642823) (xy 72.492344 -151.648923) (xy 72.43661 -151.646886)
			(xy 72.381767 -151.636756) (xy 72.328983 -151.618749) (xy 72.279383 -151.593248) (xy 72.234025 -151.560797)
			(xy 72.193876 -151.522088) (xy 72.15979 -151.477945) (xy 72.132494 -151.42931) (xy 72.112571 -151.377219)
			(xy 72.100445 -151.322782) (xy 72.096374 -151.26716) (xy 65.202481 -151.26716) (xy 65.170575 -151.307168)
			(xy 65.120142 -151.357601) (xy 65.06438 -151.40207) (xy 65.003989 -151.440016) (xy 64.93973 -151.470961)
			(xy 64.87241 -151.494518) (xy 64.802875 -151.510388) (xy 64.732001 -151.518374) (xy 64.660679 -151.518374)
			(xy 64.589805 -151.510388) (xy 64.52027 -151.494518) (xy 64.45295 -151.470961) (xy 64.388691 -151.440016)
			(xy 64.3283 -151.40207) (xy 64.272538 -151.357601) (xy 64.222105 -151.307168) (xy 64.177636 -151.251406)
			(xy 64.13969 -151.191015) (xy 64.108745 -151.126756) (xy 64.085188 -151.059436) (xy 64.069318 -150.989901)
			(xy 64.061332 -150.919027) (xy 63.427364 -150.919027) (xy 63.419378 -150.989901) (xy 63.403508 -151.059436)
			(xy 63.379951 -151.126756) (xy 63.349006 -151.191015) (xy 63.31106 -151.251406) (xy 63.266591 -151.307168)
			(xy 63.216158 -151.357601) (xy 63.160396 -151.40207) (xy 63.100005 -151.440016) (xy 63.035746 -151.470961)
			(xy 62.968426 -151.494518) (xy 62.898891 -151.510388) (xy 62.828017 -151.518374) (xy 62.756695 -151.518374)
			(xy 62.685821 -151.510388) (xy 62.616286 -151.494518) (xy 62.548966 -151.470961) (xy 62.484707 -151.440016)
			(xy 62.424316 -151.40207) (xy 62.368554 -151.357601) (xy 62.318121 -151.307168) (xy 62.273652 -151.251406)
			(xy 62.235706 -151.191015) (xy 62.204761 -151.126756) (xy 62.181204 -151.059436) (xy 62.165334 -150.989901)
			(xy 62.157348 -150.919027) (xy 61.186322 -150.919027) (xy 61.178336 -150.989901) (xy 61.162466 -151.059436)
			(xy 61.138909 -151.126756) (xy 61.107964 -151.191015) (xy 61.070018 -151.251406) (xy 61.025549 -151.307168)
			(xy 60.975116 -151.357601) (xy 60.919354 -151.40207) (xy 60.858963 -151.440016) (xy 60.794704 -151.470961)
			(xy 60.727384 -151.494518) (xy 60.657849 -151.510388) (xy 60.586975 -151.518374) (xy 60.515653 -151.518374)
			(xy 60.444779 -151.510388) (xy 60.375244 -151.494518) (xy 60.307924 -151.470961) (xy 60.243665 -151.440016)
			(xy 60.183274 -151.40207) (xy 60.127512 -151.357601) (xy 60.077079 -151.307168) (xy 60.03261 -151.251406)
			(xy 59.994664 -151.191015) (xy 59.963719 -151.126756) (xy 59.940162 -151.059436) (xy 59.924292 -150.989901)
			(xy 59.916306 -150.919027) (xy 59.29961 -150.919027) (xy 59.291624 -150.989901) (xy 59.275754 -151.059436)
			(xy 59.252197 -151.126756) (xy 59.221252 -151.191015) (xy 59.183306 -151.251406) (xy 59.138837 -151.307168)
			(xy 59.088404 -151.357601) (xy 59.032642 -151.40207) (xy 58.972251 -151.440016) (xy 58.907992 -151.470961)
			(xy 58.840672 -151.494518) (xy 58.771137 -151.510388) (xy 58.700263 -151.518374) (xy 58.628941 -151.518374)
			(xy 58.558067 -151.510388) (xy 58.488532 -151.494518) (xy 58.421212 -151.470961) (xy 58.356953 -151.440016)
			(xy 58.296562 -151.40207) (xy 58.2408 -151.357601) (xy 58.190367 -151.307168) (xy 58.145898 -151.251406)
			(xy 58.107952 -151.191015) (xy 58.077007 -151.126756) (xy 58.05345 -151.059436) (xy 58.03758 -150.989901)
			(xy 58.029594 -150.919027) (xy 29.290264 -150.919027) (xy 29.290264 -151.965575) (xy 48.168042 -151.965575)
			(xy 48.168042 -151.884465) (xy 48.175992 -151.803746) (xy 48.191815 -151.724195) (xy 48.21536 -151.646579)
			(xy 48.246399 -151.571643) (xy 48.284634 -151.500111) (xy 48.329696 -151.432671) (xy 48.381151 -151.369972)
			(xy 48.438504 -151.312619) (xy 48.501203 -151.261164) (xy 48.568643 -151.216102) (xy 48.640175 -151.177867)
			(xy 48.715111 -151.146828) (xy 48.792727 -151.123283) (xy 48.872278 -151.10746) (xy 48.952997 -151.09951)
			(xy 49.034107 -151.09951) (xy 49.114826 -151.10746) (xy 49.194377 -151.123283) (xy 49.271993 -151.146828)
			(xy 49.346929 -151.177867) (xy 49.418461 -151.216102) (xy 49.485901 -151.261164) (xy 49.5486 -151.312619)
			(xy 49.605953 -151.369972) (xy 49.657408 -151.432671) (xy 49.70247 -151.500111) (xy 49.740705 -151.571643)
			(xy 49.771744 -151.646579) (xy 49.795289 -151.724195) (xy 49.811112 -151.803746) (xy 49.819062 -151.884465)
			(xy 49.81956 -151.92502) (xy 49.819062 -151.965575) (xy 49.811112 -152.046294) (xy 49.795289 -152.125845)
			(xy 49.771744 -152.203461) (xy 49.740705 -152.278397) (xy 49.70247 -152.349929) (xy 49.657408 -152.417369)
			(xy 49.605953 -152.480068) (xy 49.5486 -152.537421) (xy 49.485901 -152.588876) (xy 49.418461 -152.633938)
			(xy 49.346929 -152.672173) (xy 49.271993 -152.703212) (xy 49.194377 -152.726757) (xy 49.114826 -152.74258)
			(xy 49.034107 -152.75053) (xy 48.952997 -152.75053) (xy 48.872278 -152.74258) (xy 48.792727 -152.726757)
			(xy 48.715111 -152.703212) (xy 48.640175 -152.672173) (xy 48.568643 -152.633938) (xy 48.501203 -152.588876)
			(xy 48.438504 -152.537421) (xy 48.381151 -152.480068) (xy 48.329696 -152.417369) (xy 48.284634 -152.349929)
			(xy 48.246399 -152.278397) (xy 48.21536 -152.203461) (xy 48.191815 -152.125845) (xy 48.175992 -152.046294)
			(xy 48.168042 -151.965575) (xy 29.290264 -151.965575) (xy 29.290264 -152.819963) (xy 58.029594 -152.819963)
			(xy 58.029594 -152.748641) (xy 58.03758 -152.677767) (xy 58.05345 -152.608232) (xy 58.077007 -152.540912)
			(xy 58.107952 -152.476653) (xy 58.145898 -152.416262) (xy 58.190367 -152.3605) (xy 58.2408 -152.310067)
			(xy 58.296562 -152.265598) (xy 58.356953 -152.227652) (xy 58.421212 -152.196707) (xy 58.488532 -152.17315)
			(xy 58.558067 -152.15728) (xy 58.628941 -152.149294) (xy 58.700263 -152.149294) (xy 58.771137 -152.15728)
			(xy 58.840672 -152.17315) (xy 58.907992 -152.196707) (xy 58.972251 -152.227652) (xy 59.032642 -152.265598)
			(xy 59.088404 -152.310067) (xy 59.138837 -152.3605) (xy 59.183306 -152.416262) (xy 59.221252 -152.476653)
			(xy 59.252197 -152.540912) (xy 59.275754 -152.608232) (xy 59.291624 -152.677767) (xy 59.29961 -152.748641)
			(xy 59.30011 -152.784302) (xy 59.29961 -152.819963) (xy 59.916306 -152.819963) (xy 59.916306 -152.748641)
			(xy 59.924292 -152.677767) (xy 59.940162 -152.608232) (xy 59.963719 -152.540912) (xy 59.994664 -152.476653)
			(xy 60.03261 -152.416262) (xy 60.077079 -152.3605) (xy 60.127512 -152.310067) (xy 60.183274 -152.265598)
			(xy 60.243665 -152.227652) (xy 60.307924 -152.196707) (xy 60.375244 -152.17315) (xy 60.444779 -152.15728)
			(xy 60.515653 -152.149294) (xy 60.586975 -152.149294) (xy 60.657849 -152.15728) (xy 60.727384 -152.17315)
			(xy 60.794704 -152.196707) (xy 60.858963 -152.227652) (xy 60.919354 -152.265598) (xy 60.975116 -152.310067)
			(xy 61.025549 -152.3605) (xy 61.070018 -152.416262) (xy 61.107964 -152.476653) (xy 61.138909 -152.540912)
			(xy 61.162466 -152.608232) (xy 61.178336 -152.677767) (xy 61.186322 -152.748641) (xy 61.186822 -152.784302)
			(xy 61.186322 -152.819963) (xy 62.157348 -152.819963) (xy 62.157348 -152.748641) (xy 62.165334 -152.677767)
			(xy 62.181204 -152.608232) (xy 62.204761 -152.540912) (xy 62.235706 -152.476653) (xy 62.273652 -152.416262)
			(xy 62.318121 -152.3605) (xy 62.368554 -152.310067) (xy 62.424316 -152.265598) (xy 62.484707 -152.227652)
			(xy 62.548966 -152.196707) (xy 62.616286 -152.17315) (xy 62.685821 -152.15728) (xy 62.756695 -152.149294)
			(xy 62.828017 -152.149294) (xy 62.898891 -152.15728) (xy 62.968426 -152.17315) (xy 63.035746 -152.196707)
			(xy 63.100005 -152.227652) (xy 63.160396 -152.265598) (xy 63.216158 -152.310067) (xy 63.266591 -152.3605)
			(xy 63.31106 -152.416262) (xy 63.349006 -152.476653) (xy 63.379951 -152.540912) (xy 63.403508 -152.608232)
			(xy 63.419378 -152.677767) (xy 63.427364 -152.748641) (xy 63.427864 -152.784302) (xy 63.427364 -152.819963)
			(xy 64.061332 -152.819963) (xy 64.061332 -152.748641) (xy 64.069318 -152.677767) (xy 64.085188 -152.608232)
			(xy 64.108745 -152.540912) (xy 64.13969 -152.476653) (xy 64.177636 -152.416262) (xy 64.222105 -152.3605)
			(xy 64.272538 -152.310067) (xy 64.3283 -152.265598) (xy 64.388691 -152.227652) (xy 64.45295 -152.196707)
			(xy 64.52027 -152.17315) (xy 64.589805 -152.15728) (xy 64.660679 -152.149294) (xy 64.732001 -152.149294)
			(xy 64.802875 -152.15728) (xy 64.87241 -152.17315) (xy 64.93973 -152.196707) (xy 65.003989 -152.227652)
			(xy 65.06438 -152.265598) (xy 65.120142 -152.310067) (xy 65.170575 -152.3605) (xy 65.215044 -152.416262)
			(xy 65.25299 -152.476653) (xy 65.283935 -152.540912) (xy 65.307492 -152.608232) (xy 65.323362 -152.677767)
			(xy 65.331348 -152.748641) (xy 65.331848 -152.784302) (xy 65.331348 -152.819963) (xy 65.323362 -152.890837)
			(xy 65.307492 -152.960372) (xy 65.283935 -153.027692) (xy 65.25299 -153.091951) (xy 65.215044 -153.152342)
			(xy 65.170575 -153.208104) (xy 65.120142 -153.258537) (xy 65.06438 -153.303006) (xy 65.003989 -153.340952)
			(xy 64.93973 -153.371897) (xy 64.87241 -153.395454) (xy 64.802875 -153.411324) (xy 64.732001 -153.41931)
			(xy 64.660679 -153.41931) (xy 64.589805 -153.411324) (xy 64.52027 -153.395454) (xy 64.45295 -153.371897)
			(xy 64.388691 -153.340952) (xy 64.3283 -153.303006) (xy 64.272538 -153.258537) (xy 64.222105 -153.208104)
			(xy 64.177636 -153.152342) (xy 64.13969 -153.091951) (xy 64.108745 -153.027692) (xy 64.085188 -152.960372)
			(xy 64.069318 -152.890837) (xy 64.061332 -152.819963) (xy 63.427364 -152.819963) (xy 63.419378 -152.890837)
			(xy 63.403508 -152.960372) (xy 63.379951 -153.027692) (xy 63.349006 -153.091951) (xy 63.31106 -153.152342)
			(xy 63.266591 -153.208104) (xy 63.216158 -153.258537) (xy 63.160396 -153.303006) (xy 63.100005 -153.340952)
			(xy 63.035746 -153.371897) (xy 62.968426 -153.395454) (xy 62.898891 -153.411324) (xy 62.828017 -153.41931)
			(xy 62.756695 -153.41931) (xy 62.685821 -153.411324) (xy 62.616286 -153.395454) (xy 62.548966 -153.371897)
			(xy 62.484707 -153.340952) (xy 62.424316 -153.303006) (xy 62.368554 -153.258537) (xy 62.318121 -153.208104)
			(xy 62.273652 -153.152342) (xy 62.235706 -153.091951) (xy 62.204761 -153.027692) (xy 62.181204 -152.960372)
			(xy 62.165334 -152.890837) (xy 62.157348 -152.819963) (xy 61.186322 -152.819963) (xy 61.178336 -152.890837)
			(xy 61.162466 -152.960372) (xy 61.138909 -153.027692) (xy 61.107964 -153.091951) (xy 61.070018 -153.152342)
			(xy 61.025549 -153.208104) (xy 60.975116 -153.258537) (xy 60.919354 -153.303006) (xy 60.858963 -153.340952)
			(xy 60.794704 -153.371897) (xy 60.727384 -153.395454) (xy 60.657849 -153.411324) (xy 60.586975 -153.41931)
			(xy 60.515653 -153.41931) (xy 60.444779 -153.411324) (xy 60.375244 -153.395454) (xy 60.307924 -153.371897)
			(xy 60.243665 -153.340952) (xy 60.183274 -153.303006) (xy 60.127512 -153.258537) (xy 60.077079 -153.208104)
			(xy 60.03261 -153.152342) (xy 59.994664 -153.091951) (xy 59.963719 -153.027692) (xy 59.940162 -152.960372)
			(xy 59.924292 -152.890837) (xy 59.916306 -152.819963) (xy 59.29961 -152.819963) (xy 59.291624 -152.890837)
			(xy 59.275754 -152.960372) (xy 59.252197 -153.027692) (xy 59.221252 -153.091951) (xy 59.183306 -153.152342)
			(xy 59.138837 -153.208104) (xy 59.088404 -153.258537) (xy 59.032642 -153.303006) (xy 58.972251 -153.340952)
			(xy 58.907992 -153.371897) (xy 58.840672 -153.395454) (xy 58.771137 -153.411324) (xy 58.700263 -153.41931)
			(xy 58.628941 -153.41931) (xy 58.558067 -153.411324) (xy 58.488532 -153.395454) (xy 58.421212 -153.371897)
			(xy 58.356953 -153.340952) (xy 58.296562 -153.303006) (xy 58.2408 -153.258537) (xy 58.190367 -153.208104)
			(xy 58.145898 -153.152342) (xy 58.107952 -153.091951) (xy 58.077007 -153.027692) (xy 58.05345 -152.960372)
			(xy 58.03758 -152.890837) (xy 58.029594 -152.819963) (xy 29.290264 -152.819963) (xy 29.290264 -154.495093)
			(xy 58.029594 -154.495093) (xy 58.029594 -154.423771) (xy 58.03758 -154.352897) (xy 58.05345 -154.283362)
			(xy 58.077007 -154.216042) (xy 58.107952 -154.151783) (xy 58.145898 -154.091392) (xy 58.190367 -154.03563)
			(xy 58.2408 -153.985197) (xy 58.296562 -153.940728) (xy 58.356953 -153.902782) (xy 58.421212 -153.871837)
			(xy 58.488532 -153.84828) (xy 58.558067 -153.83241) (xy 58.628941 -153.824424) (xy 58.700263 -153.824424)
			(xy 58.771137 -153.83241) (xy 58.840672 -153.84828) (xy 58.907992 -153.871837) (xy 58.972251 -153.902782)
			(xy 59.032642 -153.940728) (xy 59.088404 -153.985197) (xy 59.138837 -154.03563) (xy 59.183306 -154.091392)
			(xy 59.221252 -154.151783) (xy 59.252197 -154.216042) (xy 59.275754 -154.283362) (xy 59.291624 -154.352897)
			(xy 59.29961 -154.423771) (xy 59.30011 -154.459432) (xy 59.29961 -154.495093) (xy 59.916306 -154.495093)
			(xy 59.916306 -154.423771) (xy 59.924292 -154.352897) (xy 59.940162 -154.283362) (xy 59.963719 -154.216042)
			(xy 59.994664 -154.151783) (xy 60.03261 -154.091392) (xy 60.077079 -154.03563) (xy 60.127512 -153.985197)
			(xy 60.183274 -153.940728) (xy 60.243665 -153.902782) (xy 60.307924 -153.871837) (xy 60.375244 -153.84828)
			(xy 60.444779 -153.83241) (xy 60.515653 -153.824424) (xy 60.586975 -153.824424) (xy 60.657849 -153.83241)
			(xy 60.727384 -153.84828) (xy 60.794704 -153.871837) (xy 60.858963 -153.902782) (xy 60.919354 -153.940728)
			(xy 60.975116 -153.985197) (xy 61.025549 -154.03563) (xy 61.070018 -154.091392) (xy 61.107964 -154.151783)
			(xy 61.138909 -154.216042) (xy 61.162466 -154.283362) (xy 61.178336 -154.352897) (xy 61.186322 -154.423771)
			(xy 61.186822 -154.459432) (xy 61.186322 -154.495093) (xy 62.157348 -154.495093) (xy 62.157348 -154.423771)
			(xy 62.165334 -154.352897) (xy 62.181204 -154.283362) (xy 62.204761 -154.216042) (xy 62.235706 -154.151783)
			(xy 62.273652 -154.091392) (xy 62.318121 -154.03563) (xy 62.368554 -153.985197) (xy 62.424316 -153.940728)
			(xy 62.484707 -153.902782) (xy 62.548966 -153.871837) (xy 62.616286 -153.84828) (xy 62.685821 -153.83241)
			(xy 62.756695 -153.824424) (xy 62.828017 -153.824424) (xy 62.898891 -153.83241) (xy 62.968426 -153.84828)
			(xy 63.035746 -153.871837) (xy 63.100005 -153.902782) (xy 63.160396 -153.940728) (xy 63.216158 -153.985197)
			(xy 63.266591 -154.03563) (xy 63.31106 -154.091392) (xy 63.349006 -154.151783) (xy 63.379951 -154.216042)
			(xy 63.403508 -154.283362) (xy 63.419378 -154.352897) (xy 63.427364 -154.423771) (xy 63.427864 -154.459432)
			(xy 63.427364 -154.495093) (xy 64.061332 -154.495093) (xy 64.061332 -154.423771) (xy 64.069318 -154.352897)
			(xy 64.085188 -154.283362) (xy 64.108745 -154.216042) (xy 64.13969 -154.151783) (xy 64.177636 -154.091392)
			(xy 64.222105 -154.03563) (xy 64.272538 -153.985197) (xy 64.3283 -153.940728) (xy 64.388691 -153.902782)
			(xy 64.45295 -153.871837) (xy 64.52027 -153.84828) (xy 64.589805 -153.83241) (xy 64.660679 -153.824424)
			(xy 64.732001 -153.824424) (xy 64.802875 -153.83241) (xy 64.87241 -153.84828) (xy 64.93973 -153.871837)
			(xy 65.003989 -153.902782) (xy 65.06438 -153.940728) (xy 65.120142 -153.985197) (xy 65.170575 -154.03563)
			(xy 65.215044 -154.091392) (xy 65.25299 -154.151783) (xy 65.283935 -154.216042) (xy 65.307492 -154.283362)
			(xy 65.323362 -154.352897) (xy 65.331348 -154.423771) (xy 65.331848 -154.459432) (xy 65.331348 -154.495093)
			(xy 65.323362 -154.565967) (xy 65.307492 -154.635502) (xy 65.283935 -154.702822) (xy 65.25299 -154.767081)
			(xy 65.215044 -154.827472) (xy 65.170575 -154.883234) (xy 65.120142 -154.933667) (xy 65.06438 -154.978136)
			(xy 65.003989 -155.016082) (xy 64.93973 -155.047027) (xy 64.87241 -155.070584) (xy 64.802875 -155.086454)
			(xy 64.732001 -155.09444) (xy 64.660679 -155.09444) (xy 64.589805 -155.086454) (xy 64.52027 -155.070584)
			(xy 64.45295 -155.047027) (xy 64.388691 -155.016082) (xy 64.3283 -154.978136) (xy 64.272538 -154.933667)
			(xy 64.222105 -154.883234) (xy 64.177636 -154.827472) (xy 64.13969 -154.767081) (xy 64.108745 -154.702822)
			(xy 64.085188 -154.635502) (xy 64.069318 -154.565967) (xy 64.061332 -154.495093) (xy 63.427364 -154.495093)
			(xy 63.419378 -154.565967) (xy 63.403508 -154.635502) (xy 63.379951 -154.702822) (xy 63.349006 -154.767081)
			(xy 63.31106 -154.827472) (xy 63.266591 -154.883234) (xy 63.216158 -154.933667) (xy 63.160396 -154.978136)
			(xy 63.100005 -155.016082) (xy 63.035746 -155.047027) (xy 62.968426 -155.070584) (xy 62.898891 -155.086454)
			(xy 62.828017 -155.09444) (xy 62.756695 -155.09444) (xy 62.685821 -155.086454) (xy 62.616286 -155.070584)
			(xy 62.548966 -155.047027) (xy 62.484707 -155.016082) (xy 62.424316 -154.978136) (xy 62.368554 -154.933667)
			(xy 62.318121 -154.883234) (xy 62.273652 -154.827472) (xy 62.235706 -154.767081) (xy 62.204761 -154.702822)
			(xy 62.181204 -154.635502) (xy 62.165334 -154.565967) (xy 62.157348 -154.495093) (xy 61.186322 -154.495093)
			(xy 61.178336 -154.565967) (xy 61.162466 -154.635502) (xy 61.138909 -154.702822) (xy 61.107964 -154.767081)
			(xy 61.070018 -154.827472) (xy 61.025549 -154.883234) (xy 60.975116 -154.933667) (xy 60.919354 -154.978136)
			(xy 60.858963 -155.016082) (xy 60.794704 -155.047027) (xy 60.727384 -155.070584) (xy 60.657849 -155.086454)
			(xy 60.586975 -155.09444) (xy 60.515653 -155.09444) (xy 60.444779 -155.086454) (xy 60.375244 -155.070584)
			(xy 60.307924 -155.047027) (xy 60.243665 -155.016082) (xy 60.183274 -154.978136) (xy 60.127512 -154.933667)
			(xy 60.077079 -154.883234) (xy 60.03261 -154.827472) (xy 59.994664 -154.767081) (xy 59.963719 -154.702822)
			(xy 59.940162 -154.635502) (xy 59.924292 -154.565967) (xy 59.916306 -154.495093) (xy 59.29961 -154.495093)
			(xy 59.291624 -154.565967) (xy 59.275754 -154.635502) (xy 59.252197 -154.702822) (xy 59.221252 -154.767081)
			(xy 59.183306 -154.827472) (xy 59.138837 -154.883234) (xy 59.088404 -154.933667) (xy 59.032642 -154.978136)
			(xy 58.972251 -155.016082) (xy 58.907992 -155.047027) (xy 58.840672 -155.070584) (xy 58.771137 -155.086454)
			(xy 58.700263 -155.09444) (xy 58.628941 -155.09444) (xy 58.558067 -155.086454) (xy 58.488532 -155.070584)
			(xy 58.421212 -155.047027) (xy 58.356953 -155.016082) (xy 58.296562 -154.978136) (xy 58.2408 -154.933667)
			(xy 58.190367 -154.883234) (xy 58.145898 -154.827472) (xy 58.107952 -154.767081) (xy 58.077007 -154.702822)
			(xy 58.05345 -154.635502) (xy 58.03758 -154.565967) (xy 58.029594 -154.495093) (xy 29.290264 -154.495093)
			(xy 29.290264 -156.506265) (xy 57.98616 -156.506265) (xy 57.98616 -156.434943) (xy 57.994146 -156.364069)
			(xy 58.010016 -156.294534) (xy 58.033573 -156.227214) (xy 58.064518 -156.162955) (xy 58.102464 -156.102564)
			(xy 58.146933 -156.046802) (xy 58.197366 -155.996369) (xy 58.253128 -155.9519) (xy 58.313519 -155.913954)
			(xy 58.377778 -155.883009) (xy 58.445098 -155.859452) (xy 58.514633 -155.843582) (xy 58.585507 -155.835596)
			(xy 58.656829 -155.835596) (xy 58.727703 -155.843582) (xy 58.797238 -155.859452) (xy 58.864558 -155.883009)
			(xy 58.928817 -155.913954) (xy 58.989208 -155.9519) (xy 59.04497 -155.996369) (xy 59.095403 -156.046802)
			(xy 59.139872 -156.102564) (xy 59.177818 -156.162955) (xy 59.208763 -156.227214) (xy 59.23232 -156.294534)
			(xy 59.24819 -156.364069) (xy 59.256176 -156.434943) (xy 59.256676 -156.470604) (xy 59.256176 -156.506265)
			(xy 59.872872 -156.506265) (xy 59.872872 -156.434943) (xy 59.880858 -156.364069) (xy 59.896728 -156.294534)
			(xy 59.920285 -156.227214) (xy 59.95123 -156.162955) (xy 59.989176 -156.102564) (xy 60.033645 -156.046802)
			(xy 60.084078 -155.996369) (xy 60.13984 -155.9519) (xy 60.200231 -155.913954) (xy 60.26449 -155.883009)
			(xy 60.33181 -155.859452) (xy 60.401345 -155.843582) (xy 60.472219 -155.835596) (xy 60.543541 -155.835596)
			(xy 60.614415 -155.843582) (xy 60.68395 -155.859452) (xy 60.75127 -155.883009) (xy 60.815529 -155.913954)
			(xy 60.87592 -155.9519) (xy 60.931682 -155.996369) (xy 60.982115 -156.046802) (xy 61.026584 -156.102564)
			(xy 61.06453 -156.162955) (xy 61.095475 -156.227214) (xy 61.119032 -156.294534) (xy 61.134902 -156.364069)
			(xy 61.142888 -156.434943) (xy 61.143388 -156.470604) (xy 61.142888 -156.506265) (xy 62.113914 -156.506265)
			(xy 62.113914 -156.434943) (xy 62.1219 -156.364069) (xy 62.13777 -156.294534) (xy 62.161327 -156.227214)
			(xy 62.192272 -156.162955) (xy 62.230218 -156.102564) (xy 62.274687 -156.046802) (xy 62.32512 -155.996369)
			(xy 62.380882 -155.9519) (xy 62.441273 -155.913954) (xy 62.505532 -155.883009) (xy 62.572852 -155.859452)
			(xy 62.642387 -155.843582) (xy 62.713261 -155.835596) (xy 62.784583 -155.835596) (xy 62.855457 -155.843582)
			(xy 62.924992 -155.859452) (xy 62.992312 -155.883009) (xy 63.056571 -155.913954) (xy 63.116962 -155.9519)
			(xy 63.172724 -155.996369) (xy 63.223157 -156.046802) (xy 63.267626 -156.102564) (xy 63.305572 -156.162955)
			(xy 63.336517 -156.227214) (xy 63.360074 -156.294534) (xy 63.375944 -156.364069) (xy 63.38393 -156.434943)
			(xy 63.38443 -156.470604) (xy 63.38393 -156.506265) (xy 64.017898 -156.506265) (xy 64.017898 -156.434943)
			(xy 64.025884 -156.364069) (xy 64.041754 -156.294534) (xy 64.065311 -156.227214) (xy 64.096256 -156.162955)
			(xy 64.134202 -156.102564) (xy 64.178671 -156.046802) (xy 64.229104 -155.996369) (xy 64.284866 -155.9519)
			(xy 64.345257 -155.913954) (xy 64.409516 -155.883009) (xy 64.476836 -155.859452) (xy 64.546371 -155.843582)
			(xy 64.617245 -155.835596) (xy 64.688567 -155.835596) (xy 64.759441 -155.843582) (xy 64.828976 -155.859452)
			(xy 64.896296 -155.883009) (xy 64.960555 -155.913954) (xy 65.020946 -155.9519) (xy 65.076708 -155.996369)
			(xy 65.127141 -156.046802) (xy 65.17161 -156.102564) (xy 65.209556 -156.162955) (xy 65.240501 -156.227214)
			(xy 65.264058 -156.294534) (xy 65.279928 -156.364069) (xy 65.287914 -156.434943) (xy 65.288414 -156.470604)
			(xy 65.287914 -156.506265) (xy 65.279928 -156.577139) (xy 65.264058 -156.646674) (xy 65.240501 -156.713994)
			(xy 65.209556 -156.778253) (xy 65.17161 -156.838644) (xy 65.127141 -156.894406) (xy 65.076708 -156.944839)
			(xy 65.020946 -156.989308) (xy 64.960555 -157.027254) (xy 64.896296 -157.058199) (xy 64.828976 -157.081756)
			(xy 64.759441 -157.097626) (xy 64.688567 -157.105612) (xy 64.617245 -157.105612) (xy 64.546371 -157.097626)
			(xy 64.476836 -157.081756) (xy 64.409516 -157.058199) (xy 64.345257 -157.027254) (xy 64.284866 -156.989308)
			(xy 64.229104 -156.944839) (xy 64.178671 -156.894406) (xy 64.134202 -156.838644) (xy 64.096256 -156.778253)
			(xy 64.065311 -156.713994) (xy 64.041754 -156.646674) (xy 64.025884 -156.577139) (xy 64.017898 -156.506265)
			(xy 63.38393 -156.506265) (xy 63.375944 -156.577139) (xy 63.360074 -156.646674) (xy 63.336517 -156.713994)
			(xy 63.305572 -156.778253) (xy 63.267626 -156.838644) (xy 63.223157 -156.894406) (xy 63.172724 -156.944839)
			(xy 63.116962 -156.989308) (xy 63.056571 -157.027254) (xy 62.992312 -157.058199) (xy 62.924992 -157.081756)
			(xy 62.855457 -157.097626) (xy 62.784583 -157.105612) (xy 62.713261 -157.105612) (xy 62.642387 -157.097626)
			(xy 62.572852 -157.081756) (xy 62.505532 -157.058199) (xy 62.441273 -157.027254) (xy 62.380882 -156.989308)
			(xy 62.32512 -156.944839) (xy 62.274687 -156.894406) (xy 62.230218 -156.838644) (xy 62.192272 -156.778253)
			(xy 62.161327 -156.713994) (xy 62.13777 -156.646674) (xy 62.1219 -156.577139) (xy 62.113914 -156.506265)
			(xy 61.142888 -156.506265) (xy 61.134902 -156.577139) (xy 61.119032 -156.646674) (xy 61.095475 -156.713994)
			(xy 61.06453 -156.778253) (xy 61.026584 -156.838644) (xy 60.982115 -156.894406) (xy 60.931682 -156.944839)
			(xy 60.87592 -156.989308) (xy 60.815529 -157.027254) (xy 60.75127 -157.058199) (xy 60.68395 -157.081756)
			(xy 60.614415 -157.097626) (xy 60.543541 -157.105612) (xy 60.472219 -157.105612) (xy 60.401345 -157.097626)
			(xy 60.33181 -157.081756) (xy 60.26449 -157.058199) (xy 60.200231 -157.027254) (xy 60.13984 -156.989308)
			(xy 60.084078 -156.944839) (xy 60.033645 -156.894406) (xy 59.989176 -156.838644) (xy 59.95123 -156.778253)
			(xy 59.920285 -156.713994) (xy 59.896728 -156.646674) (xy 59.880858 -156.577139) (xy 59.872872 -156.506265)
			(xy 59.256176 -156.506265) (xy 59.24819 -156.577139) (xy 59.23232 -156.646674) (xy 59.208763 -156.713994)
			(xy 59.177818 -156.778253) (xy 59.139872 -156.838644) (xy 59.095403 -156.894406) (xy 59.04497 -156.944839)
			(xy 58.989208 -156.989308) (xy 58.928817 -157.027254) (xy 58.864558 -157.058199) (xy 58.797238 -157.081756)
			(xy 58.727703 -157.097626) (xy 58.656829 -157.105612) (xy 58.585507 -157.105612) (xy 58.514633 -157.097626)
			(xy 58.445098 -157.081756) (xy 58.377778 -157.058199) (xy 58.313519 -157.027254) (xy 58.253128 -156.989308)
			(xy 58.197366 -156.944839) (xy 58.146933 -156.894406) (xy 58.102464 -156.838644) (xy 58.064518 -156.778253)
			(xy 58.033573 -156.713994) (xy 58.010016 -156.646674) (xy 57.994146 -156.577139) (xy 57.98616 -156.506265)
			(xy 29.290264 -156.506265) (xy 29.290264 -158.396787) (xy 57.98616 -158.396787) (xy 57.98616 -158.325465)
			(xy 57.994146 -158.254591) (xy 58.010016 -158.185056) (xy 58.033573 -158.117736) (xy 58.064518 -158.053477)
			(xy 58.102464 -157.993086) (xy 58.146933 -157.937324) (xy 58.197366 -157.886891) (xy 58.253128 -157.842422)
			(xy 58.313519 -157.804476) (xy 58.377778 -157.773531) (xy 58.445098 -157.749974) (xy 58.514633 -157.734104)
			(xy 58.585507 -157.726118) (xy 58.656829 -157.726118) (xy 58.727703 -157.734104) (xy 58.797238 -157.749974)
			(xy 58.864558 -157.773531) (xy 58.928817 -157.804476) (xy 58.989208 -157.842422) (xy 59.04497 -157.886891)
			(xy 59.095403 -157.937324) (xy 59.139872 -157.993086) (xy 59.177818 -158.053477) (xy 59.208763 -158.117736)
			(xy 59.23232 -158.185056) (xy 59.24819 -158.254591) (xy 59.256176 -158.325465) (xy 59.256676 -158.361126)
			(xy 59.256176 -158.396787) (xy 59.872872 -158.396787) (xy 59.872872 -158.325465) (xy 59.880858 -158.254591)
			(xy 59.896728 -158.185056) (xy 59.920285 -158.117736) (xy 59.95123 -158.053477) (xy 59.989176 -157.993086)
			(xy 60.033645 -157.937324) (xy 60.084078 -157.886891) (xy 60.13984 -157.842422) (xy 60.200231 -157.804476)
			(xy 60.26449 -157.773531) (xy 60.33181 -157.749974) (xy 60.401345 -157.734104) (xy 60.472219 -157.726118)
			(xy 60.543541 -157.726118) (xy 60.614415 -157.734104) (xy 60.68395 -157.749974) (xy 60.75127 -157.773531)
			(xy 60.815529 -157.804476) (xy 60.87592 -157.842422) (xy 60.931682 -157.886891) (xy 60.982115 -157.937324)
			(xy 61.026584 -157.993086) (xy 61.06453 -158.053477) (xy 61.095475 -158.117736) (xy 61.119032 -158.185056)
			(xy 61.134902 -158.254591) (xy 61.142888 -158.325465) (xy 61.143388 -158.361126) (xy 61.142888 -158.396787)
			(xy 62.113914 -158.396787) (xy 62.113914 -158.325465) (xy 62.1219 -158.254591) (xy 62.13777 -158.185056)
			(xy 62.161327 -158.117736) (xy 62.192272 -158.053477) (xy 62.230218 -157.993086) (xy 62.274687 -157.937324)
			(xy 62.32512 -157.886891) (xy 62.380882 -157.842422) (xy 62.441273 -157.804476) (xy 62.505532 -157.773531)
			(xy 62.572852 -157.749974) (xy 62.642387 -157.734104) (xy 62.713261 -157.726118) (xy 62.784583 -157.726118)
			(xy 62.855457 -157.734104) (xy 62.924992 -157.749974) (xy 62.992312 -157.773531) (xy 63.056571 -157.804476)
			(xy 63.116962 -157.842422) (xy 63.172724 -157.886891) (xy 63.223157 -157.937324) (xy 63.267626 -157.993086)
			(xy 63.305572 -158.053477) (xy 63.336517 -158.117736) (xy 63.360074 -158.185056) (xy 63.375944 -158.254591)
			(xy 63.38393 -158.325465) (xy 63.38443 -158.361126) (xy 63.38393 -158.396787) (xy 64.017898 -158.396787)
			(xy 64.017898 -158.325465) (xy 64.025884 -158.254591) (xy 64.041754 -158.185056) (xy 64.065311 -158.117736)
			(xy 64.096256 -158.053477) (xy 64.134202 -157.993086) (xy 64.178671 -157.937324) (xy 64.229104 -157.886891)
			(xy 64.284866 -157.842422) (xy 64.345257 -157.804476) (xy 64.409516 -157.773531) (xy 64.476836 -157.749974)
			(xy 64.546371 -157.734104) (xy 64.617245 -157.726118) (xy 64.688567 -157.726118) (xy 64.759441 -157.734104)
			(xy 64.828976 -157.749974) (xy 64.896296 -157.773531) (xy 64.960555 -157.804476) (xy 65.020946 -157.842422)
			(xy 65.076708 -157.886891) (xy 65.127141 -157.937324) (xy 65.17161 -157.993086) (xy 65.209556 -158.053477)
			(xy 65.240501 -158.117736) (xy 65.264058 -158.185056) (xy 65.279928 -158.254591) (xy 65.287914 -158.325465)
			(xy 65.288414 -158.361126) (xy 65.287914 -158.396787) (xy 65.279928 -158.467661) (xy 65.264058 -158.537196)
			(xy 65.240501 -158.604516) (xy 65.236321 -158.613195) (xy 67.292974 -158.613195) (xy 67.292974 -158.541873)
			(xy 67.30096 -158.470999) (xy 67.31683 -158.401464) (xy 67.340387 -158.334144) (xy 67.371332 -158.269885)
			(xy 67.409278 -158.209494) (xy 67.453747 -158.153732) (xy 67.50418 -158.103299) (xy 67.559942 -158.05883)
			(xy 67.620333 -158.020884) (xy 67.684592 -157.989939) (xy 67.751912 -157.966382) (xy 67.821447 -157.950512)
			(xy 67.892321 -157.942526) (xy 67.963643 -157.942526) (xy 68.034517 -157.950512) (xy 68.104052 -157.966382)
			(xy 68.171372 -157.989939) (xy 68.235631 -158.020884) (xy 68.296022 -158.05883) (xy 68.351784 -158.103299)
			(xy 68.402217 -158.153732) (xy 68.446686 -158.209494) (xy 68.484632 -158.269885) (xy 68.515577 -158.334144)
			(xy 68.539134 -158.401464) (xy 68.555004 -158.470999) (xy 68.56299 -158.541873) (xy 68.56349 -158.577534)
			(xy 68.56299 -158.613195) (xy 68.555004 -158.684069) (xy 68.553441 -158.690919) (xy 70.242168 -158.690919)
			(xy 70.242168 -158.619597) (xy 70.250154 -158.548723) (xy 70.266024 -158.479188) (xy 70.289581 -158.411868)
			(xy 70.320526 -158.347609) (xy 70.358472 -158.287218) (xy 70.402941 -158.231456) (xy 70.453374 -158.181023)
			(xy 70.509136 -158.136554) (xy 70.569527 -158.098608) (xy 70.633786 -158.067663) (xy 70.701106 -158.044106)
			(xy 70.770641 -158.028236) (xy 70.841515 -158.02025) (xy 70.912837 -158.02025) (xy 70.983711 -158.028236)
			(xy 71.053246 -158.044106) (xy 71.120566 -158.067663) (xy 71.184825 -158.098608) (xy 71.245216 -158.136554)
			(xy 71.300978 -158.181023) (xy 71.351411 -158.231456) (xy 71.39588 -158.287218) (xy 71.433826 -158.347609)
			(xy 71.464771 -158.411868) (xy 71.488328 -158.479188) (xy 71.504198 -158.548723) (xy 71.512184 -158.619597)
			(xy 71.512684 -158.655258) (xy 71.512184 -158.690919) (xy 71.504198 -158.761793) (xy 71.488328 -158.831328)
			(xy 71.464771 -158.898648) (xy 71.433826 -158.962907) (xy 71.39588 -159.023298) (xy 71.351411 -159.07906)
			(xy 71.300978 -159.129493) (xy 71.245216 -159.173962) (xy 71.184825 -159.211908) (xy 71.120566 -159.242853)
			(xy 71.053246 -159.26641) (xy 70.983711 -159.28228) (xy 70.912837 -159.290266) (xy 70.841515 -159.290266)
			(xy 70.770641 -159.28228) (xy 70.701106 -159.26641) (xy 70.633786 -159.242853) (xy 70.569527 -159.211908)
			(xy 70.509136 -159.173962) (xy 70.453374 -159.129493) (xy 70.402941 -159.07906) (xy 70.358472 -159.023298)
			(xy 70.320526 -158.962907) (xy 70.289581 -158.898648) (xy 70.266024 -158.831328) (xy 70.250154 -158.761793)
			(xy 70.242168 -158.690919) (xy 68.553441 -158.690919) (xy 68.539134 -158.753604) (xy 68.515577 -158.820924)
			(xy 68.484632 -158.885183) (xy 68.446686 -158.945574) (xy 68.402217 -159.001336) (xy 68.351784 -159.051769)
			(xy 68.296022 -159.096238) (xy 68.235631 -159.134184) (xy 68.171372 -159.165129) (xy 68.104052 -159.188686)
			(xy 68.034517 -159.204556) (xy 67.963643 -159.212542) (xy 67.892321 -159.212542) (xy 67.821447 -159.204556)
			(xy 67.751912 -159.188686) (xy 67.684592 -159.165129) (xy 67.620333 -159.134184) (xy 67.559942 -159.096238)
			(xy 67.50418 -159.051769) (xy 67.453747 -159.001336) (xy 67.409278 -158.945574) (xy 67.371332 -158.885183)
			(xy 67.340387 -158.820924) (xy 67.31683 -158.753604) (xy 67.30096 -158.684069) (xy 67.292974 -158.613195)
			(xy 65.236321 -158.613195) (xy 65.209556 -158.668775) (xy 65.17161 -158.729166) (xy 65.127141 -158.784928)
			(xy 65.076708 -158.835361) (xy 65.020946 -158.87983) (xy 64.960555 -158.917776) (xy 64.896296 -158.948721)
			(xy 64.828976 -158.972278) (xy 64.759441 -158.988148) (xy 64.688567 -158.996134) (xy 64.617245 -158.996134)
			(xy 64.546371 -158.988148) (xy 64.476836 -158.972278) (xy 64.409516 -158.948721) (xy 64.345257 -158.917776)
			(xy 64.284866 -158.87983) (xy 64.229104 -158.835361) (xy 64.178671 -158.784928) (xy 64.134202 -158.729166)
			(xy 64.096256 -158.668775) (xy 64.065311 -158.604516) (xy 64.041754 -158.537196) (xy 64.025884 -158.467661)
			(xy 64.017898 -158.396787) (xy 63.38393 -158.396787) (xy 63.375944 -158.467661) (xy 63.360074 -158.537196)
			(xy 63.336517 -158.604516) (xy 63.305572 -158.668775) (xy 63.267626 -158.729166) (xy 63.223157 -158.784928)
			(xy 63.172724 -158.835361) (xy 63.116962 -158.87983) (xy 63.056571 -158.917776) (xy 62.992312 -158.948721)
			(xy 62.924992 -158.972278) (xy 62.855457 -158.988148) (xy 62.784583 -158.996134) (xy 62.713261 -158.996134)
			(xy 62.642387 -158.988148) (xy 62.572852 -158.972278) (xy 62.505532 -158.948721) (xy 62.441273 -158.917776)
			(xy 62.380882 -158.87983) (xy 62.32512 -158.835361) (xy 62.274687 -158.784928) (xy 62.230218 -158.729166)
			(xy 62.192272 -158.668775) (xy 62.161327 -158.604516) (xy 62.13777 -158.537196) (xy 62.1219 -158.467661)
			(xy 62.113914 -158.396787) (xy 61.142888 -158.396787) (xy 61.134902 -158.467661) (xy 61.119032 -158.537196)
			(xy 61.095475 -158.604516) (xy 61.06453 -158.668775) (xy 61.026584 -158.729166) (xy 60.982115 -158.784928)
			(xy 60.931682 -158.835361) (xy 60.87592 -158.87983) (xy 60.815529 -158.917776) (xy 60.75127 -158.948721)
			(xy 60.68395 -158.972278) (xy 60.614415 -158.988148) (xy 60.543541 -158.996134) (xy 60.472219 -158.996134)
			(xy 60.401345 -158.988148) (xy 60.33181 -158.972278) (xy 60.26449 -158.948721) (xy 60.200231 -158.917776)
			(xy 60.13984 -158.87983) (xy 60.084078 -158.835361) (xy 60.033645 -158.784928) (xy 59.989176 -158.729166)
			(xy 59.95123 -158.668775) (xy 59.920285 -158.604516) (xy 59.896728 -158.537196) (xy 59.880858 -158.467661)
			(xy 59.872872 -158.396787) (xy 59.256176 -158.396787) (xy 59.24819 -158.467661) (xy 59.23232 -158.537196)
			(xy 59.208763 -158.604516) (xy 59.177818 -158.668775) (xy 59.139872 -158.729166) (xy 59.095403 -158.784928)
			(xy 59.04497 -158.835361) (xy 58.989208 -158.87983) (xy 58.928817 -158.917776) (xy 58.864558 -158.948721)
			(xy 58.797238 -158.972278) (xy 58.727703 -158.988148) (xy 58.656829 -158.996134) (xy 58.585507 -158.996134)
			(xy 58.514633 -158.988148) (xy 58.445098 -158.972278) (xy 58.377778 -158.948721) (xy 58.313519 -158.917776)
			(xy 58.253128 -158.87983) (xy 58.197366 -158.835361) (xy 58.146933 -158.784928) (xy 58.102464 -158.729166)
			(xy 58.064518 -158.668775) (xy 58.033573 -158.604516) (xy 58.010016 -158.537196) (xy 57.994146 -158.467661)
			(xy 57.98616 -158.396787) (xy 29.290264 -158.396787) (xy 29.290264 -160.437931) (xy 57.98616 -160.437931)
			(xy 57.98616 -160.366609) (xy 57.994146 -160.295735) (xy 58.010016 -160.2262) (xy 58.033573 -160.15888)
			(xy 58.064518 -160.094621) (xy 58.102464 -160.03423) (xy 58.146933 -159.978468) (xy 58.197366 -159.928035)
			(xy 58.253128 -159.883566) (xy 58.313519 -159.84562) (xy 58.377778 -159.814675) (xy 58.445098 -159.791118)
			(xy 58.514633 -159.775248) (xy 58.585507 -159.767262) (xy 58.656829 -159.767262) (xy 58.727703 -159.775248)
			(xy 58.797238 -159.791118) (xy 58.864558 -159.814675) (xy 58.928817 -159.84562) (xy 58.989208 -159.883566)
			(xy 59.04497 -159.928035) (xy 59.095403 -159.978468) (xy 59.139872 -160.03423) (xy 59.177818 -160.094621)
			(xy 59.208763 -160.15888) (xy 59.23232 -160.2262) (xy 59.24819 -160.295735) (xy 59.256176 -160.366609)
			(xy 59.256676 -160.40227) (xy 59.256176 -160.437931) (xy 59.872872 -160.437931) (xy 59.872872 -160.366609)
			(xy 59.880858 -160.295735) (xy 59.896728 -160.2262) (xy 59.920285 -160.15888) (xy 59.95123 -160.094621)
			(xy 59.989176 -160.03423) (xy 60.033645 -159.978468) (xy 60.084078 -159.928035) (xy 60.13984 -159.883566)
			(xy 60.200231 -159.84562) (xy 60.26449 -159.814675) (xy 60.33181 -159.791118) (xy 60.401345 -159.775248)
			(xy 60.472219 -159.767262) (xy 60.543541 -159.767262) (xy 60.614415 -159.775248) (xy 60.68395 -159.791118)
			(xy 60.75127 -159.814675) (xy 60.815529 -159.84562) (xy 60.87592 -159.883566) (xy 60.931682 -159.928035)
			(xy 60.982115 -159.978468) (xy 61.026584 -160.03423) (xy 61.06453 -160.094621) (xy 61.095475 -160.15888)
			(xy 61.119032 -160.2262) (xy 61.134902 -160.295735) (xy 61.142888 -160.366609) (xy 61.143388 -160.40227)
			(xy 61.142888 -160.437931) (xy 62.113914 -160.437931) (xy 62.113914 -160.366609) (xy 62.1219 -160.295735)
			(xy 62.13777 -160.2262) (xy 62.161327 -160.15888) (xy 62.192272 -160.094621) (xy 62.230218 -160.03423)
			(xy 62.274687 -159.978468) (xy 62.32512 -159.928035) (xy 62.380882 -159.883566) (xy 62.441273 -159.84562)
			(xy 62.505532 -159.814675) (xy 62.572852 -159.791118) (xy 62.642387 -159.775248) (xy 62.713261 -159.767262)
			(xy 62.784583 -159.767262) (xy 62.855457 -159.775248) (xy 62.924992 -159.791118) (xy 62.992312 -159.814675)
			(xy 63.056571 -159.84562) (xy 63.116962 -159.883566) (xy 63.172724 -159.928035) (xy 63.223157 -159.978468)
			(xy 63.267626 -160.03423) (xy 63.305572 -160.094621) (xy 63.336517 -160.15888) (xy 63.360074 -160.2262)
			(xy 63.375944 -160.295735) (xy 63.38393 -160.366609) (xy 63.38443 -160.40227) (xy 63.38393 -160.437931)
			(xy 64.017898 -160.437931) (xy 64.017898 -160.366609) (xy 64.025884 -160.295735) (xy 64.041754 -160.2262)
			(xy 64.065311 -160.15888) (xy 64.096256 -160.094621) (xy 64.134202 -160.03423) (xy 64.178671 -159.978468)
			(xy 64.229104 -159.928035) (xy 64.284866 -159.883566) (xy 64.345257 -159.84562) (xy 64.409516 -159.814675)
			(xy 64.476836 -159.791118) (xy 64.546371 -159.775248) (xy 64.617245 -159.767262) (xy 64.688567 -159.767262)
			(xy 64.759441 -159.775248) (xy 64.828976 -159.791118) (xy 64.896296 -159.814675) (xy 64.960555 -159.84562)
			(xy 65.020946 -159.883566) (xy 65.076708 -159.928035) (xy 65.127141 -159.978468) (xy 65.17161 -160.03423)
			(xy 65.209556 -160.094621) (xy 65.240501 -160.15888) (xy 65.264058 -160.2262) (xy 65.279928 -160.295735)
			(xy 65.287914 -160.366609) (xy 65.288414 -160.40227) (xy 65.287914 -160.437931) (xy 65.279928 -160.508805)
			(xy 65.264058 -160.57834) (xy 65.240501 -160.64566) (xy 65.209556 -160.709919) (xy 65.17161 -160.77031)
			(xy 65.127141 -160.826072) (xy 65.076708 -160.876505) (xy 65.020946 -160.920974) (xy 64.960555 -160.95892)
			(xy 64.896296 -160.989865) (xy 64.828976 -161.013422) (xy 64.759441 -161.029292) (xy 64.688567 -161.037278)
			(xy 64.617245 -161.037278) (xy 64.546371 -161.029292) (xy 64.476836 -161.013422) (xy 64.409516 -160.989865)
			(xy 64.345257 -160.95892) (xy 64.284866 -160.920974) (xy 64.229104 -160.876505) (xy 64.178671 -160.826072)
			(xy 64.134202 -160.77031) (xy 64.096256 -160.709919) (xy 64.065311 -160.64566) (xy 64.041754 -160.57834)
			(xy 64.025884 -160.508805) (xy 64.017898 -160.437931) (xy 63.38393 -160.437931) (xy 63.375944 -160.508805)
			(xy 63.360074 -160.57834) (xy 63.336517 -160.64566) (xy 63.305572 -160.709919) (xy 63.267626 -160.77031)
			(xy 63.223157 -160.826072) (xy 63.172724 -160.876505) (xy 63.116962 -160.920974) (xy 63.056571 -160.95892)
			(xy 62.992312 -160.989865) (xy 62.924992 -161.013422) (xy 62.855457 -161.029292) (xy 62.784583 -161.037278)
			(xy 62.713261 -161.037278) (xy 62.642387 -161.029292) (xy 62.572852 -161.013422) (xy 62.505532 -160.989865)
			(xy 62.441273 -160.95892) (xy 62.380882 -160.920974) (xy 62.32512 -160.876505) (xy 62.274687 -160.826072)
			(xy 62.230218 -160.77031) (xy 62.192272 -160.709919) (xy 62.161327 -160.64566) (xy 62.13777 -160.57834)
			(xy 62.1219 -160.508805) (xy 62.113914 -160.437931) (xy 61.142888 -160.437931) (xy 61.134902 -160.508805)
			(xy 61.119032 -160.57834) (xy 61.095475 -160.64566) (xy 61.06453 -160.709919) (xy 61.026584 -160.77031)
			(xy 60.982115 -160.826072) (xy 60.931682 -160.876505) (xy 60.87592 -160.920974) (xy 60.815529 -160.95892)
			(xy 60.75127 -160.989865) (xy 60.68395 -161.013422) (xy 60.614415 -161.029292) (xy 60.543541 -161.037278)
			(xy 60.472219 -161.037278) (xy 60.401345 -161.029292) (xy 60.33181 -161.013422) (xy 60.26449 -160.989865)
			(xy 60.200231 -160.95892) (xy 60.13984 -160.920974) (xy 60.084078 -160.876505) (xy 60.033645 -160.826072)
			(xy 59.989176 -160.77031) (xy 59.95123 -160.709919) (xy 59.920285 -160.64566) (xy 59.896728 -160.57834)
			(xy 59.880858 -160.508805) (xy 59.872872 -160.437931) (xy 59.256176 -160.437931) (xy 59.24819 -160.508805)
			(xy 59.23232 -160.57834) (xy 59.208763 -160.64566) (xy 59.177818 -160.709919) (xy 59.139872 -160.77031)
			(xy 59.095403 -160.826072) (xy 59.04497 -160.876505) (xy 58.989208 -160.920974) (xy 58.928817 -160.95892)
			(xy 58.864558 -160.989865) (xy 58.797238 -161.013422) (xy 58.727703 -161.029292) (xy 58.656829 -161.037278)
			(xy 58.585507 -161.037278) (xy 58.514633 -161.029292) (xy 58.445098 -161.013422) (xy 58.377778 -160.989865)
			(xy 58.313519 -160.95892) (xy 58.253128 -160.920974) (xy 58.197366 -160.876505) (xy 58.146933 -160.826072)
			(xy 58.102464 -160.77031) (xy 58.064518 -160.709919) (xy 58.033573 -160.64566) (xy 58.010016 -160.57834)
			(xy 57.994146 -160.508805) (xy 57.98616 -160.437931) (xy 29.290264 -160.437931) (xy 29.290264 -162.347757)
			(xy 57.98616 -162.347757) (xy 57.98616 -162.276435) (xy 57.994146 -162.205561) (xy 58.010016 -162.136026)
			(xy 58.033573 -162.068706) (xy 58.064518 -162.004447) (xy 58.102464 -161.944056) (xy 58.146933 -161.888294)
			(xy 58.197366 -161.837861) (xy 58.253128 -161.793392) (xy 58.313519 -161.755446) (xy 58.377778 -161.724501)
			(xy 58.445098 -161.700944) (xy 58.514633 -161.685074) (xy 58.585507 -161.677088) (xy 58.656829 -161.677088)
			(xy 58.727703 -161.685074) (xy 58.797238 -161.700944) (xy 58.864558 -161.724501) (xy 58.928817 -161.755446)
			(xy 58.989208 -161.793392) (xy 59.04497 -161.837861) (xy 59.095403 -161.888294) (xy 59.139872 -161.944056)
			(xy 59.177818 -162.004447) (xy 59.208763 -162.068706) (xy 59.23232 -162.136026) (xy 59.24819 -162.205561)
			(xy 59.256176 -162.276435) (xy 59.256676 -162.312096) (xy 59.256176 -162.347757) (xy 59.872872 -162.347757)
			(xy 59.872872 -162.276435) (xy 59.880858 -162.205561) (xy 59.896728 -162.136026) (xy 59.920285 -162.068706)
			(xy 59.95123 -162.004447) (xy 59.989176 -161.944056) (xy 60.033645 -161.888294) (xy 60.084078 -161.837861)
			(xy 60.13984 -161.793392) (xy 60.200231 -161.755446) (xy 60.26449 -161.724501) (xy 60.33181 -161.700944)
			(xy 60.401345 -161.685074) (xy 60.472219 -161.677088) (xy 60.543541 -161.677088) (xy 60.614415 -161.685074)
			(xy 60.68395 -161.700944) (xy 60.75127 -161.724501) (xy 60.815529 -161.755446) (xy 60.87592 -161.793392)
			(xy 60.931682 -161.837861) (xy 60.982115 -161.888294) (xy 61.026584 -161.944056) (xy 61.06453 -162.004447)
			(xy 61.095475 -162.068706) (xy 61.119032 -162.136026) (xy 61.134902 -162.205561) (xy 61.142888 -162.276435)
			(xy 61.143388 -162.312096) (xy 61.142888 -162.347757) (xy 62.113914 -162.347757) (xy 62.113914 -162.276435)
			(xy 62.1219 -162.205561) (xy 62.13777 -162.136026) (xy 62.161327 -162.068706) (xy 62.192272 -162.004447)
			(xy 62.230218 -161.944056) (xy 62.274687 -161.888294) (xy 62.32512 -161.837861) (xy 62.380882 -161.793392)
			(xy 62.441273 -161.755446) (xy 62.505532 -161.724501) (xy 62.572852 -161.700944) (xy 62.642387 -161.685074)
			(xy 62.713261 -161.677088) (xy 62.784583 -161.677088) (xy 62.855457 -161.685074) (xy 62.924992 -161.700944)
			(xy 62.992312 -161.724501) (xy 63.056571 -161.755446) (xy 63.116962 -161.793392) (xy 63.172724 -161.837861)
			(xy 63.223157 -161.888294) (xy 63.267626 -161.944056) (xy 63.305572 -162.004447) (xy 63.336517 -162.068706)
			(xy 63.360074 -162.136026) (xy 63.375944 -162.205561) (xy 63.38393 -162.276435) (xy 63.38443 -162.312096)
			(xy 63.38393 -162.347757) (xy 64.017898 -162.347757) (xy 64.017898 -162.276435) (xy 64.025884 -162.205561)
			(xy 64.041754 -162.136026) (xy 64.065311 -162.068706) (xy 64.096256 -162.004447) (xy 64.134202 -161.944056)
			(xy 64.178671 -161.888294) (xy 64.229104 -161.837861) (xy 64.284866 -161.793392) (xy 64.345257 -161.755446)
			(xy 64.409516 -161.724501) (xy 64.476836 -161.700944) (xy 64.546371 -161.685074) (xy 64.617245 -161.677088)
			(xy 64.688567 -161.677088) (xy 64.759441 -161.685074) (xy 64.828976 -161.700944) (xy 64.896296 -161.724501)
			(xy 64.960555 -161.755446) (xy 65.020946 -161.793392) (xy 65.076708 -161.837861) (xy 65.127141 -161.888294)
			(xy 65.17161 -161.944056) (xy 65.209556 -162.004447) (xy 65.240501 -162.068706) (xy 65.264058 -162.136026)
			(xy 65.279928 -162.205561) (xy 65.287914 -162.276435) (xy 65.288414 -162.312096) (xy 65.287914 -162.347757)
			(xy 65.279928 -162.418631) (xy 65.264058 -162.488166) (xy 65.240501 -162.555486) (xy 65.209556 -162.619745)
			(xy 65.17161 -162.680136) (xy 65.127141 -162.735898) (xy 65.076708 -162.786331) (xy 65.020946 -162.8308)
			(xy 64.960555 -162.868746) (xy 64.896296 -162.899691) (xy 64.828976 -162.923248) (xy 64.759441 -162.939118)
			(xy 64.688567 -162.947104) (xy 64.617245 -162.947104) (xy 64.546371 -162.939118) (xy 64.476836 -162.923248)
			(xy 64.409516 -162.899691) (xy 64.345257 -162.868746) (xy 64.284866 -162.8308) (xy 64.229104 -162.786331)
			(xy 64.178671 -162.735898) (xy 64.134202 -162.680136) (xy 64.096256 -162.619745) (xy 64.065311 -162.555486)
			(xy 64.041754 -162.488166) (xy 64.025884 -162.418631) (xy 64.017898 -162.347757) (xy 63.38393 -162.347757)
			(xy 63.375944 -162.418631) (xy 63.360074 -162.488166) (xy 63.336517 -162.555486) (xy 63.305572 -162.619745)
			(xy 63.267626 -162.680136) (xy 63.223157 -162.735898) (xy 63.172724 -162.786331) (xy 63.116962 -162.8308)
			(xy 63.056571 -162.868746) (xy 62.992312 -162.899691) (xy 62.924992 -162.923248) (xy 62.855457 -162.939118)
			(xy 62.784583 -162.947104) (xy 62.713261 -162.947104) (xy 62.642387 -162.939118) (xy 62.572852 -162.923248)
			(xy 62.505532 -162.899691) (xy 62.441273 -162.868746) (xy 62.380882 -162.8308) (xy 62.32512 -162.786331)
			(xy 62.274687 -162.735898) (xy 62.230218 -162.680136) (xy 62.192272 -162.619745) (xy 62.161327 -162.555486)
			(xy 62.13777 -162.488166) (xy 62.1219 -162.418631) (xy 62.113914 -162.347757) (xy 61.142888 -162.347757)
			(xy 61.134902 -162.418631) (xy 61.119032 -162.488166) (xy 61.095475 -162.555486) (xy 61.06453 -162.619745)
			(xy 61.026584 -162.680136) (xy 60.982115 -162.735898) (xy 60.931682 -162.786331) (xy 60.87592 -162.8308)
			(xy 60.815529 -162.868746) (xy 60.75127 -162.899691) (xy 60.68395 -162.923248) (xy 60.614415 -162.939118)
			(xy 60.543541 -162.947104) (xy 60.472219 -162.947104) (xy 60.401345 -162.939118) (xy 60.33181 -162.923248)
			(xy 60.26449 -162.899691) (xy 60.200231 -162.868746) (xy 60.13984 -162.8308) (xy 60.084078 -162.786331)
			(xy 60.033645 -162.735898) (xy 59.989176 -162.680136) (xy 59.95123 -162.619745) (xy 59.920285 -162.555486)
			(xy 59.896728 -162.488166) (xy 59.880858 -162.418631) (xy 59.872872 -162.347757) (xy 59.256176 -162.347757)
			(xy 59.24819 -162.418631) (xy 59.23232 -162.488166) (xy 59.208763 -162.555486) (xy 59.177818 -162.619745)
			(xy 59.139872 -162.680136) (xy 59.095403 -162.735898) (xy 59.04497 -162.786331) (xy 58.989208 -162.8308)
			(xy 58.928817 -162.868746) (xy 58.864558 -162.899691) (xy 58.797238 -162.923248) (xy 58.727703 -162.939118)
			(xy 58.656829 -162.947104) (xy 58.585507 -162.947104) (xy 58.514633 -162.939118) (xy 58.445098 -162.923248)
			(xy 58.377778 -162.899691) (xy 58.313519 -162.868746) (xy 58.253128 -162.8308) (xy 58.197366 -162.786331)
			(xy 58.146933 -162.735898) (xy 58.102464 -162.680136) (xy 58.064518 -162.619745) (xy 58.033573 -162.555486)
			(xy 58.010016 -162.488166) (xy 57.994146 -162.418631) (xy 57.98616 -162.347757) (xy 29.290264 -162.347757)
			(xy 29.290264 -171.364402) (xy 27.476333 -173.178385) (xy 47.641754 -173.178385) (xy 47.641754 -173.097275)
			(xy 47.649704 -173.016556) (xy 47.665527 -172.937005) (xy 47.689072 -172.859389) (xy 47.720111 -172.784453)
			(xy 47.758346 -172.712921) (xy 47.803408 -172.645481) (xy 47.854863 -172.582782) (xy 47.912216 -172.525429)
			(xy 47.974915 -172.473974) (xy 48.042355 -172.428912) (xy 48.113887 -172.390677) (xy 48.188823 -172.359638)
			(xy 48.266439 -172.336093) (xy 48.34599 -172.32027) (xy 48.426709 -172.31232) (xy 48.507819 -172.31232)
			(xy 48.588538 -172.32027) (xy 48.668089 -172.336093) (xy 48.745705 -172.359638) (xy 48.820641 -172.390677)
			(xy 48.892173 -172.428912) (xy 48.959613 -172.473974) (xy 49.022312 -172.525429) (xy 49.079665 -172.582782)
			(xy 49.13112 -172.645481) (xy 49.176182 -172.712921) (xy 49.214417 -172.784453) (xy 49.245456 -172.859389)
			(xy 49.269001 -172.937005) (xy 49.284824 -173.016556) (xy 49.292774 -173.097275) (xy 49.293272 -173.13783)
			(xy 49.292774 -173.178385) (xy 49.284824 -173.259104) (xy 49.269001 -173.338655) (xy 49.245456 -173.416271)
			(xy 49.214417 -173.491207) (xy 49.176182 -173.562739) (xy 49.13112 -173.630179) (xy 49.079665 -173.692878)
			(xy 49.022312 -173.750231) (xy 48.959613 -173.801686) (xy 48.892173 -173.846748) (xy 48.820641 -173.884983)
			(xy 48.745705 -173.916022) (xy 48.668089 -173.939567) (xy 48.588538 -173.95539) (xy 48.507819 -173.96334)
			(xy 48.426709 -173.96334) (xy 48.34599 -173.95539) (xy 48.266439 -173.939567) (xy 48.188823 -173.916022)
			(xy 48.113887 -173.884983) (xy 48.042355 -173.846748) (xy 47.974915 -173.801686) (xy 47.912216 -173.750231)
			(xy 47.854863 -173.692878) (xy 47.803408 -173.630179) (xy 47.758346 -173.562739) (xy 47.720111 -173.491207)
			(xy 47.689072 -173.416271) (xy 47.665527 -173.338655) (xy 47.649704 -173.259104) (xy 47.641754 -173.178385)
			(xy 27.476333 -173.178385) (xy 20.354036 -180.300884) (xy 20.354036 -180.516022) (xy 20.354534 -180.532681)
			(xy 20.363168 -180.564862) (xy 20.379841 -180.593709) (xy 20.403415 -180.617254) (xy 20.432283 -180.633892)
			(xy 20.464474 -180.642486) (xy 20.497792 -180.642451) (xy 20.529965 -180.633789) (xy 20.558798 -180.617091)
			(xy 20.570952 -180.605684) (xy 25.691592 -175.485044) (xy 58.30824 -175.485044) (xy 76.85278 -156.940504)
			(xy 76.85278 -147.236434) (xy 81.000854 -143.08836) (xy 81.341214 -143.08836) (xy 82.682842 -141.746732)
			(xy 82.692362 -141.735607) (xy 82.706547 -141.709999) (xy 82.71452 -141.681832) (xy 82.715608 -141.66723)
			(xy 82.715608 -137.14349) (xy 83.387946 -136.470898) (xy 83.472528 -136.386316) (xy 83.472528 -115.413282)
			(xy 81.210912 -113.151666) (xy 81.210912 -107.71251) (xy 81.195164 -107.683808) (xy 81.182247 -107.659467)
			(xy 81.162779 -107.607918) (xy 81.150931 -107.554103) (xy 81.14695 -107.499144) (xy 81.150918 -107.444184)
			(xy 81.162754 -107.390366) (xy 81.18221 -107.338812) (xy 81.195164 -107.314492) (xy 81.210912 -107.28579)
			(xy 81.210912 -102.297738) (xy 82.962242 -100.546408) (xy 82.97176 -100.535282) (xy 82.98594 -100.509674)
			(xy 82.993908 -100.481507) (xy 82.995008 -100.466906) (xy 82.995008 -94.70009) (xy 85.899752 -91.795092)
			(xy 92.00134 -91.795092) (xy 92.159074 -91.952826) (xy 93.413072 -93.207078) (xy 93.413072 -94.38259)
			(xy 92.302838 -95.492824) (xy 92.140786 -95.492824) (xy 92.124134 -95.49332) (xy 92.091965 -95.501944)
			(xy 92.063124 -95.518601) (xy 92.039577 -95.542154) (xy 92.02293 -95.571) (xy 92.014315 -95.603171)
			(xy 92.013786 -95.619824) (xy 92.013786 -95.666052) (xy 92.07246 -95.73641) (xy 92.117926 -95.744792)
			(xy 92.154139 -95.751894) (xy 92.224968 -95.772617) (xy 92.293274 -95.800557) (xy 92.358322 -95.835414)
			(xy 92.419414 -95.876814) (xy 92.475895 -95.924313) (xy 92.527159 -95.977401) (xy 92.572654 -96.035508)
			(xy 92.611894 -96.09801) (xy 92.644456 -96.164237) (xy 92.657676 -96.19869) (xy 92.670149 -96.233924)
			(xy 92.688497 -96.306385) (xy 92.699152 -96.380369) (xy 92.701998 -96.455063) (xy 92.697002 -96.529643)
			(xy 92.68422 -96.60329) (xy 92.663792 -96.675192) (xy 92.635944 -96.744558) (xy 92.600982 -96.810625)
			(xy 92.55929 -96.872666) (xy 92.511328 -96.929997) (xy 92.457623 -96.981987) (xy 92.398767 -97.028065)
			(xy 92.367354 -97.04832) (xy 92.35396 -97.057253) (xy 92.331812 -97.080607) (xy 92.316216 -97.108761)
			(xy 92.308163 -97.139923) (xy 92.307664 -97.156016) (xy 92.307664 -97.16008) (xy 93.154506 -97.16008)
			(xy 93.158522 -97.04381) (xy 93.170549 -96.928095) (xy 93.190531 -96.813485) (xy 93.218373 -96.700526)
			(xy 93.253942 -96.589758) (xy 93.297068 -96.481707) (xy 93.347545 -96.376889) (xy 93.405134 -96.275804)
			(xy 93.46956 -96.178932) (xy 93.540515 -96.086736) (xy 93.617662 -95.999655) (xy 93.700633 -95.918104)
			(xy 93.789033 -95.842472) (xy 93.88244 -95.773118) (xy 93.980409 -95.710375) (xy 94.082473 -95.654539)
			(xy 94.188147 -95.605878) (xy 94.296926 -95.564624) (xy 94.408291 -95.530973) (xy 94.521714 -95.505085)
			(xy 94.636651 -95.487084) (xy 94.752557 -95.477055) (xy 94.868879 -95.475047) (xy 94.985062 -95.481069)
			(xy 95.100553 -95.495092) (xy 95.214801 -95.51705) (xy 95.327262 -95.546837) (xy 95.4374 -95.584312)
			(xy 95.54469 -95.629297) (xy 95.648621 -95.681576) (xy 95.748697 -95.740901) (xy 95.844443 -95.806989)
			(xy 95.9354 -95.879525) (xy 96.021136 -95.958164) (xy 96.101243 -96.04253) (xy 96.175339 -96.132222)
			(xy 96.243069 -96.226812) (xy 96.304113 -96.32585) (xy 96.358178 -96.428863) (xy 96.405008 -96.53536)
			(xy 96.444379 -96.644835) (xy 96.476103 -96.756765) (xy 96.500029 -96.870617) (xy 96.516043 -96.985849)
			(xy 96.52407 -97.101911) (xy 96.524572 -97.16008) (xy 96.52407 -97.218249) (xy 96.516043 -97.334311)
			(xy 96.500029 -97.449543) (xy 96.476103 -97.563395) (xy 96.444379 -97.675325) (xy 96.405008 -97.7848)
			(xy 96.358178 -97.891297) (xy 96.304113 -97.99431) (xy 96.243069 -98.093348) (xy 96.175339 -98.187938)
			(xy 96.101243 -98.27763) (xy 96.021136 -98.361996) (xy 95.9354 -98.440635) (xy 95.844443 -98.513171)
			(xy 95.748697 -98.579259) (xy 95.648621 -98.638584) (xy 95.54469 -98.690863) (xy 95.4374 -98.735848)
			(xy 95.327262 -98.773323) (xy 95.214801 -98.80311) (xy 95.100553 -98.825068) (xy 94.985062 -98.839091)
			(xy 94.868879 -98.845113) (xy 94.752557 -98.843105) (xy 94.636651 -98.833076) (xy 94.521714 -98.815075)
			(xy 94.408291 -98.789187) (xy 94.296926 -98.755536) (xy 94.188147 -98.714282) (xy 94.082473 -98.665621)
			(xy 93.980409 -98.609785) (xy 93.88244 -98.547042) (xy 93.789033 -98.477688) (xy 93.700633 -98.402056)
			(xy 93.617662 -98.320505) (xy 93.540515 -98.233424) (xy 93.46956 -98.141228) (xy 93.405134 -98.044356)
			(xy 93.347545 -97.943271) (xy 93.297068 -97.838453) (xy 93.253942 -97.730402) (xy 93.218373 -97.619634)
			(xy 93.190531 -97.506675) (xy 93.170549 -97.392065) (xy 93.158522 -97.27635) (xy 93.154506 -97.16008)
			(xy 92.307664 -97.16008) (xy 92.307664 -97.679002) (xy 91.23426 -98.75266) (xy 91.099132 -98.887788)
			(xy 90.482166 -98.887788) (xy 87.320882 -102.049072) (xy 92.029532 -102.049072) (xy 92.033603 -101.99345)
			(xy 92.045729 -101.939013) (xy 92.065652 -101.886922) (xy 92.092948 -101.838287) (xy 92.127034 -101.794144)
			(xy 92.167183 -101.755435) (xy 92.212541 -101.722984) (xy 92.262141 -101.697483) (xy 92.314925 -101.679476)
			(xy 92.369768 -101.669346) (xy 92.425502 -101.667309) (xy 92.480939 -101.673409) (xy 92.534896 -101.687515)
			(xy 92.586225 -101.709327) (xy 92.633831 -101.738381) (xy 92.676699 -101.774056) (xy 92.713916 -101.815593)
			(xy 92.744689 -101.862106) (xy 92.768361 -101.912603) (xy 92.77228 -101.925628) (xy 94.75165 -101.925628)
			(xy 94.755721 -101.870006) (xy 94.767847 -101.815569) (xy 94.78777 -101.763478) (xy 94.815066 -101.714843)
			(xy 94.849152 -101.6707) (xy 94.889301 -101.631991) (xy 94.934659 -101.59954) (xy 94.984259 -101.574039)
			(xy 95.037043 -101.556032) (xy 95.091886 -101.545902) (xy 95.14762 -101.543865) (xy 95.203057 -101.549965)
			(xy 95.257014 -101.564071) (xy 95.308343 -101.585883) (xy 95.355949 -101.614937) (xy 95.398817 -101.650612)
			(xy 95.436034 -101.692149) (xy 95.466807 -101.738662) (xy 95.490479 -101.789159) (xy 95.506547 -101.842566)
			(xy 95.514667 -101.897742) (xy 95.515176 -101.925628) (xy 95.514667 -101.953514) (xy 95.506547 -102.00869)
			(xy 95.490479 -102.062097) (xy 95.466807 -102.112594) (xy 95.436034 -102.159107) (xy 95.398817 -102.200644)
			(xy 95.355949 -102.236319) (xy 95.308343 -102.265373) (xy 95.257014 -102.287185) (xy 95.203057 -102.301291)
			(xy 95.14762 -102.307391) (xy 95.091886 -102.305354) (xy 95.037043 -102.295224) (xy 94.984259 -102.277217)
			(xy 94.934659 -102.251716) (xy 94.889301 -102.219265) (xy 94.849152 -102.180556) (xy 94.815066 -102.136413)
			(xy 94.78777 -102.087778) (xy 94.767847 -102.035687) (xy 94.755721 -101.98125) (xy 94.75165 -101.925628)
			(xy 92.77228 -101.925628) (xy 92.784429 -101.96601) (xy 92.792549 -102.021186) (xy 92.793058 -102.049072)
			(xy 92.792549 -102.076958) (xy 92.784429 -102.132134) (xy 92.768361 -102.185541) (xy 92.744689 -102.236038)
			(xy 92.713916 -102.282551) (xy 92.676699 -102.324088) (xy 92.633831 -102.359763) (xy 92.586225 -102.388817)
			(xy 92.534896 -102.410629) (xy 92.480939 -102.424735) (xy 92.425502 -102.430835) (xy 92.369768 -102.428798)
			(xy 92.314925 -102.418668) (xy 92.262141 -102.400661) (xy 92.212541 -102.37516) (xy 92.167183 -102.342709)
			(xy 92.127034 -102.304) (xy 92.092948 -102.259857) (xy 92.065652 -102.211222) (xy 92.045729 -102.159131)
			(xy 92.033603 -102.104694) (xy 92.029532 -102.049072) (xy 87.320882 -102.049072) (xy 87.268558 -102.101396)
			(xy 87.259414 -102.132892) (xy 87.251336 -102.159291) (xy 87.228629 -102.209612) (xy 87.198908 -102.256136)
			(xy 87.162793 -102.297891) (xy 87.121038 -102.334007) (xy 87.074515 -102.363728) (xy 87.024194 -102.386435)
			(xy 86.997794 -102.394512) (xy 86.966298 -102.403656) (xy 86.675722 -102.694232) (xy 93.32036 -102.694232)
			(xy 93.324431 -102.63861) (xy 93.336557 -102.584173) (xy 93.35648 -102.532082) (xy 93.383776 -102.483447)
			(xy 93.417862 -102.439304) (xy 93.458011 -102.400595) (xy 93.503369 -102.368144) (xy 93.552969 -102.342643)
			(xy 93.605753 -102.324636) (xy 93.660596 -102.314506) (xy 93.71633 -102.312469) (xy 93.771767 -102.318569)
			(xy 93.825724 -102.332675) (xy 93.877053 -102.354487) (xy 93.924659 -102.383541) (xy 93.967527 -102.419216)
			(xy 94.004744 -102.460753) (xy 94.035517 -102.507266) (xy 94.059189 -102.557763) (xy 94.075257 -102.61117)
			(xy 94.07593 -102.615746) (xy 96.360994 -102.615746) (xy 96.365065 -102.560124) (xy 96.377191 -102.505687)
			(xy 96.397114 -102.453596) (xy 96.42441 -102.404961) (xy 96.458496 -102.360818) (xy 96.498645 -102.322109)
			(xy 96.544003 -102.289658) (xy 96.593603 -102.264157) (xy 96.646387 -102.24615) (xy 96.70123 -102.23602)
			(xy 96.756964 -102.233983) (xy 96.812401 -102.240083) (xy 96.866358 -102.254189) (xy 96.917687 -102.276001)
			(xy 96.965293 -102.305055) (xy 97.008161 -102.34073) (xy 97.045378 -102.382267) (xy 97.076151 -102.42878)
			(xy 97.099823 -102.479277) (xy 97.115891 -102.532684) (xy 97.124011 -102.58786) (xy 97.12452 -102.615746)
			(xy 97.124011 -102.643632) (xy 97.115891 -102.698808) (xy 97.099823 -102.752215) (xy 97.076151 -102.802712)
			(xy 97.045378 -102.849225) (xy 97.008161 -102.890762) (xy 96.965293 -102.926437) (xy 96.917687 -102.955491)
			(xy 96.866358 -102.977303) (xy 96.812401 -102.991409) (xy 96.756964 -102.997509) (xy 96.70123 -102.995472)
			(xy 96.646387 -102.985342) (xy 96.593603 -102.967335) (xy 96.544003 -102.941834) (xy 96.498645 -102.909383)
			(xy 96.458496 -102.870674) (xy 96.42441 -102.826531) (xy 96.397114 -102.777896) (xy 96.377191 -102.725805)
			(xy 96.365065 -102.671368) (xy 96.360994 -102.615746) (xy 94.07593 -102.615746) (xy 94.083377 -102.666346)
			(xy 94.083886 -102.694232) (xy 94.083377 -102.722118) (xy 94.075257 -102.777294) (xy 94.059189 -102.830701)
			(xy 94.035517 -102.881198) (xy 94.004744 -102.927711) (xy 93.967527 -102.969248) (xy 93.924659 -103.004923)
			(xy 93.877053 -103.033977) (xy 93.825724 -103.055789) (xy 93.771767 -103.069895) (xy 93.71633 -103.075995)
			(xy 93.660596 -103.073958) (xy 93.605753 -103.063828) (xy 93.552969 -103.045821) (xy 93.503369 -103.02032)
			(xy 93.458011 -102.987869) (xy 93.417862 -102.94916) (xy 93.383776 -102.905017) (xy 93.35648 -102.856382)
			(xy 93.336557 -102.804291) (xy 93.324431 -102.749854) (xy 93.32036 -102.694232) (xy 86.675722 -102.694232)
			(xy 86.028276 -103.341678) (xy 94.72625 -103.341678) (xy 94.730321 -103.286056) (xy 94.742447 -103.231619)
			(xy 94.76237 -103.179528) (xy 94.789666 -103.130893) (xy 94.823752 -103.08675) (xy 94.863901 -103.048041)
			(xy 94.909259 -103.01559) (xy 94.958859 -102.990089) (xy 95.011643 -102.972082) (xy 95.066486 -102.961952)
			(xy 95.12222 -102.959915) (xy 95.177657 -102.966015) (xy 95.231614 -102.980121) (xy 95.282943 -103.001933)
			(xy 95.330549 -103.030987) (xy 95.373417 -103.066662) (xy 95.410634 -103.108199) (xy 95.441407 -103.154712)
			(xy 95.465079 -103.205209) (xy 95.481147 -103.258616) (xy 95.489267 -103.313792) (xy 95.489776 -103.341678)
			(xy 95.489267 -103.369564) (xy 95.481147 -103.42474) (xy 95.465079 -103.478147) (xy 95.441407 -103.528644)
			(xy 95.410634 -103.575157) (xy 95.373417 -103.616694) (xy 95.330549 -103.652369) (xy 95.282943 -103.681423)
			(xy 95.231614 -103.703235) (xy 95.177657 -103.717341) (xy 95.12222 -103.723441) (xy 95.066486 -103.721404)
			(xy 95.011643 -103.711274) (xy 94.958859 -103.693267) (xy 94.909259 -103.667766) (xy 94.863901 -103.635315)
			(xy 94.823752 -103.596606) (xy 94.789666 -103.552463) (xy 94.76237 -103.503828) (xy 94.742447 -103.451737)
			(xy 94.730321 -103.3973) (xy 94.72625 -103.341678) (xy 86.028276 -103.341678) (xy 85.201506 -104.168448)
			(xy 96.295208 -104.168448) (xy 96.299279 -104.112826) (xy 96.311405 -104.058389) (xy 96.331328 -104.006298)
			(xy 96.358624 -103.957663) (xy 96.39271 -103.91352) (xy 96.432859 -103.874811) (xy 96.478217 -103.84236)
			(xy 96.527817 -103.816859) (xy 96.580601 -103.798852) (xy 96.635444 -103.788722) (xy 96.691178 -103.786685)
			(xy 96.746615 -103.792785) (xy 96.800572 -103.806891) (xy 96.851901 -103.828703) (xy 96.899507 -103.857757)
			(xy 96.942375 -103.893432) (xy 96.979592 -103.934969) (xy 97.010365 -103.981482) (xy 97.034037 -104.031979)
			(xy 97.050105 -104.085386) (xy 97.058225 -104.140562) (xy 97.058734 -104.168448) (xy 97.058225 -104.196334)
			(xy 97.050105 -104.25151) (xy 97.034037 -104.304917) (xy 97.010365 -104.355414) (xy 96.979592 -104.401927)
			(xy 96.942375 -104.443464) (xy 96.899507 -104.479139) (xy 96.851901 -104.508193) (xy 96.800572 -104.530005)
			(xy 96.746615 -104.544111) (xy 96.691178 -104.550211) (xy 96.635444 -104.548174) (xy 96.580601 -104.538044)
			(xy 96.527817 -104.520037) (xy 96.478217 -104.494536) (xy 96.432859 -104.462085) (xy 96.39271 -104.423376)
			(xy 96.358624 -104.379233) (xy 96.331328 -104.330598) (xy 96.311405 -104.278507) (xy 96.299279 -104.22407)
			(xy 96.295208 -104.168448) (xy 85.201506 -104.168448) (xy 85.111844 -104.25811) (xy 85.111844 -108.909866)
			(xy 86.877404 -108.909866) (xy 86.881424 -108.719215) (xy 86.893478 -108.528902) (xy 86.913544 -108.339267)
			(xy 86.941587 -108.150646) (xy 86.977556 -107.963376) (xy 87.021388 -107.777788) (xy 87.073005 -107.594213)
			(xy 87.132315 -107.412977) (xy 87.199213 -107.234402) (xy 87.273579 -107.058807) (xy 87.355281 -106.886502)
			(xy 87.444175 -106.717795) (xy 87.540101 -106.552985) (xy 87.64289 -106.392366) (xy 87.752359 -106.236223)
			(xy 87.868313 -106.084834) (xy 87.990547 -105.938467) (xy 88.118841 -105.797383) (xy 88.252969 -105.661834)
			(xy 88.392693 -105.532059) (xy 88.537763 -105.408289) (xy 88.687921 -105.290746) (xy 88.842902 -105.179637)
			(xy 89.002429 -105.07516) (xy 89.166218 -104.977501) (xy 89.333978 -104.886834) (xy 89.505412 -104.80332)
			(xy 89.680214 -104.727107) (xy 89.858073 -104.658331) (xy 90.038674 -104.597113) (xy 90.221694 -104.543564)
			(xy 90.40681 -104.497778) (xy 90.593691 -104.459836) (xy 90.782006 -104.429807) (xy 90.971419 -104.407742)
			(xy 91.161593 -104.393683) (xy 91.352192 -104.387653) (xy 91.542875 -104.389663) (xy 91.733304 -104.39971)
			(xy 91.92314 -104.417776) (xy 92.112046 -104.443829) (xy 92.299685 -104.477822) (xy 92.485725 -104.519695)
			(xy 92.669834 -104.569374) (xy 92.851685 -104.62677) (xy 93.030955 -104.691781) (xy 93.207325 -104.764292)
			(xy 93.380481 -104.844173) (xy 93.550116 -104.931283) (xy 93.715928 -105.025467) (xy 93.877622 -105.126558)
			(xy 94.03491 -105.234374) (xy 94.187513 -105.348726) (xy 94.335161 -105.469409) (xy 94.477589 -105.59621)
			(xy 94.614545 -105.728901) (xy 94.745786 -105.867249) (xy 94.871078 -106.011006) (xy 94.990198 -106.159917)
			(xy 95.102934 -106.313718) (xy 95.209087 -106.472134) (xy 95.308467 -106.634885) (xy 95.400897 -106.80168)
			(xy 95.486214 -106.972224) (xy 95.564266 -107.146212) (xy 95.634913 -107.323337) (xy 95.698031 -107.503282)
			(xy 95.753507 -107.685728) (xy 95.801242 -107.870351) (xy 95.841152 -108.056821) (xy 95.873165 -108.244809)
			(xy 95.897225 -108.433979) (xy 95.913288 -108.623995) (xy 95.921327 -108.814519) (xy 95.92183 -108.909866)
			(xy 95.921327 -109.005213) (xy 95.913288 -109.195737) (xy 95.897225 -109.385753) (xy 95.873165 -109.574923)
			(xy 95.841152 -109.762911) (xy 95.801242 -109.949381) (xy 95.753507 -110.134004) (xy 95.698031 -110.31645)
			(xy 95.634913 -110.496395) (xy 95.564266 -110.67352) (xy 95.486214 -110.847508) (xy 95.400897 -111.018052)
			(xy 95.308467 -111.184847) (xy 95.209087 -111.347598) (xy 95.102934 -111.506014) (xy 94.990198 -111.659815)
			(xy 94.871078 -111.808726) (xy 94.745786 -111.952483) (xy 94.614545 -112.090831) (xy 94.477589 -112.223522)
			(xy 94.335161 -112.350323) (xy 94.187513 -112.471006) (xy 94.03491 -112.585358) (xy 93.877622 -112.693174)
			(xy 93.715928 -112.794265) (xy 93.550116 -112.888449) (xy 93.380481 -112.975559) (xy 93.207325 -113.05544)
			(xy 93.030955 -113.127951) (xy 92.851685 -113.192962) (xy 92.669834 -113.250358) (xy 92.485725 -113.300037)
			(xy 92.299685 -113.34191) (xy 92.112046 -113.375903) (xy 91.92314 -113.401956) (xy 91.733304 -113.420022)
			(xy 91.542875 -113.430069) (xy 91.352192 -113.432079) (xy 91.161593 -113.426049) (xy 90.971419 -113.41199)
			(xy 90.782006 -113.389925) (xy 90.593691 -113.359896) (xy 90.40681 -113.321954) (xy 90.221694 -113.276168)
			(xy 90.038674 -113.222619) (xy 89.858073 -113.161401) (xy 89.680214 -113.092625) (xy 89.505412 -113.016412)
			(xy 89.333978 -112.932898) (xy 89.166218 -112.842231) (xy 89.002429 -112.744572) (xy 88.842902 -112.640095)
			(xy 88.687921 -112.528986) (xy 88.537763 -112.411443) (xy 88.392693 -112.287673) (xy 88.252969 -112.157898)
			(xy 88.118841 -112.022349) (xy 87.990547 -111.881265) (xy 87.868313 -111.734898) (xy 87.752359 -111.583509)
			(xy 87.64289 -111.427366) (xy 87.540101 -111.266747) (xy 87.444175 -111.101937) (xy 87.355281 -110.93323)
			(xy 87.273579 -110.760925) (xy 87.199213 -110.58533) (xy 87.132315 -110.406755) (xy 87.073005 -110.225519)
			(xy 87.021388 -110.041944) (xy 86.977556 -109.856356) (xy 86.941587 -109.669086) (xy 86.913544 -109.480465)
			(xy 86.893478 -109.29083) (xy 86.881424 -109.100517) (xy 86.877404 -108.909866) (xy 85.111844 -108.909866)
			(xy 85.111844 -113.743232) (xy 85.812376 -114.443764) (xy 85.812376 -137.355834) (xy 85.092286 -138.075924)
			(xy 85.081422 -138.087348) (xy 85.065177 -138.114352) (xy 85.056094 -138.14453) (xy 85.054948 -138.160252)
			(xy 85.054948 -138.72591) (xy 85.056093 -138.747615) (xy 85.064863 -138.790183) (xy 85.080743 -138.83064)
			(xy 85.10327 -138.867807) (xy 85.13179 -138.900603) (xy 85.165471 -138.928072) (xy 85.203332 -138.949413)
			(xy 85.24427 -138.964007) (xy 85.287094 -138.971426) (xy 85.330556 -138.971456) (xy 85.37339 -138.964096)
			(xy 85.394038 -138.957304) (xy 85.429325 -138.944807) (xy 85.501897 -138.926431) (xy 85.575997 -138.915773)
			(xy 85.650806 -138.912953) (xy 85.725498 -138.918) (xy 85.799248 -138.930859) (xy 85.87124 -138.951389)
			(xy 85.94068 -138.979362) (xy 86.0068 -139.014469) (xy 86.06887 -139.056322) (xy 86.126204 -139.104459)
			(xy 86.178168 -139.158349) (xy 86.224189 -139.217395) (xy 86.263758 -139.280946) (xy 86.280498 -139.314428)
			(xy 86.291632 -139.335126) (xy 86.320324 -139.372345) (xy 86.35537 -139.403655) (xy 86.395574 -139.427988)
			(xy 86.439567 -139.444515) (xy 86.485848 -139.452673) (xy 86.53284 -139.452182) (xy 86.578941 -139.443061)
			(xy 86.62258 -139.42562) (xy 86.662268 -139.400453) (xy 86.679786 -139.384786) (xy 86.75751 -139.307316)
			(xy 86.759288 -139.307316) (xy 86.775938 -139.306774) (xy 86.808105 -139.298159) (xy 86.836945 -139.281512)
			(xy 86.860495 -139.257967) (xy 86.877148 -139.229131) (xy 86.885771 -139.196966) (xy 86.886288 -139.180316)
			(xy 86.886288 -139.134088) (xy 86.827614 -139.06373) (xy 86.782148 -139.055348) (xy 86.745203 -139.048096)
			(xy 86.672979 -139.026814) (xy 86.603404 -138.998028) (xy 86.537256 -138.96206) (xy 86.475274 -138.919311)
			(xy 86.41815 -138.870259) (xy 86.366523 -138.815451) (xy 86.320968 -138.755501) (xy 86.281996 -138.691078)
			(xy 86.25004 -138.622901) (xy 86.225459 -138.551732) (xy 86.208527 -138.478366) (xy 86.199433 -138.403623)
			(xy 86.198278 -138.328337) (xy 86.205076 -138.25335) (xy 86.21975 -138.1795) (xy 86.242137 -138.10761)
			(xy 86.271986 -138.038486) (xy 86.308965 -137.972897) (xy 86.352659 -137.911578) (xy 86.402582 -137.855213)
			(xy 86.458174 -137.804432) (xy 86.518816 -137.759802) (xy 86.58383 -137.721822) (xy 86.652489 -137.690916)
			(xy 86.724026 -137.66743) (xy 86.797643 -137.651624) (xy 86.872517 -137.643677) (xy 86.947811 -137.643677)
			(xy 87.022685 -137.651624) (xy 87.096302 -137.66743) (xy 87.167839 -137.690916) (xy 87.236498 -137.721822)
			(xy 87.301512 -137.759802) (xy 87.362154 -137.804432) (xy 87.417746 -137.855213) (xy 87.467669 -137.911578)
			(xy 87.511363 -137.972897) (xy 87.548342 -138.038486) (xy 87.578191 -138.10761) (xy 87.600578 -138.1795)
			(xy 87.615252 -138.25335) (xy 87.62205 -138.328337) (xy 87.620895 -138.403623) (xy 87.611801 -138.478366)
			(xy 87.594869 -138.551732) (xy 87.570288 -138.622901) (xy 87.538332 -138.691078) (xy 87.49936 -138.755501)
			(xy 87.453805 -138.815451) (xy 87.402178 -138.870259) (xy 87.345054 -138.919311) (xy 87.283072 -138.96206)
			(xy 87.216924 -138.998028) (xy 87.147349 -139.026814) (xy 87.075125 -139.048096) (xy 87.03818 -139.055348)
			(xy 86.992714 -139.06373) (xy 86.93404 -139.134088) (xy 86.93404 -139.180316) (xy 86.934537 -139.196967)
			(xy 86.943161 -139.229134) (xy 86.959818 -139.257972) (xy 86.983372 -139.281516) (xy 87.012218 -139.29816)
			(xy 87.044388 -139.306771) (xy 87.06104 -139.307316) (xy 87.469218 -139.307316) (xy 87.485312 -139.306842)
			(xy 87.516475 -139.298781) (xy 87.544627 -139.283175) (xy 87.567977 -139.26102) (xy 87.576914 -139.247626)
			(xy 87.5977 -139.215378) (xy 87.645165 -139.155097) (xy 87.698839 -139.10027) (xy 87.758099 -139.051536)
			(xy 87.822257 -139.009459) (xy 87.89057 -138.974528) (xy 87.962244 -138.947148) (xy 88.036447 -138.927636)
			(xy 88.112318 -138.91622) (xy 88.188978 -138.913032) (xy 88.265535 -138.918109) (xy 88.341102 -138.931391)
			(xy 88.414802 -138.952725) (xy 88.485779 -138.981864) (xy 88.55321 -139.018468) (xy 88.616312 -139.062113)
			(xy 88.674353 -139.112294) (xy 88.726659 -139.168426) (xy 88.772624 -139.22986) (xy 88.811713 -139.295881)
			(xy 88.843474 -139.365724) (xy 88.867537 -139.438578) (xy 88.876124 -139.475972) (xy 88.883998 -139.512548)
			(xy 88.904826 -139.53363) (xy 88.916987 -139.545043) (xy 88.94584 -139.561742) (xy 88.978031 -139.570413)
			(xy 89.011368 -139.570466) (xy 89.043585 -139.561897) (xy 89.072492 -139.545289) (xy 89.084658 -139.533884)
			(xy 89.124536 -139.494006) (xy 89.124536 -139.06119) (xy 89.124045 -139.045283) (xy 89.116174 -139.014457)
			(xy 89.100925 -138.986535) (xy 89.079244 -138.963252) (xy 89.066116 -138.954256) (xy 89.034918 -138.933695)
			(xy 88.976581 -138.887005) (xy 88.923456 -138.83446) (xy 88.876129 -138.776638) (xy 88.83512 -138.714175)
			(xy 88.800881 -138.64776) (xy 88.773789 -138.578123) (xy 88.754142 -138.506031) (xy 88.742156 -138.432278)
			(xy 88.737964 -138.357674) (xy 88.741611 -138.283042) (xy 88.753057 -138.209203) (xy 88.772176 -138.136969)
			(xy 88.798758 -138.067136) (xy 88.83251 -138.000472) (xy 88.873061 -137.937712) (xy 88.919964 -137.879545)
			(xy 88.972704 -137.826613) (xy 89.030698 -137.779497) (xy 89.09331 -137.738717) (xy 89.15985 -137.704721)
			(xy 89.229585 -137.677884) (xy 89.301749 -137.658501) (xy 89.375546 -137.646785) (xy 89.450164 -137.642865)
			(xy 89.524782 -137.646785) (xy 89.598579 -137.658501) (xy 89.670743 -137.677884) (xy 89.740478 -137.704721)
			(xy 89.807018 -137.738717) (xy 89.86963 -137.779497) (xy 89.927624 -137.826613) (xy 89.980364 -137.879545)
			(xy 90.027267 -137.937712) (xy 90.067818 -138.000472) (xy 90.10157 -138.067136) (xy 90.128152 -138.136969)
			(xy 90.147271 -138.209203) (xy 90.158717 -138.283042) (xy 90.162237 -138.35507) (xy 91.277951 -138.35507)
			(xy 91.281986 -138.279366) (xy 91.294045 -138.204521) (xy 91.313991 -138.13138) (xy 91.341598 -138.060775)
			(xy 91.376554 -137.993504) (xy 91.418462 -137.930329) (xy 91.466848 -137.871967) (xy 91.521164 -137.819079)
			(xy 91.580793 -137.772264) (xy 91.645061 -137.732052) (xy 91.713238 -137.6989) (xy 91.784554 -137.673182)
			(xy 91.858199 -137.65519) (xy 91.933339 -137.645128) (xy 92.009123 -137.643109) (xy 92.084693 -137.649158)
			(xy 92.159191 -137.663205) (xy 92.231774 -137.685091) (xy 92.30162 -137.714568) (xy 92.367937 -137.751303)
			(xy 92.429973 -137.794878) (xy 92.487026 -137.8448) (xy 92.53845 -137.900504) (xy 92.583661 -137.961359)
			(xy 92.622148 -138.026674) (xy 92.653474 -138.09571) (xy 92.677284 -138.167685) (xy 92.693309 -138.241783)
			(xy 92.701368 -138.317164) (xy 92.701872 -138.35507) (xy 92.701368 -138.392976) (xy 92.693309 -138.468357)
			(xy 92.677284 -138.542455) (xy 92.653474 -138.61443) (xy 92.622148 -138.683466) (xy 92.583661 -138.748781)
			(xy 92.53845 -138.809636) (xy 92.487026 -138.86534) (xy 92.429973 -138.915262) (xy 92.367937 -138.958837)
			(xy 92.30162 -138.995572) (xy 92.231774 -139.025049) (xy 92.159191 -139.046935) (xy 92.084693 -139.060982)
			(xy 92.009123 -139.067031) (xy 91.933339 -139.065012) (xy 91.858199 -139.05495) (xy 91.784554 -139.036958)
			(xy 91.713238 -139.01124) (xy 91.645061 -138.978088) (xy 91.580793 -138.937876) (xy 91.521164 -138.891061)
			(xy 91.466848 -138.838173) (xy 91.418462 -138.779811) (xy 91.376554 -138.716636) (xy 91.341598 -138.649365)
			(xy 91.313991 -138.57876) (xy 91.294045 -138.505619) (xy 91.281986 -138.430774) (xy 91.277951 -138.35507)
			(xy 90.162237 -138.35507) (xy 90.162364 -138.357674) (xy 90.158172 -138.432278) (xy 90.146186 -138.506031)
			(xy 90.126539 -138.578123) (xy 90.099447 -138.64776) (xy 90.065208 -138.714175) (xy 90.024199 -138.776638)
			(xy 89.976872 -138.83446) (xy 89.923747 -138.887005) (xy 89.86541 -138.933695) (xy 89.834212 -138.954256)
			(xy 89.821084 -138.963256) (xy 89.799387 -138.986528) (xy 89.784132 -139.01445) (xy 89.776271 -139.045281)
			(xy 89.775792 -139.06119) (xy 89.775792 -139.473432) (xy 89.776339 -139.490078) (xy 89.784962 -139.522234)
			(xy 89.801612 -139.551063) (xy 89.825156 -139.574602) (xy 89.853988 -139.591247) (xy 89.886146 -139.599864)
			(xy 89.902792 -139.600432) (xy 89.9414 -139.600432) (xy 90.011758 -139.541758) (xy 90.02014 -139.496546)
			(xy 90.027454 -139.45954) (xy 90.048879 -139.387209) (xy 90.077833 -139.31755) (xy 90.113992 -139.251343)
			(xy 90.15695 -139.189331) (xy 90.206225 -139.132211) (xy 90.261264 -139.080621) (xy 90.32145 -139.035142)
			(xy 90.386109 -138.996282) (xy 90.454514 -138.964478) (xy 90.525899 -138.940087) (xy 90.599464 -138.923382)
			(xy 90.674382 -138.91455) (xy 90.749815 -138.913691) (xy 90.824915 -138.920814) (xy 90.898841 -138.935839)
			(xy 90.970763 -138.958598) (xy 91.039875 -138.988836) (xy 91.105402 -139.026212) (xy 91.166609 -139.070309)
			(xy 91.222809 -139.120632) (xy 91.273372 -139.176616) (xy 91.317731 -139.237633) (xy 91.355388 -139.302999)
			(xy 91.385921 -139.37198) (xy 91.408989 -139.443805) (xy 91.424331 -139.517665) (xy 91.431775 -139.592734)
			(xy 91.43124 -139.66817) (xy 91.422729 -139.743125) (xy 91.40634 -139.816761) (xy 91.382255 -139.88825)
			(xy 91.350745 -139.956791) (xy 91.312163 -140.021616) (xy 91.266941 -140.081997) (xy 91.215588 -140.137256)
			(xy 91.158679 -140.186776) (xy 91.096852 -140.229999) (xy 91.030801 -140.266441) (xy 90.961267 -140.295694)
			(xy 90.889028 -140.317429) (xy 90.814896 -140.331402) (xy 90.739703 -140.337458) (xy 90.66429 -140.335527)
			(xy 90.589504 -140.325632) (xy 90.516185 -140.307884) (xy 90.445153 -140.282481) (xy 90.377206 -140.249709)
			(xy 90.313106 -140.209935) (xy 90.253572 -140.163605) (xy 90.199271 -140.111239) (xy 90.150813 -140.053424)
			(xy 90.10874 -139.990809) (xy 90.073526 -139.924095) (xy 90.045564 -139.854031) (xy 90.034872 -139.817856)
			(xy 90.030141 -139.802778) (xy 90.014383 -139.775397) (xy 89.992376 -139.752731) (xy 89.965473 -139.736171)
			(xy 89.950544 -139.730988) (xy 89.84488 -139.697968) (xy 89.776046 -139.714986) (xy 89.775792 -139.71524)
			(xy 89.775792 -139.763754) (xy 89.647014 -139.892278) (xy 89.635568 -139.912394) (xy 89.619379 -139.955748)
			(xy 89.611303 -140.001316) (xy 89.611605 -140.047592) (xy 89.620275 -140.093051) (xy 89.637027 -140.13619)
			(xy 89.661308 -140.175586) (xy 89.692317 -140.209938) (xy 89.72903 -140.238113) (xy 89.749376 -140.249148)
			(xy 89.782565 -140.265026) (xy 89.845786 -140.302667) (xy 89.904786 -140.34663) (xy 89.958935 -140.396445)
			(xy 90.007657 -140.451581) (xy 90.05043 -140.511449) (xy 90.086798 -140.57541) (xy 90.116373 -140.642783)
			(xy 90.13884 -140.712847) (xy 90.153958 -140.784854) (xy 90.161567 -140.858038) (xy 90.161576 -140.89507)
			(xy 91.277951 -140.89507) (xy 91.281986 -140.819366) (xy 91.294045 -140.744521) (xy 91.313991 -140.67138)
			(xy 91.341598 -140.600775) (xy 91.376554 -140.533504) (xy 91.418462 -140.470329) (xy 91.466848 -140.411967)
			(xy 91.521164 -140.359079) (xy 91.580793 -140.312264) (xy 91.645061 -140.272052) (xy 91.713238 -140.2389)
			(xy 91.784554 -140.213182) (xy 91.858199 -140.19519) (xy 91.933339 -140.185128) (xy 92.009123 -140.183109)
			(xy 92.084693 -140.189158) (xy 92.159191 -140.203205) (xy 92.231774 -140.225091) (xy 92.30162 -140.254568)
			(xy 92.367937 -140.291303) (xy 92.429973 -140.334878) (xy 92.487026 -140.3848) (xy 92.53845 -140.440504)
			(xy 92.583661 -140.501359) (xy 92.622148 -140.566674) (xy 92.653474 -140.63571) (xy 92.677284 -140.707685)
			(xy 92.693309 -140.781783) (xy 92.701368 -140.857164) (xy 92.701872 -140.89507) (xy 92.701368 -140.932976)
			(xy 92.693309 -141.008357) (xy 92.677284 -141.082455) (xy 92.653474 -141.15443) (xy 92.622148 -141.223466)
			(xy 92.583661 -141.288781) (xy 92.53845 -141.349636) (xy 92.487026 -141.40534) (xy 92.429973 -141.455262)
			(xy 92.367937 -141.498837) (xy 92.30162 -141.535572) (xy 92.231774 -141.565049) (xy 92.159191 -141.586935)
			(xy 92.084693 -141.600982) (xy 92.009123 -141.607031) (xy 91.933339 -141.605012) (xy 91.858199 -141.59495)
			(xy 91.784554 -141.576958) (xy 91.713238 -141.55124) (xy 91.645061 -141.518088) (xy 91.580793 -141.477876)
			(xy 91.521164 -141.431061) (xy 91.466848 -141.378173) (xy 91.418462 -141.319811) (xy 91.376554 -141.256636)
			(xy 91.341598 -141.189365) (xy 91.313991 -141.11876) (xy 91.294045 -141.045619) (xy 91.281986 -140.970774)
			(xy 91.277951 -140.89507) (xy 90.161576 -140.89507) (xy 90.161585 -140.931616) (xy 90.154012 -141.004803)
			(xy 90.138928 -141.076818) (xy 90.116496 -141.146893) (xy 90.086953 -141.21428) (xy 90.050616 -141.278259)
			(xy 90.007872 -141.338148) (xy 89.983818 -141.365986) (xy 89.960875 -141.391371) (xy 89.910884 -141.438098)
			(xy 89.856643 -141.479816) (xy 89.827862 -141.49832) (xy 89.814467 -141.507252) (xy 89.792318 -141.530606)
			(xy 89.776721 -141.55876) (xy 89.768668 -141.589923) (xy 89.768172 -141.606016) (xy 89.768172 -141.670532)
			(xy 89.380822 -142.057882) (xy 89.369961 -142.069307) (xy 89.353724 -142.096312) (xy 89.344652 -142.12649)
			(xy 89.343484 -142.14221) (xy 89.343484 -142.16507) (xy 90.007951 -142.16507) (xy 90.011986 -142.089366)
			(xy 90.024045 -142.014521) (xy 90.043991 -141.94138) (xy 90.071598 -141.870775) (xy 90.106554 -141.803504)
			(xy 90.148462 -141.740329) (xy 90.196848 -141.681967) (xy 90.251164 -141.629079) (xy 90.310793 -141.582264)
			(xy 90.375061 -141.542052) (xy 90.443238 -141.5089) (xy 90.514554 -141.483182) (xy 90.588199 -141.46519)
			(xy 90.663339 -141.455128) (xy 90.739123 -141.453109) (xy 90.814693 -141.459158) (xy 90.889191 -141.473205)
			(xy 90.961774 -141.495091) (xy 91.03162 -141.524568) (xy 91.097937 -141.561303) (xy 91.159973 -141.604878)
			(xy 91.165918 -141.61008) (xy 93.15476 -141.61008) (xy 93.158776 -141.49381) (xy 93.170803 -141.378095)
			(xy 93.190785 -141.263485) (xy 93.218627 -141.150526) (xy 93.254196 -141.039758) (xy 93.297322 -140.931707)
			(xy 93.347799 -140.826889) (xy 93.405388 -140.725804) (xy 93.469814 -140.628932) (xy 93.540769 -140.536736)
			(xy 93.617916 -140.449655) (xy 93.700887 -140.368104) (xy 93.789287 -140.292472) (xy 93.882694 -140.223118)
			(xy 93.980663 -140.160375) (xy 94.082727 -140.104539) (xy 94.188401 -140.055878) (xy 94.29718 -140.014624)
			(xy 94.408545 -139.980973) (xy 94.521968 -139.955085) (xy 94.636905 -139.937084) (xy 94.752811 -139.927055)
			(xy 94.869133 -139.925047) (xy 94.985316 -139.931069) (xy 95.100807 -139.945092) (xy 95.215055 -139.96705)
			(xy 95.327516 -139.996837) (xy 95.437654 -140.034312) (xy 95.544944 -140.079297) (xy 95.648875 -140.131576)
			(xy 95.748951 -140.190901) (xy 95.844697 -140.256989) (xy 95.935654 -140.329525) (xy 96.02139 -140.408164)
			(xy 96.101497 -140.49253) (xy 96.175593 -140.582222) (xy 96.243323 -140.676812) (xy 96.304367 -140.77585)
			(xy 96.358432 -140.878863) (xy 96.405262 -140.98536) (xy 96.444633 -141.094835) (xy 96.476357 -141.206765)
			(xy 96.500283 -141.320617) (xy 96.516297 -141.435849) (xy 96.524324 -141.551911) (xy 96.524826 -141.61008)
			(xy 96.524324 -141.668249) (xy 96.516297 -141.784311) (xy 96.500283 -141.899543) (xy 96.476357 -142.013395)
			(xy 96.444633 -142.125325) (xy 96.405262 -142.2348) (xy 96.358432 -142.341297) (xy 96.304367 -142.44431)
			(xy 96.243323 -142.543348) (xy 96.175593 -142.637938) (xy 96.101497 -142.72763) (xy 96.02139 -142.811996)
			(xy 95.935654 -142.890635) (xy 95.844697 -142.963171) (xy 95.748951 -143.029259) (xy 95.648875 -143.088584)
			(xy 95.544944 -143.140863) (xy 95.437654 -143.185848) (xy 95.327516 -143.223323) (xy 95.215055 -143.25311)
			(xy 95.100807 -143.275068) (xy 94.985316 -143.289091) (xy 94.869133 -143.295113) (xy 94.752811 -143.293105)
			(xy 94.636905 -143.283076) (xy 94.521968 -143.265075) (xy 94.408545 -143.239187) (xy 94.29718 -143.205536)
			(xy 94.188401 -143.164282) (xy 94.082727 -143.115621) (xy 93.980663 -143.059785) (xy 93.882694 -142.997042)
			(xy 93.789287 -142.927688) (xy 93.700887 -142.852056) (xy 93.617916 -142.770505) (xy 93.540769 -142.683424)
			(xy 93.469814 -142.591228) (xy 93.405388 -142.494356) (xy 93.347799 -142.393271) (xy 93.297322 -142.288453)
			(xy 93.254196 -142.180402) (xy 93.218627 -142.069634) (xy 93.190785 -141.956675) (xy 93.170803 -141.842065)
			(xy 93.158776 -141.72635) (xy 93.15476 -141.61008) (xy 91.165918 -141.61008) (xy 91.217026 -141.6548)
			(xy 91.26845 -141.710504) (xy 91.313661 -141.771359) (xy 91.352148 -141.836674) (xy 91.383474 -141.90571)
			(xy 91.407284 -141.977685) (xy 91.423309 -142.051783) (xy 91.431368 -142.127164) (xy 91.431872 -142.16507)
			(xy 91.431368 -142.202976) (xy 91.423309 -142.278357) (xy 91.407284 -142.352455) (xy 91.383474 -142.42443)
			(xy 91.352148 -142.493466) (xy 91.313661 -142.558781) (xy 91.26845 -142.619636) (xy 91.217026 -142.67534)
			(xy 91.159973 -142.725262) (xy 91.097937 -142.768837) (xy 91.03162 -142.805572) (xy 90.961774 -142.835049)
			(xy 90.889191 -142.856935) (xy 90.814693 -142.870982) (xy 90.739123 -142.877031) (xy 90.663339 -142.875012)
			(xy 90.588199 -142.86495) (xy 90.514554 -142.846958) (xy 90.443238 -142.82124) (xy 90.375061 -142.788088)
			(xy 90.310793 -142.747876) (xy 90.251164 -142.701061) (xy 90.196848 -142.648173) (xy 90.148462 -142.589811)
			(xy 90.106554 -142.526636) (xy 90.071598 -142.459365) (xy 90.043991 -142.38876) (xy 90.024045 -142.315619)
			(xy 90.011986 -142.240774) (xy 90.007951 -142.16507) (xy 89.343484 -142.16507) (xy 89.343484 -142.546832)
			(xy 85.741002 -146.149568) (xy 85.725047 -146.16625) (xy 85.698853 -146.204253) (xy 85.679948 -146.24636)
			(xy 85.668953 -146.291188) (xy 85.666228 -146.337263) (xy 85.671863 -146.383074) (xy 85.685673 -146.427115)
			(xy 85.707205 -146.467942) (xy 85.735751 -146.504211) (xy 85.752686 -146.5199) (xy 85.772744 -146.538177)
			(xy 85.808001 -146.579425) (xy 85.837059 -146.625253) (xy 85.85933 -146.674735) (xy 85.874367 -146.726873)
			(xy 85.881865 -146.780616) (xy 85.881673 -146.834879) (xy 85.873795 -146.888567) (xy 85.85839 -146.940598)
			(xy 85.835769 -146.989921) (xy 85.806388 -147.035542) (xy 85.77084 -147.07654) (xy 85.729842 -147.112088)
			(xy 85.684221 -147.141469) (xy 85.634898 -147.16409) (xy 85.582867 -147.179495) (xy 85.529178 -147.187373)
			(xy 85.474915 -147.187565) (xy 85.421173 -147.180067) (xy 85.369034 -147.16503) (xy 85.319552 -147.142758)
			(xy 85.273725 -147.113701) (xy 85.232476 -147.078443) (xy 85.214206 -147.05838) (xy 85.198579 -147.041377)
			(xy 85.162319 -147.012786) (xy 85.121487 -146.991221) (xy 85.07743 -146.977393) (xy 85.031599 -146.971757)
			(xy 84.985504 -146.9745) (xy 84.940665 -146.985532) (xy 84.898559 -147.004487) (xy 84.860573 -147.030742)
			(xy 84.843874 -147.046696) (xy 84.538566 -147.352004) (xy 86.714582 -147.352004) (xy 86.718653 -147.296382)
			(xy 86.730779 -147.241945) (xy 86.750702 -147.189854) (xy 86.777998 -147.141219) (xy 86.812084 -147.097076)
			(xy 86.852233 -147.058367) (xy 86.897591 -147.025916) (xy 86.947191 -147.000415) (xy 86.999975 -146.982408)
			(xy 87.054818 -146.972278) (xy 87.110552 -146.970241) (xy 87.165989 -146.976341) (xy 87.219946 -146.990447)
			(xy 87.271275 -147.012259) (xy 87.318881 -147.041313) (xy 87.361749 -147.076988) (xy 87.398966 -147.118525)
			(xy 87.429739 -147.165038) (xy 87.453411 -147.215535) (xy 87.469479 -147.268942) (xy 87.477599 -147.324118)
			(xy 87.478108 -147.352004) (xy 87.477599 -147.37989) (xy 87.469479 -147.435066) (xy 87.453411 -147.488473)
			(xy 87.429739 -147.53897) (xy 87.398966 -147.585483) (xy 87.361749 -147.62702) (xy 87.318881 -147.662695)
			(xy 87.271275 -147.691749) (xy 87.219946 -147.713561) (xy 87.165989 -147.727667) (xy 87.110552 -147.733767)
			(xy 87.054818 -147.73173) (xy 86.999975 -147.7216) (xy 86.947191 -147.703593) (xy 86.897591 -147.678092)
			(xy 86.852233 -147.645641) (xy 86.812084 -147.606932) (xy 86.777998 -147.562789) (xy 86.750702 -147.514154)
			(xy 86.730779 -147.462063) (xy 86.718653 -147.407626) (xy 86.714582 -147.352004) (xy 84.538566 -147.352004)
			(xy 83.999578 -147.890992) (xy 83.98438 -147.906848) (xy 83.959128 -147.942779) (xy 83.94043 -147.982517)
			(xy 83.928842 -148.024877) (xy 83.924709 -148.068599) (xy 83.928154 -148.112381) (xy 83.939075 -148.154918)
			(xy 83.957146 -148.194945) (xy 83.981829 -148.231269) (xy 83.996784 -148.247354) (xy 84.015782 -148.266942)
			(xy 84.048554 -148.310572) (xy 84.074775 -148.358426) (xy 84.09391 -148.409528) (xy 84.10557 -148.462835)
			(xy 84.109516 -148.517259) (xy 84.105667 -148.571691) (xy 84.094103 -148.625018) (xy 84.075058 -148.676154)
			(xy 84.048922 -148.724055) (xy 84.016229 -148.767744) (xy 83.977644 -148.806329) (xy 83.933955 -148.839022)
			(xy 83.886054 -148.865158) (xy 83.834918 -148.884203) (xy 83.781591 -148.895767) (xy 83.727159 -148.899616)
			(xy 83.672735 -148.89567) (xy 83.619428 -148.88401) (xy 83.568326 -148.864875) (xy 83.520472 -148.838654)
			(xy 83.476842 -148.805882) (xy 83.457288 -148.78685) (xy 83.441198 -148.771897) (xy 83.404876 -148.747203)
			(xy 83.364849 -148.729122) (xy 83.322309 -148.718194) (xy 83.278523 -148.714743) (xy 83.234797 -148.718874)
			(xy 83.192432 -148.730461) (xy 83.15269 -148.749162) (xy 83.116757 -148.774418) (xy 83.100926 -148.789644)
			(xy 82.98815 -148.90242) (xy 85.31428 -148.90242) (xy 85.318351 -148.846798) (xy 85.330477 -148.792361)
			(xy 85.3504 -148.74027) (xy 85.377696 -148.691635) (xy 85.411782 -148.647492) (xy 85.451931 -148.608783)
			(xy 85.497289 -148.576332) (xy 85.546889 -148.550831) (xy 85.599673 -148.532824) (xy 85.654516 -148.522694)
			(xy 85.71025 -148.520657) (xy 85.765687 -148.526757) (xy 85.819644 -148.540863) (xy 85.870973 -148.562675)
			(xy 85.918579 -148.591729) (xy 85.961447 -148.627404) (xy 85.998664 -148.668941) (xy 86.029437 -148.715454)
			(xy 86.053109 -148.765951) (xy 86.069177 -148.819358) (xy 86.077297 -148.874534) (xy 86.077806 -148.90242)
			(xy 86.077297 -148.930306) (xy 86.069177 -148.985482) (xy 86.053109 -149.038889) (xy 86.029437 -149.089386)
			(xy 85.998664 -149.135899) (xy 85.961447 -149.177436) (xy 85.918579 -149.213111) (xy 85.870973 -149.242165)
			(xy 85.819644 -149.263977) (xy 85.765687 -149.278083) (xy 85.71025 -149.284183) (xy 85.654516 -149.282146)
			(xy 85.599673 -149.272016) (xy 85.546889 -149.254009) (xy 85.497289 -149.228508) (xy 85.451931 -149.196057)
			(xy 85.411782 -149.157348) (xy 85.377696 -149.113205) (xy 85.3504 -149.06457) (xy 85.330477 -149.012479)
			(xy 85.318351 -148.958042) (xy 85.31428 -148.90242) (xy 82.98815 -148.90242) (xy 82.587846 -149.302724)
			(xy 82.576978 -149.314146) (xy 82.560725 -149.341149) (xy 82.551638 -149.371328) (xy 82.550508 -149.387052)
			(xy 82.550508 -149.43201) (xy 82.56651 -149.460712) (xy 82.579427 -149.485052) (xy 82.598893 -149.536602)
			(xy 82.610739 -149.590415) (xy 82.614718 -149.645374) (xy 82.610747 -149.700333) (xy 82.598908 -149.754148)
			(xy 82.579449 -149.8057) (xy 82.576237 -149.81174) (xy 83.9122 -149.81174) (xy 83.916271 -149.756118)
			(xy 83.928397 -149.701681) (xy 83.94832 -149.64959) (xy 83.975616 -149.600955) (xy 84.009702 -149.556812)
			(xy 84.049851 -149.518103) (xy 84.095209 -149.485652) (xy 84.144809 -149.460151) (xy 84.197593 -149.442144)
			(xy 84.252436 -149.432014) (xy 84.30817 -149.429977) (xy 84.363607 -149.436077) (xy 84.417564 -149.450183)
			(xy 84.468893 -149.471995) (xy 84.516499 -149.501049) (xy 84.559367 -149.536724) (xy 84.596584 -149.578261)
			(xy 84.627357 -149.624774) (xy 84.651029 -149.675271) (xy 84.667097 -149.728678) (xy 84.675217 -149.783854)
			(xy 84.675726 -149.81174) (xy 84.675217 -149.839626) (xy 84.667097 -149.894802) (xy 84.651029 -149.948209)
			(xy 84.627357 -149.998706) (xy 84.596584 -150.045219) (xy 84.559367 -150.086756) (xy 84.516499 -150.122431)
			(xy 84.468893 -150.151485) (xy 84.417564 -150.173297) (xy 84.363607 -150.187403) (xy 84.30817 -150.193503)
			(xy 84.252436 -150.191466) (xy 84.197593 -150.181336) (xy 84.144809 -150.163329) (xy 84.095209 -150.137828)
			(xy 84.049851 -150.105377) (xy 84.009702 -150.066668) (xy 83.975616 -150.022525) (xy 83.94832 -149.97389)
			(xy 83.928397 -149.921799) (xy 83.916271 -149.867362) (xy 83.9122 -149.81174) (xy 82.576237 -149.81174)
			(xy 82.56651 -149.830028) (xy 82.550508 -149.85873) (xy 82.550508 -151.212804) (xy 84.390482 -151.212804)
			(xy 84.394553 -151.157182) (xy 84.406679 -151.102745) (xy 84.426602 -151.050654) (xy 84.453898 -151.002019)
			(xy 84.487984 -150.957876) (xy 84.528133 -150.919167) (xy 84.573491 -150.886716) (xy 84.623091 -150.861215)
			(xy 84.675875 -150.843208) (xy 84.730718 -150.833078) (xy 84.786452 -150.831041) (xy 84.841889 -150.837141)
			(xy 84.895846 -150.851247) (xy 84.947175 -150.873059) (xy 84.994781 -150.902113) (xy 85.037649 -150.937788)
			(xy 85.074866 -150.979325) (xy 85.105639 -151.025838) (xy 85.129311 -151.076335) (xy 85.145379 -151.129742)
			(xy 85.153499 -151.184918) (xy 85.154008 -151.212804) (xy 85.153499 -151.24069) (xy 85.145379 -151.295866)
			(xy 85.129311 -151.349273) (xy 85.105639 -151.39977) (xy 85.074866 -151.446283) (xy 85.037649 -151.48782)
			(xy 84.994781 -151.523495) (xy 84.947175 -151.552549) (xy 84.895846 -151.574361) (xy 84.841889 -151.588467)
			(xy 84.786452 -151.594567) (xy 84.730718 -151.59253) (xy 84.675875 -151.5824) (xy 84.623091 -151.564393)
			(xy 84.573491 -151.538892) (xy 84.528133 -151.506441) (xy 84.487984 -151.467732) (xy 84.453898 -151.423589)
			(xy 84.426602 -151.374954) (xy 84.406679 -151.322863) (xy 84.394553 -151.268426) (xy 84.390482 -151.212804)
			(xy 82.550508 -151.212804) (xy 82.550508 -153.359866) (xy 86.877404 -153.359866) (xy 86.881424 -153.169215)
			(xy 86.893478 -152.978902) (xy 86.913544 -152.789267) (xy 86.941587 -152.600646) (xy 86.977556 -152.413376)
			(xy 87.021388 -152.227788) (xy 87.073005 -152.044213) (xy 87.132315 -151.862977) (xy 87.199213 -151.684402)
			(xy 87.273579 -151.508807) (xy 87.355281 -151.336502) (xy 87.444175 -151.167795) (xy 87.540101 -151.002985)
			(xy 87.64289 -150.842366) (xy 87.752359 -150.686223) (xy 87.868313 -150.534834) (xy 87.990547 -150.388467)
			(xy 88.118841 -150.247383) (xy 88.252969 -150.111834) (xy 88.392693 -149.982059) (xy 88.537763 -149.858289)
			(xy 88.687921 -149.740746) (xy 88.842902 -149.629637) (xy 89.002429 -149.52516) (xy 89.166218 -149.427501)
			(xy 89.333978 -149.336834) (xy 89.505412 -149.25332) (xy 89.680214 -149.177107) (xy 89.858073 -149.108331)
			(xy 90.038674 -149.047113) (xy 90.221694 -148.993564) (xy 90.40681 -148.947778) (xy 90.593691 -148.909836)
			(xy 90.782006 -148.879807) (xy 90.971419 -148.857742) (xy 91.161593 -148.843683) (xy 91.352192 -148.837653)
			(xy 91.542875 -148.839663) (xy 91.733304 -148.84971) (xy 91.92314 -148.867776) (xy 92.112046 -148.893829)
			(xy 92.299685 -148.927822) (xy 92.485725 -148.969695) (xy 92.669834 -149.019374) (xy 92.851685 -149.07677)
			(xy 93.030955 -149.141781) (xy 93.207325 -149.214292) (xy 93.380481 -149.294173) (xy 93.550116 -149.381283)
			(xy 93.715928 -149.475467) (xy 93.877622 -149.576558) (xy 94.03491 -149.684374) (xy 94.187513 -149.798726)
			(xy 94.335161 -149.919409) (xy 94.477589 -150.04621) (xy 94.614545 -150.178901) (xy 94.745786 -150.317249)
			(xy 94.871078 -150.461006) (xy 94.990198 -150.609917) (xy 95.102934 -150.763718) (xy 95.209087 -150.922134)
			(xy 95.308467 -151.084885) (xy 95.400897 -151.25168) (xy 95.486214 -151.422224) (xy 95.564266 -151.596212)
			(xy 95.634913 -151.773337) (xy 95.698031 -151.953282) (xy 95.753507 -152.135728) (xy 95.801242 -152.320351)
			(xy 95.841152 -152.506821) (xy 95.873165 -152.694809) (xy 95.897225 -152.883979) (xy 95.913288 -153.073995)
			(xy 95.921327 -153.264519) (xy 95.92183 -153.359866) (xy 95.921327 -153.455213) (xy 95.913288 -153.645737)
			(xy 95.897225 -153.835753) (xy 95.873165 -154.024923) (xy 95.841152 -154.212911) (xy 95.801242 -154.399381)
			(xy 95.753507 -154.584004) (xy 95.698031 -154.76645) (xy 95.634913 -154.946395) (xy 95.564266 -155.12352)
			(xy 95.486214 -155.297508) (xy 95.400897 -155.468052) (xy 95.308467 -155.634847) (xy 95.209087 -155.797598)
			(xy 95.102934 -155.956014) (xy 94.990198 -156.109815) (xy 94.871078 -156.258726) (xy 94.745786 -156.402483)
			(xy 94.614545 -156.540831) (xy 94.477589 -156.673522) (xy 94.335161 -156.800323) (xy 94.187513 -156.921006)
			(xy 94.03491 -157.035358) (xy 93.877622 -157.143174) (xy 93.715928 -157.244265) (xy 93.550116 -157.338449)
			(xy 93.380481 -157.425559) (xy 93.207325 -157.50544) (xy 93.030955 -157.577951) (xy 92.851685 -157.642962)
			(xy 92.669834 -157.700358) (xy 92.485725 -157.750037) (xy 92.299685 -157.79191) (xy 92.112046 -157.825903)
			(xy 91.92314 -157.851956) (xy 91.733304 -157.870022) (xy 91.542875 -157.880069) (xy 91.352192 -157.882079)
			(xy 91.161593 -157.876049) (xy 90.971419 -157.86199) (xy 90.782006 -157.839925) (xy 90.593691 -157.809896)
			(xy 90.40681 -157.771954) (xy 90.221694 -157.726168) (xy 90.038674 -157.672619) (xy 89.858073 -157.611401)
			(xy 89.680214 -157.542625) (xy 89.505412 -157.466412) (xy 89.333978 -157.382898) (xy 89.166218 -157.292231)
			(xy 89.002429 -157.194572) (xy 88.842902 -157.090095) (xy 88.687921 -156.978986) (xy 88.537763 -156.861443)
			(xy 88.392693 -156.737673) (xy 88.252969 -156.607898) (xy 88.118841 -156.472349) (xy 87.990547 -156.331265)
			(xy 87.868313 -156.184898) (xy 87.752359 -156.033509) (xy 87.64289 -155.877366) (xy 87.540101 -155.716747)
			(xy 87.444175 -155.551937) (xy 87.355281 -155.38323) (xy 87.273579 -155.210925) (xy 87.199213 -155.03533)
			(xy 87.132315 -154.856755) (xy 87.073005 -154.675519) (xy 87.021388 -154.491944) (xy 86.977556 -154.306356)
			(xy 86.941587 -154.119086) (xy 86.913544 -153.930465) (xy 86.893478 -153.74083) (xy 86.881424 -153.550517)
			(xy 86.877404 -153.359866) (xy 82.550508 -153.359866) (xy 82.550508 -158.1912) (xy 66.19494 -174.546768)
			(xy 68.225668 -174.546768) (xy 68.229739 -174.491146) (xy 68.241865 -174.436709) (xy 68.261788 -174.384618)
			(xy 68.289084 -174.335983) (xy 68.32317 -174.29184) (xy 68.363319 -174.253131) (xy 68.408677 -174.22068)
			(xy 68.458277 -174.195179) (xy 68.511061 -174.177172) (xy 68.565904 -174.167042) (xy 68.621638 -174.165005)
			(xy 68.677075 -174.171105) (xy 68.731032 -174.185211) (xy 68.782361 -174.207023) (xy 68.829967 -174.236077)
			(xy 68.872835 -174.271752) (xy 68.910052 -174.313289) (xy 68.940825 -174.359802) (xy 68.964497 -174.410299)
			(xy 68.980565 -174.463706) (xy 68.988685 -174.518882) (xy 68.989194 -174.546768) (xy 69.344538 -174.546768)
			(xy 69.348609 -174.491146) (xy 69.360735 -174.436709) (xy 69.380658 -174.384618) (xy 69.407954 -174.335983)
			(xy 69.44204 -174.29184) (xy 69.482189 -174.253131) (xy 69.527547 -174.22068) (xy 69.577147 -174.195179)
			(xy 69.629931 -174.177172) (xy 69.684774 -174.167042) (xy 69.740508 -174.165005) (xy 69.795945 -174.171105)
			(xy 69.849902 -174.185211) (xy 69.901231 -174.207023) (xy 69.948837 -174.236077) (xy 69.991705 -174.271752)
			(xy 70.028922 -174.313289) (xy 70.059695 -174.359802) (xy 70.083367 -174.410299) (xy 70.099435 -174.463706)
			(xy 70.107555 -174.518882) (xy 70.108064 -174.546768) (xy 70.472552 -174.546768) (xy 70.476623 -174.491146)
			(xy 70.488749 -174.436709) (xy 70.508672 -174.384618) (xy 70.535968 -174.335983) (xy 70.570054 -174.29184)
			(xy 70.610203 -174.253131) (xy 70.655561 -174.22068) (xy 70.705161 -174.195179) (xy 70.757945 -174.177172)
			(xy 70.812788 -174.167042) (xy 70.868522 -174.165005) (xy 70.923959 -174.171105) (xy 70.977916 -174.185211)
			(xy 71.029245 -174.207023) (xy 71.076851 -174.236077) (xy 71.119719 -174.271752) (xy 71.156936 -174.313289)
			(xy 71.187709 -174.359802) (xy 71.211381 -174.410299) (xy 71.227449 -174.463706) (xy 71.235569 -174.518882)
			(xy 71.236078 -174.546768) (xy 71.586342 -174.546768) (xy 71.590413 -174.491146) (xy 71.602539 -174.436709)
			(xy 71.622462 -174.384618) (xy 71.649758 -174.335983) (xy 71.683844 -174.29184) (xy 71.723993 -174.253131)
			(xy 71.769351 -174.22068) (xy 71.818951 -174.195179) (xy 71.871735 -174.177172) (xy 71.926578 -174.167042)
			(xy 71.982312 -174.165005) (xy 72.037749 -174.171105) (xy 72.091706 -174.185211) (xy 72.143035 -174.207023)
			(xy 72.190641 -174.236077) (xy 72.233509 -174.271752) (xy 72.270726 -174.313289) (xy 72.301499 -174.359802)
			(xy 72.325171 -174.410299) (xy 72.341239 -174.463706) (xy 72.349359 -174.518882) (xy 72.349868 -174.546768)
			(xy 72.349359 -174.574654) (xy 72.341239 -174.62983) (xy 72.325171 -174.683237) (xy 72.301499 -174.733734)
			(xy 72.270726 -174.780247) (xy 72.233509 -174.821784) (xy 72.190641 -174.857459) (xy 72.143035 -174.886513)
			(xy 72.091706 -174.908325) (xy 72.037749 -174.922431) (xy 71.982312 -174.928531) (xy 71.926578 -174.926494)
			(xy 71.871735 -174.916364) (xy 71.818951 -174.898357) (xy 71.769351 -174.872856) (xy 71.723993 -174.840405)
			(xy 71.683844 -174.801696) (xy 71.649758 -174.757553) (xy 71.622462 -174.708918) (xy 71.602539 -174.656827)
			(xy 71.590413 -174.60239) (xy 71.586342 -174.546768) (xy 71.236078 -174.546768) (xy 71.235569 -174.574654)
			(xy 71.227449 -174.62983) (xy 71.211381 -174.683237) (xy 71.187709 -174.733734) (xy 71.156936 -174.780247)
			(xy 71.119719 -174.821784) (xy 71.076851 -174.857459) (xy 71.029245 -174.886513) (xy 70.977916 -174.908325)
			(xy 70.923959 -174.922431) (xy 70.868522 -174.928531) (xy 70.812788 -174.926494) (xy 70.757945 -174.916364)
			(xy 70.705161 -174.898357) (xy 70.655561 -174.872856) (xy 70.610203 -174.840405) (xy 70.570054 -174.801696)
			(xy 70.535968 -174.757553) (xy 70.508672 -174.708918) (xy 70.488749 -174.656827) (xy 70.476623 -174.60239)
			(xy 70.472552 -174.546768) (xy 70.108064 -174.546768) (xy 70.107555 -174.574654) (xy 70.099435 -174.62983)
			(xy 70.083367 -174.683237) (xy 70.059695 -174.733734) (xy 70.028922 -174.780247) (xy 69.991705 -174.821784)
			(xy 69.948837 -174.857459) (xy 69.901231 -174.886513) (xy 69.849902 -174.908325) (xy 69.795945 -174.922431)
			(xy 69.740508 -174.928531) (xy 69.684774 -174.926494) (xy 69.629931 -174.916364) (xy 69.577147 -174.898357)
			(xy 69.527547 -174.872856) (xy 69.482189 -174.840405) (xy 69.44204 -174.801696) (xy 69.407954 -174.757553)
			(xy 69.380658 -174.708918) (xy 69.360735 -174.656827) (xy 69.348609 -174.60239) (xy 69.344538 -174.546768)
			(xy 68.989194 -174.546768) (xy 68.988685 -174.574654) (xy 68.980565 -174.62983) (xy 68.964497 -174.683237)
			(xy 68.940825 -174.733734) (xy 68.910052 -174.780247) (xy 68.872835 -174.821784) (xy 68.829967 -174.857459)
			(xy 68.782361 -174.886513) (xy 68.731032 -174.908325) (xy 68.677075 -174.922431) (xy 68.621638 -174.928531)
			(xy 68.565904 -174.926494) (xy 68.511061 -174.916364) (xy 68.458277 -174.898357) (xy 68.408677 -174.872856)
			(xy 68.363319 -174.840405) (xy 68.32317 -174.801696) (xy 68.289084 -174.757553) (xy 68.261788 -174.708918)
			(xy 68.241865 -174.656827) (xy 68.229739 -174.60239) (xy 68.225668 -174.546768) (xy 66.19494 -174.546768)
			(xy 60.82538 -179.916328) (xy 30.951932 -179.916328) (xy 30.93622 -179.917529) (xy 30.906063 -179.926636)
			(xy 30.879041 -179.942827) (xy 30.867604 -179.953666) (xy 30.720792 -180.100478) (xy 30.704977 -180.116976)
			(xy 30.678964 -180.154548) (xy 30.660092 -180.196168) (xy 30.64897 -180.240492) (xy 30.645956 -180.28609)
			(xy 30.651149 -180.331493) (xy 30.66438 -180.375233) (xy 30.685222 -180.415902) (xy 30.713004 -180.452186)
			(xy 30.746828 -180.482914) (xy 30.785604 -180.507096) (xy 30.806644 -180.516022) (xy 30.84756 -180.532807)
			(xy 30.926338 -180.573011) (xy 31.000993 -180.620435) (xy 31.070864 -180.674661) (xy 31.135334 -180.735209)
			(xy 31.193832 -180.801544) (xy 31.245842 -180.873079) (xy 31.290904 -180.949183) (xy 31.32862 -181.029182)
			(xy 31.358657 -181.11237) (xy 31.380748 -181.198011) (xy 31.394698 -181.285348) (xy 31.400385 -181.373609)
			(xy 31.398606 -181.433486) (xy 34.599874 -181.433486) (xy 34.599874 -181.346586) (xy 34.607892 -181.260057)
			(xy 34.62386 -181.174637) (xy 34.647641 -181.091055) (xy 34.679033 -181.010023) (xy 34.717767 -180.932234)
			(xy 34.763514 -180.85835) (xy 34.815883 -180.789003) (xy 34.874427 -180.724783) (xy 34.938647 -180.666239)
			(xy 35.007994 -180.61387) (xy 35.081878 -180.568123) (xy 35.159667 -180.529389) (xy 35.240699 -180.497997)
			(xy 35.324281 -180.474216) (xy 35.409701 -180.458248) (xy 35.49623 -180.45023) (xy 35.58313 -180.45023)
			(xy 35.669659 -180.458248) (xy 35.755079 -180.474216) (xy 35.838661 -180.497997) (xy 35.919693 -180.529389)
			(xy 35.997482 -180.568123) (xy 36.071366 -180.61387) (xy 36.140713 -180.666239) (xy 36.204933 -180.724783)
			(xy 36.263477 -180.789003) (xy 36.315846 -180.85835) (xy 36.361593 -180.932234) (xy 36.400327 -181.010023)
			(xy 36.431719 -181.091055) (xy 36.4555 -181.174637) (xy 36.471468 -181.260057) (xy 36.479486 -181.346586)
			(xy 36.479988 -181.390036) (xy 36.479486 -181.433486) (xy 36.471468 -181.520015) (xy 36.4555 -181.605435)
			(xy 36.431719 -181.689017) (xy 36.400327 -181.770049) (xy 36.361593 -181.847838) (xy 36.315846 -181.921722)
			(xy 36.263477 -181.991069) (xy 36.204933 -182.055289) (xy 36.140713 -182.113833) (xy 36.071366 -182.166202)
			(xy 35.997482 -182.211949) (xy 35.919693 -182.250683) (xy 35.838661 -182.282075) (xy 35.755079 -182.305856)
			(xy 35.669659 -182.321824) (xy 35.58313 -182.329842) (xy 35.49623 -182.329842) (xy 35.409701 -182.321824)
			(xy 35.324281 -182.305856) (xy 35.240699 -182.282075) (xy 35.159667 -182.250683) (xy 35.081878 -182.211949)
			(xy 35.007994 -182.166202) (xy 34.938647 -182.113833) (xy 34.874427 -182.055289) (xy 34.815883 -181.991069)
			(xy 34.763514 -181.921722) (xy 34.717767 -181.847838) (xy 34.679033 -181.770049) (xy 34.647641 -181.689017)
			(xy 34.62386 -181.605435) (xy 34.607892 -181.520015) (xy 34.599874 -181.433486) (xy 31.398606 -181.433486)
			(xy 31.397758 -181.462015) (xy 31.38684 -181.549782) (xy 31.367728 -181.636137) (xy 31.340591 -181.720315)
			(xy 31.305668 -181.801572) (xy 31.284926 -181.840632) (xy 31.262883 -181.879942) (xy 31.212349 -181.954575)
			(xy 31.154897 -182.024023) (xy 31.091056 -182.087647) (xy 31.021413 -182.144862) (xy 30.946609 -182.195142)
			(xy 30.907228 -182.21706) (xy 30.86814 -182.237637) (xy 30.786844 -182.272207) (xy 30.702664 -182.299)
			(xy 30.616342 -182.31778) (xy 30.52864 -182.328381) (xy 30.440329 -182.330711) (xy 30.35219 -182.324748)
			(xy 30.264998 -182.310545) (xy 30.179522 -182.288228) (xy 30.096517 -182.257992) (xy 30.016712 -182.220105)
			(xy 29.940813 -182.174901) (xy 29.869488 -182.122777) (xy 29.803366 -182.064194) (xy 29.743029 -181.999668)
			(xy 29.68901 -181.929768) (xy 29.641784 -181.855109) (xy 29.601769 -181.77635) (xy 29.569316 -181.694186)
			(xy 29.544713 -181.609341) (xy 29.535882 -181.566058) (xy 29.528516 -181.52745) (xy 29.501084 -181.500018)
			(xy 29.488952 -181.488557) (xy 29.460073 -181.471848) (xy 29.42785 -181.463197) (xy 29.394486 -181.463197)
			(xy 29.362263 -181.471848) (xy 29.333384 -181.488557) (xy 29.321252 -181.500018) (xy 29.168344 -181.652926)
			(xy 29.168344 -183.973486) (xy 29.519874 -183.973486) (xy 29.519874 -183.886586) (xy 29.527892 -183.800057)
			(xy 29.54386 -183.714637) (xy 29.567641 -183.631055) (xy 29.599033 -183.550023) (xy 29.637767 -183.472234)
			(xy 29.683514 -183.39835) (xy 29.735883 -183.329003) (xy 29.794427 -183.264783) (xy 29.858647 -183.206239)
			(xy 29.927994 -183.15387) (xy 30.001878 -183.108123) (xy 30.079667 -183.069389) (xy 30.160699 -183.037997)
			(xy 30.244281 -183.014216) (xy 30.329701 -182.998248) (xy 30.41623 -182.99023) (xy 30.50313 -182.99023)
			(xy 30.589659 -182.998248) (xy 30.675079 -183.014216) (xy 30.758661 -183.037997) (xy 30.839693 -183.069389)
			(xy 30.917482 -183.108123) (xy 30.991366 -183.15387) (xy 31.060713 -183.206239) (xy 31.124933 -183.264783)
			(xy 31.183477 -183.329003) (xy 31.235846 -183.39835) (xy 31.281593 -183.472234) (xy 31.320327 -183.550023)
			(xy 31.351719 -183.631055) (xy 31.3755 -183.714637) (xy 31.391468 -183.800057) (xy 31.399486 -183.886586)
			(xy 31.399988 -183.930036) (xy 31.399486 -183.973486) (xy 34.599874 -183.973486) (xy 34.599874 -183.886586)
			(xy 34.607892 -183.800057) (xy 34.62386 -183.714637) (xy 34.647641 -183.631055) (xy 34.679033 -183.550023)
			(xy 34.717767 -183.472234) (xy 34.763514 -183.39835) (xy 34.815883 -183.329003) (xy 34.874427 -183.264783)
			(xy 34.938647 -183.206239) (xy 35.007994 -183.15387) (xy 35.081878 -183.108123) (xy 35.159667 -183.069389)
			(xy 35.240699 -183.037997) (xy 35.324281 -183.014216) (xy 35.409701 -182.998248) (xy 35.49623 -182.99023)
			(xy 35.58313 -182.99023) (xy 35.669659 -182.998248) (xy 35.755079 -183.014216) (xy 35.838661 -183.037997)
			(xy 35.919693 -183.069389) (xy 35.997482 -183.108123) (xy 36.071366 -183.15387) (xy 36.140713 -183.206239)
			(xy 36.204933 -183.264783) (xy 36.263477 -183.329003) (xy 36.315846 -183.39835) (xy 36.361593 -183.472234)
			(xy 36.400327 -183.550023) (xy 36.431719 -183.631055) (xy 36.4555 -183.714637) (xy 36.471468 -183.800057)
			(xy 36.479486 -183.886586) (xy 36.479988 -183.930036) (xy 36.479486 -183.973486) (xy 36.471468 -184.060015)
			(xy 36.4555 -184.145435) (xy 36.431719 -184.229017) (xy 36.400327 -184.310049) (xy 36.361593 -184.387838)
			(xy 36.315846 -184.461722) (xy 36.263477 -184.531069) (xy 36.204933 -184.595289) (xy 36.140713 -184.653833)
			(xy 36.071366 -184.706202) (xy 36.065119 -184.71007) (xy 39.818317 -184.71007) (xy 39.822324 -184.594046)
			(xy 39.834326 -184.478574) (xy 39.854266 -184.364206) (xy 39.882049 -184.251486) (xy 39.917543 -184.140952)
			(xy 39.960578 -184.033129) (xy 40.010949 -183.928532) (xy 40.068416 -183.82766) (xy 40.132706 -183.730993)
			(xy 40.203511 -183.638992) (xy 40.280495 -183.552095) (xy 40.363291 -183.470716) (xy 40.451504 -183.395243)
			(xy 40.544714 -183.326036) (xy 40.642477 -183.263424) (xy 40.744326 -183.207707) (xy 40.849776 -183.159149)
			(xy 40.958325 -183.117981) (xy 41.069456 -183.084401) (xy 41.182639 -183.058568) (xy 41.297334 -183.040605)
			(xy 41.412996 -183.030597) (xy 41.529072 -183.028594) (xy 41.64501 -183.034603) (xy 41.760257 -183.048596)
			(xy 41.874263 -183.070507) (xy 41.986487 -183.100232) (xy 42.096393 -183.137628) (xy 42.203456 -183.182517)
			(xy 42.307168 -183.234686) (xy 42.407033 -183.293886) (xy 42.502576 -183.359835) (xy 42.502858 -183.36006)
			(xy 43.327831 -183.36006) (xy 43.331866 -183.284356) (xy 43.343925 -183.209511) (xy 43.363871 -183.13637)
			(xy 43.391478 -183.065765) (xy 43.426434 -182.998494) (xy 43.468342 -182.935319) (xy 43.516728 -182.876957)
			(xy 43.571044 -182.824069) (xy 43.630673 -182.777254) (xy 43.694941 -182.737042) (xy 43.763118 -182.70389)
			(xy 43.834434 -182.678172) (xy 43.908079 -182.66018) (xy 43.983219 -182.650118) (xy 44.059003 -182.648099)
			(xy 44.134573 -182.654148) (xy 44.209071 -182.668195) (xy 44.281654 -182.690081) (xy 44.3515 -182.719558)
			(xy 44.417817 -182.756293) (xy 44.479853 -182.799868) (xy 44.536906 -182.84979) (xy 44.58833 -182.905494)
			(xy 44.633541 -182.966349) (xy 44.672028 -183.031664) (xy 44.703354 -183.1007) (xy 44.727164 -183.172675)
			(xy 44.743189 -183.246773) (xy 44.751248 -183.322154) (xy 44.751752 -183.36006) (xy 45.867831 -183.36006)
			(xy 45.871866 -183.284356) (xy 45.883925 -183.209511) (xy 45.903871 -183.13637) (xy 45.931478 -183.065765)
			(xy 45.966434 -182.998494) (xy 46.008342 -182.935319) (xy 46.056728 -182.876957) (xy 46.111044 -182.824069)
			(xy 46.170673 -182.777254) (xy 46.234941 -182.737042) (xy 46.303118 -182.70389) (xy 46.374434 -182.678172)
			(xy 46.448079 -182.66018) (xy 46.523219 -182.650118) (xy 46.599003 -182.648099) (xy 46.674573 -182.654148)
			(xy 46.749071 -182.668195) (xy 46.821654 -182.690081) (xy 46.8915 -182.719558) (xy 46.957817 -182.756293)
			(xy 47.019853 -182.799868) (xy 47.076906 -182.84979) (xy 47.12833 -182.905494) (xy 47.173541 -182.966349)
			(xy 47.212028 -183.031664) (xy 47.243354 -183.1007) (xy 47.267164 -183.172675) (xy 47.283189 -183.246773)
			(xy 47.291248 -183.322154) (xy 47.291752 -183.36006) (xy 48.407831 -183.36006) (xy 48.411866 -183.284356)
			(xy 48.423925 -183.209511) (xy 48.443871 -183.13637) (xy 48.471478 -183.065765) (xy 48.506434 -182.998494)
			(xy 48.548342 -182.935319) (xy 48.596728 -182.876957) (xy 48.651044 -182.824069) (xy 48.710673 -182.777254)
			(xy 48.774941 -182.737042) (xy 48.843118 -182.70389) (xy 48.914434 -182.678172) (xy 48.988079 -182.66018)
			(xy 49.063219 -182.650118) (xy 49.139003 -182.648099) (xy 49.214573 -182.654148) (xy 49.289071 -182.668195)
			(xy 49.361654 -182.690081) (xy 49.4315 -182.719558) (xy 49.497817 -182.756293) (xy 49.559853 -182.799868)
			(xy 49.616906 -182.84979) (xy 49.66833 -182.905494) (xy 49.713541 -182.966349) (xy 49.752028 -183.031664)
			(xy 49.783354 -183.1007) (xy 49.807164 -183.172675) (xy 49.823189 -183.246773) (xy 49.831248 -183.322154)
			(xy 49.831752 -183.36006) (xy 50.947831 -183.36006) (xy 50.951866 -183.284356) (xy 50.963925 -183.209511)
			(xy 50.983871 -183.13637) (xy 51.011478 -183.065765) (xy 51.046434 -182.998494) (xy 51.088342 -182.935319)
			(xy 51.136728 -182.876957) (xy 51.191044 -182.824069) (xy 51.250673 -182.777254) (xy 51.314941 -182.737042)
			(xy 51.383118 -182.70389) (xy 51.454434 -182.678172) (xy 51.528079 -182.66018) (xy 51.603219 -182.650118)
			(xy 51.679003 -182.648099) (xy 51.754573 -182.654148) (xy 51.829071 -182.668195) (xy 51.901654 -182.690081)
			(xy 51.9715 -182.719558) (xy 52.037817 -182.756293) (xy 52.099853 -182.799868) (xy 52.156906 -182.84979)
			(xy 52.20833 -182.905494) (xy 52.253541 -182.966349) (xy 52.292028 -183.031664) (xy 52.323354 -183.1007)
			(xy 52.347164 -183.172675) (xy 52.363189 -183.246773) (xy 52.371248 -183.322154) (xy 52.371752 -183.36006)
			(xy 53.487831 -183.36006) (xy 53.491866 -183.284356) (xy 53.503925 -183.209511) (xy 53.523871 -183.13637)
			(xy 53.551478 -183.065765) (xy 53.586434 -182.998494) (xy 53.628342 -182.935319) (xy 53.676728 -182.876957)
			(xy 53.731044 -182.824069) (xy 53.790673 -182.777254) (xy 53.854941 -182.737042) (xy 53.923118 -182.70389)
			(xy 53.994434 -182.678172) (xy 54.068079 -182.66018) (xy 54.143219 -182.650118) (xy 54.219003 -182.648099)
			(xy 54.294573 -182.654148) (xy 54.369071 -182.668195) (xy 54.441654 -182.690081) (xy 54.5115 -182.719558)
			(xy 54.577817 -182.756293) (xy 54.639853 -182.799868) (xy 54.696906 -182.84979) (xy 54.74833 -182.905494)
			(xy 54.793541 -182.966349) (xy 54.832028 -183.031664) (xy 54.863354 -183.1007) (xy 54.887164 -183.172675)
			(xy 54.903189 -183.246773) (xy 54.911248 -183.322154) (xy 54.911752 -183.36006) (xy 56.027831 -183.36006)
			(xy 56.031866 -183.284356) (xy 56.043925 -183.209511) (xy 56.063871 -183.13637) (xy 56.091478 -183.065765)
			(xy 56.126434 -182.998494) (xy 56.168342 -182.935319) (xy 56.216728 -182.876957) (xy 56.271044 -182.824069)
			(xy 56.330673 -182.777254) (xy 56.394941 -182.737042) (xy 56.463118 -182.70389) (xy 56.534434 -182.678172)
			(xy 56.608079 -182.66018) (xy 56.683219 -182.650118) (xy 56.759003 -182.648099) (xy 56.834573 -182.654148)
			(xy 56.909071 -182.668195) (xy 56.981654 -182.690081) (xy 57.0515 -182.719558) (xy 57.117817 -182.756293)
			(xy 57.179853 -182.799868) (xy 57.236906 -182.84979) (xy 57.28833 -182.905494) (xy 57.333541 -182.966349)
			(xy 57.372028 -183.031664) (xy 57.403354 -183.1007) (xy 57.427164 -183.172675) (xy 57.443189 -183.246773)
			(xy 57.451248 -183.322154) (xy 57.451752 -183.36006) (xy 58.567831 -183.36006) (xy 58.571866 -183.284356)
			(xy 58.583925 -183.209511) (xy 58.603871 -183.13637) (xy 58.631478 -183.065765) (xy 58.666434 -182.998494)
			(xy 58.708342 -182.935319) (xy 58.756728 -182.876957) (xy 58.811044 -182.824069) (xy 58.870673 -182.777254)
			(xy 58.934941 -182.737042) (xy 59.003118 -182.70389) (xy 59.074434 -182.678172) (xy 59.148079 -182.66018)
			(xy 59.223219 -182.650118) (xy 59.299003 -182.648099) (xy 59.374573 -182.654148) (xy 59.449071 -182.668195)
			(xy 59.521654 -182.690081) (xy 59.5915 -182.719558) (xy 59.657817 -182.756293) (xy 59.719853 -182.799868)
			(xy 59.776906 -182.84979) (xy 59.82833 -182.905494) (xy 59.873541 -182.966349) (xy 59.912028 -183.031664)
			(xy 59.943354 -183.1007) (xy 59.967164 -183.172675) (xy 59.983189 -183.246773) (xy 59.991248 -183.322154)
			(xy 59.991752 -183.36006) (xy 61.107831 -183.36006) (xy 61.111866 -183.284356) (xy 61.123925 -183.209511)
			(xy 61.143871 -183.13637) (xy 61.171478 -183.065765) (xy 61.206434 -182.998494) (xy 61.248342 -182.935319)
			(xy 61.296728 -182.876957) (xy 61.351044 -182.824069) (xy 61.410673 -182.777254) (xy 61.474941 -182.737042)
			(xy 61.543118 -182.70389) (xy 61.614434 -182.678172) (xy 61.688079 -182.66018) (xy 61.763219 -182.650118)
			(xy 61.839003 -182.648099) (xy 61.914573 -182.654148) (xy 61.989071 -182.668195) (xy 62.061654 -182.690081)
			(xy 62.1315 -182.719558) (xy 62.197817 -182.756293) (xy 62.259853 -182.799868) (xy 62.316906 -182.84979)
			(xy 62.36833 -182.905494) (xy 62.413541 -182.966349) (xy 62.452028 -183.031664) (xy 62.483354 -183.1007)
			(xy 62.507164 -183.172675) (xy 62.523189 -183.246773) (xy 62.531248 -183.322154) (xy 62.531752 -183.36006)
			(xy 62.531248 -183.397966) (xy 62.523189 -183.473347) (xy 62.507164 -183.547445) (xy 62.483354 -183.61942)
			(xy 62.452028 -183.688456) (xy 62.413541 -183.753771) (xy 62.36833 -183.814626) (xy 62.316906 -183.87033)
			(xy 62.259853 -183.920252) (xy 62.197817 -183.963827) (xy 62.1315 -184.000562) (xy 62.061654 -184.030039)
			(xy 61.989071 -184.051925) (xy 61.914573 -184.065972) (xy 61.839003 -184.072021) (xy 61.763219 -184.070002)
			(xy 61.688079 -184.05994) (xy 61.614434 -184.041948) (xy 61.543118 -184.01623) (xy 61.474941 -183.983078)
			(xy 61.410673 -183.942866) (xy 61.351044 -183.896051) (xy 61.296728 -183.843163) (xy 61.248342 -183.784801)
			(xy 61.206434 -183.721626) (xy 61.171478 -183.654355) (xy 61.143871 -183.58375) (xy 61.123925 -183.510609)
			(xy 61.111866 -183.435764) (xy 61.107831 -183.36006) (xy 59.991752 -183.36006) (xy 59.991248 -183.397966)
			(xy 59.983189 -183.473347) (xy 59.967164 -183.547445) (xy 59.943354 -183.61942) (xy 59.912028 -183.688456)
			(xy 59.873541 -183.753771) (xy 59.82833 -183.814626) (xy 59.776906 -183.87033) (xy 59.719853 -183.920252)
			(xy 59.657817 -183.963827) (xy 59.5915 -184.000562) (xy 59.521654 -184.030039) (xy 59.449071 -184.051925)
			(xy 59.374573 -184.065972) (xy 59.299003 -184.072021) (xy 59.223219 -184.070002) (xy 59.148079 -184.05994)
			(xy 59.074434 -184.041948) (xy 59.003118 -184.01623) (xy 58.934941 -183.983078) (xy 58.870673 -183.942866)
			(xy 58.811044 -183.896051) (xy 58.756728 -183.843163) (xy 58.708342 -183.784801) (xy 58.666434 -183.721626)
			(xy 58.631478 -183.654355) (xy 58.603871 -183.58375) (xy 58.583925 -183.510609) (xy 58.571866 -183.435764)
			(xy 58.567831 -183.36006) (xy 57.451752 -183.36006) (xy 57.451248 -183.397966) (xy 57.443189 -183.473347)
			(xy 57.427164 -183.547445) (xy 57.403354 -183.61942) (xy 57.372028 -183.688456) (xy 57.333541 -183.753771)
			(xy 57.28833 -183.814626) (xy 57.236906 -183.87033) (xy 57.179853 -183.920252) (xy 57.117817 -183.963827)
			(xy 57.0515 -184.000562) (xy 56.981654 -184.030039) (xy 56.909071 -184.051925) (xy 56.834573 -184.065972)
			(xy 56.759003 -184.072021) (xy 56.683219 -184.070002) (xy 56.608079 -184.05994) (xy 56.534434 -184.041948)
			(xy 56.463118 -184.01623) (xy 56.394941 -183.983078) (xy 56.330673 -183.942866) (xy 56.271044 -183.896051)
			(xy 56.216728 -183.843163) (xy 56.168342 -183.784801) (xy 56.126434 -183.721626) (xy 56.091478 -183.654355)
			(xy 56.063871 -183.58375) (xy 56.043925 -183.510609) (xy 56.031866 -183.435764) (xy 56.027831 -183.36006)
			(xy 54.911752 -183.36006) (xy 54.911248 -183.397966) (xy 54.903189 -183.473347) (xy 54.887164 -183.547445)
			(xy 54.863354 -183.61942) (xy 54.832028 -183.688456) (xy 54.793541 -183.753771) (xy 54.74833 -183.814626)
			(xy 54.696906 -183.87033) (xy 54.639853 -183.920252) (xy 54.577817 -183.963827) (xy 54.5115 -184.000562)
			(xy 54.441654 -184.030039) (xy 54.369071 -184.051925) (xy 54.294573 -184.065972) (xy 54.219003 -184.072021)
			(xy 54.143219 -184.070002) (xy 54.068079 -184.05994) (xy 53.994434 -184.041948) (xy 53.923118 -184.01623)
			(xy 53.854941 -183.983078) (xy 53.790673 -183.942866) (xy 53.731044 -183.896051) (xy 53.676728 -183.843163)
			(xy 53.628342 -183.784801) (xy 53.586434 -183.721626) (xy 53.551478 -183.654355) (xy 53.523871 -183.58375)
			(xy 53.503925 -183.510609) (xy 53.491866 -183.435764) (xy 53.487831 -183.36006) (xy 52.371752 -183.36006)
			(xy 52.371248 -183.397966) (xy 52.363189 -183.473347) (xy 52.347164 -183.547445) (xy 52.323354 -183.61942)
			(xy 52.292028 -183.688456) (xy 52.253541 -183.753771) (xy 52.20833 -183.814626) (xy 52.156906 -183.87033)
			(xy 52.099853 -183.920252) (xy 52.037817 -183.963827) (xy 51.9715 -184.000562) (xy 51.901654 -184.030039)
			(xy 51.829071 -184.051925) (xy 51.754573 -184.065972) (xy 51.679003 -184.072021) (xy 51.603219 -184.070002)
			(xy 51.528079 -184.05994) (xy 51.454434 -184.041948) (xy 51.383118 -184.01623) (xy 51.314941 -183.983078)
			(xy 51.250673 -183.942866) (xy 51.191044 -183.896051) (xy 51.136728 -183.843163) (xy 51.088342 -183.784801)
			(xy 51.046434 -183.721626) (xy 51.011478 -183.654355) (xy 50.983871 -183.58375) (xy 50.963925 -183.510609)
			(xy 50.951866 -183.435764) (xy 50.947831 -183.36006) (xy 49.831752 -183.36006) (xy 49.831248 -183.397966)
			(xy 49.823189 -183.473347) (xy 49.807164 -183.547445) (xy 49.783354 -183.61942) (xy 49.752028 -183.688456)
			(xy 49.713541 -183.753771) (xy 49.66833 -183.814626) (xy 49.616906 -183.87033) (xy 49.559853 -183.920252)
			(xy 49.497817 -183.963827) (xy 49.4315 -184.000562) (xy 49.361654 -184.030039) (xy 49.289071 -184.051925)
			(xy 49.214573 -184.065972) (xy 49.139003 -184.072021) (xy 49.063219 -184.070002) (xy 48.988079 -184.05994)
			(xy 48.914434 -184.041948) (xy 48.843118 -184.01623) (xy 48.774941 -183.983078) (xy 48.710673 -183.942866)
			(xy 48.651044 -183.896051) (xy 48.596728 -183.843163) (xy 48.548342 -183.784801) (xy 48.506434 -183.721626)
			(xy 48.471478 -183.654355) (xy 48.443871 -183.58375) (xy 48.423925 -183.510609) (xy 48.411866 -183.435764)
			(xy 48.407831 -183.36006) (xy 47.291752 -183.36006) (xy 47.291248 -183.397966) (xy 47.283189 -183.473347)
			(xy 47.267164 -183.547445) (xy 47.243354 -183.61942) (xy 47.212028 -183.688456) (xy 47.173541 -183.753771)
			(xy 47.12833 -183.814626) (xy 47.076906 -183.87033) (xy 47.019853 -183.920252) (xy 46.957817 -183.963827)
			(xy 46.8915 -184.000562) (xy 46.821654 -184.030039) (xy 46.749071 -184.051925) (xy 46.674573 -184.065972)
			(xy 46.599003 -184.072021) (xy 46.523219 -184.070002) (xy 46.448079 -184.05994) (xy 46.374434 -184.041948)
			(xy 46.303118 -184.01623) (xy 46.234941 -183.983078) (xy 46.170673 -183.942866) (xy 46.111044 -183.896051)
			(xy 46.056728 -183.843163) (xy 46.008342 -183.784801) (xy 45.966434 -183.721626) (xy 45.931478 -183.654355)
			(xy 45.903871 -183.58375) (xy 45.883925 -183.510609) (xy 45.871866 -183.435764) (xy 45.867831 -183.36006)
			(xy 44.751752 -183.36006) (xy 44.751248 -183.397966) (xy 44.743189 -183.473347) (xy 44.727164 -183.547445)
			(xy 44.703354 -183.61942) (xy 44.672028 -183.688456) (xy 44.633541 -183.753771) (xy 44.58833 -183.814626)
			(xy 44.536906 -183.87033) (xy 44.479853 -183.920252) (xy 44.417817 -183.963827) (xy 44.3515 -184.000562)
			(xy 44.281654 -184.030039) (xy 44.209071 -184.051925) (xy 44.134573 -184.065972) (xy 44.059003 -184.072021)
			(xy 43.983219 -184.070002) (xy 43.908079 -184.05994) (xy 43.834434 -184.041948) (xy 43.763118 -184.01623)
			(xy 43.694941 -183.983078) (xy 43.630673 -183.942866) (xy 43.571044 -183.896051) (xy 43.516728 -183.843163)
			(xy 43.468342 -183.784801) (xy 43.426434 -183.721626) (xy 43.391478 -183.654355) (xy 43.363871 -183.58375)
			(xy 43.343925 -183.510609) (xy 43.331866 -183.435764) (xy 43.327831 -183.36006) (xy 42.502858 -183.36006)
			(xy 42.593342 -183.432218) (xy 42.678897 -183.510691) (xy 42.758835 -183.594879) (xy 42.832774 -183.684381)
			(xy 42.900362 -183.778772) (xy 42.961276 -183.8776) (xy 43.015228 -183.980396) (xy 43.061958 -184.086669)
			(xy 43.101246 -184.195913) (xy 43.132903 -184.307606) (xy 43.156779 -184.421218) (xy 43.17276 -184.536206)
			(xy 43.180769 -184.652023) (xy 43.18127 -184.71007) (xy 43.180769 -184.768117) (xy 43.17276 -184.883934)
			(xy 43.156779 -184.998922) (xy 43.132903 -185.112534) (xy 43.101246 -185.224227) (xy 43.061958 -185.333471)
			(xy 43.015228 -185.439744) (xy 42.961276 -185.54254) (xy 42.900362 -185.641368) (xy 42.832774 -185.735759)
			(xy 42.758835 -185.825261) (xy 42.678897 -185.909449) (xy 42.593342 -185.987922) (xy 42.502858 -186.06008)
			(xy 43.327831 -186.06008) (xy 43.331866 -185.984376) (xy 43.343925 -185.909531) (xy 43.363871 -185.83639)
			(xy 43.391478 -185.765785) (xy 43.426434 -185.698514) (xy 43.468342 -185.635339) (xy 43.516728 -185.576977)
			(xy 43.571044 -185.524089) (xy 43.630673 -185.477274) (xy 43.694941 -185.437062) (xy 43.763118 -185.40391)
			(xy 43.834434 -185.378192) (xy 43.908079 -185.3602) (xy 43.983219 -185.350138) (xy 44.059003 -185.348119)
			(xy 44.134573 -185.354168) (xy 44.209071 -185.368215) (xy 44.281654 -185.390101) (xy 44.3515 -185.419578)
			(xy 44.417817 -185.456313) (xy 44.479853 -185.499888) (xy 44.536906 -185.54981) (xy 44.58833 -185.605514)
			(xy 44.633541 -185.666369) (xy 44.672028 -185.731684) (xy 44.703354 -185.80072) (xy 44.727164 -185.872695)
			(xy 44.743189 -185.946793) (xy 44.751248 -186.022174) (xy 44.751752 -186.06008) (xy 45.867831 -186.06008)
			(xy 45.871866 -185.984376) (xy 45.883925 -185.909531) (xy 45.903871 -185.83639) (xy 45.931478 -185.765785)
			(xy 45.966434 -185.698514) (xy 46.008342 -185.635339) (xy 46.056728 -185.576977) (xy 46.111044 -185.524089)
			(xy 46.170673 -185.477274) (xy 46.234941 -185.437062) (xy 46.303118 -185.40391) (xy 46.374434 -185.378192)
			(xy 46.448079 -185.3602) (xy 46.523219 -185.350138) (xy 46.599003 -185.348119) (xy 46.674573 -185.354168)
			(xy 46.749071 -185.368215) (xy 46.821654 -185.390101) (xy 46.8915 -185.419578) (xy 46.957817 -185.456313)
			(xy 47.019853 -185.499888) (xy 47.076906 -185.54981) (xy 47.12833 -185.605514) (xy 47.173541 -185.666369)
			(xy 47.212028 -185.731684) (xy 47.243354 -185.80072) (xy 47.267164 -185.872695) (xy 47.283189 -185.946793)
			(xy 47.291248 -186.022174) (xy 47.291752 -186.06008) (xy 48.407831 -186.06008) (xy 48.411866 -185.984376)
			(xy 48.423925 -185.909531) (xy 48.443871 -185.83639) (xy 48.471478 -185.765785) (xy 48.506434 -185.698514)
			(xy 48.548342 -185.635339) (xy 48.596728 -185.576977) (xy 48.651044 -185.524089) (xy 48.710673 -185.477274)
			(xy 48.774941 -185.437062) (xy 48.843118 -185.40391) (xy 48.914434 -185.378192) (xy 48.988079 -185.3602)
			(xy 49.063219 -185.350138) (xy 49.139003 -185.348119) (xy 49.214573 -185.354168) (xy 49.289071 -185.368215)
			(xy 49.361654 -185.390101) (xy 49.4315 -185.419578) (xy 49.497817 -185.456313) (xy 49.559853 -185.499888)
			(xy 49.616906 -185.54981) (xy 49.66833 -185.605514) (xy 49.713541 -185.666369) (xy 49.752028 -185.731684)
			(xy 49.783354 -185.80072) (xy 49.807164 -185.872695) (xy 49.823189 -185.946793) (xy 49.831248 -186.022174)
			(xy 49.831752 -186.06008) (xy 50.947831 -186.06008) (xy 50.951866 -185.984376) (xy 50.963925 -185.909531)
			(xy 50.983871 -185.83639) (xy 51.011478 -185.765785) (xy 51.046434 -185.698514) (xy 51.088342 -185.635339)
			(xy 51.136728 -185.576977) (xy 51.191044 -185.524089) (xy 51.250673 -185.477274) (xy 51.314941 -185.437062)
			(xy 51.383118 -185.40391) (xy 51.454434 -185.378192) (xy 51.528079 -185.3602) (xy 51.603219 -185.350138)
			(xy 51.679003 -185.348119) (xy 51.754573 -185.354168) (xy 51.829071 -185.368215) (xy 51.901654 -185.390101)
			(xy 51.9715 -185.419578) (xy 52.037817 -185.456313) (xy 52.099853 -185.499888) (xy 52.156906 -185.54981)
			(xy 52.20833 -185.605514) (xy 52.253541 -185.666369) (xy 52.292028 -185.731684) (xy 52.323354 -185.80072)
			(xy 52.347164 -185.872695) (xy 52.363189 -185.946793) (xy 52.371248 -186.022174) (xy 52.371752 -186.06008)
			(xy 53.487831 -186.06008) (xy 53.491866 -185.984376) (xy 53.503925 -185.909531) (xy 53.523871 -185.83639)
			(xy 53.551478 -185.765785) (xy 53.586434 -185.698514) (xy 53.628342 -185.635339) (xy 53.676728 -185.576977)
			(xy 53.731044 -185.524089) (xy 53.790673 -185.477274) (xy 53.854941 -185.437062) (xy 53.923118 -185.40391)
			(xy 53.994434 -185.378192) (xy 54.068079 -185.3602) (xy 54.143219 -185.350138) (xy 54.219003 -185.348119)
			(xy 54.294573 -185.354168) (xy 54.369071 -185.368215) (xy 54.441654 -185.390101) (xy 54.5115 -185.419578)
			(xy 54.577817 -185.456313) (xy 54.639853 -185.499888) (xy 54.696906 -185.54981) (xy 54.74833 -185.605514)
			(xy 54.793541 -185.666369) (xy 54.832028 -185.731684) (xy 54.863354 -185.80072) (xy 54.887164 -185.872695)
			(xy 54.903189 -185.946793) (xy 54.911248 -186.022174) (xy 54.911752 -186.06008) (xy 56.027831 -186.06008)
			(xy 56.031866 -185.984376) (xy 56.043925 -185.909531) (xy 56.063871 -185.83639) (xy 56.091478 -185.765785)
			(xy 56.126434 -185.698514) (xy 56.168342 -185.635339) (xy 56.216728 -185.576977) (xy 56.271044 -185.524089)
			(xy 56.330673 -185.477274) (xy 56.394941 -185.437062) (xy 56.463118 -185.40391) (xy 56.534434 -185.378192)
			(xy 56.608079 -185.3602) (xy 56.683219 -185.350138) (xy 56.759003 -185.348119) (xy 56.834573 -185.354168)
			(xy 56.909071 -185.368215) (xy 56.981654 -185.390101) (xy 57.0515 -185.419578) (xy 57.117817 -185.456313)
			(xy 57.179853 -185.499888) (xy 57.236906 -185.54981) (xy 57.28833 -185.605514) (xy 57.333541 -185.666369)
			(xy 57.372028 -185.731684) (xy 57.403354 -185.80072) (xy 57.427164 -185.872695) (xy 57.443189 -185.946793)
			(xy 57.451248 -186.022174) (xy 57.451752 -186.06008) (xy 58.567831 -186.06008) (xy 58.571866 -185.984376)
			(xy 58.583925 -185.909531) (xy 58.603871 -185.83639) (xy 58.631478 -185.765785) (xy 58.666434 -185.698514)
			(xy 58.708342 -185.635339) (xy 58.756728 -185.576977) (xy 58.811044 -185.524089) (xy 58.870673 -185.477274)
			(xy 58.934941 -185.437062) (xy 59.003118 -185.40391) (xy 59.074434 -185.378192) (xy 59.148079 -185.3602)
			(xy 59.223219 -185.350138) (xy 59.299003 -185.348119) (xy 59.374573 -185.354168) (xy 59.449071 -185.368215)
			(xy 59.521654 -185.390101) (xy 59.5915 -185.419578) (xy 59.657817 -185.456313) (xy 59.719853 -185.499888)
			(xy 59.776906 -185.54981) (xy 59.82833 -185.605514) (xy 59.873541 -185.666369) (xy 59.912028 -185.731684)
			(xy 59.943354 -185.80072) (xy 59.967164 -185.872695) (xy 59.983189 -185.946793) (xy 59.991248 -186.022174)
			(xy 59.991752 -186.06008) (xy 61.107831 -186.06008) (xy 61.111866 -185.984376) (xy 61.123925 -185.909531)
			(xy 61.143871 -185.83639) (xy 61.171478 -185.765785) (xy 61.206434 -185.698514) (xy 61.248342 -185.635339)
			(xy 61.296728 -185.576977) (xy 61.351044 -185.524089) (xy 61.410673 -185.477274) (xy 61.474941 -185.437062)
			(xy 61.543118 -185.40391) (xy 61.614434 -185.378192) (xy 61.688079 -185.3602) (xy 61.763219 -185.350138)
			(xy 61.839003 -185.348119) (xy 61.914573 -185.354168) (xy 61.989071 -185.368215) (xy 62.061654 -185.390101)
			(xy 62.1315 -185.419578) (xy 62.197817 -185.456313) (xy 62.259853 -185.499888) (xy 62.316906 -185.54981)
			(xy 62.36833 -185.605514) (xy 62.413541 -185.666369) (xy 62.452028 -185.731684) (xy 62.483354 -185.80072)
			(xy 62.507164 -185.872695) (xy 62.523189 -185.946793) (xy 62.531248 -186.022174) (xy 62.531752 -186.06008)
			(xy 62.531248 -186.097986) (xy 62.523189 -186.173367) (xy 62.507164 -186.247465) (xy 62.483354 -186.31944)
			(xy 62.452028 -186.388476) (xy 62.413541 -186.453791) (xy 62.36833 -186.514646) (xy 62.316906 -186.57035)
			(xy 62.259853 -186.620272) (xy 62.197817 -186.663847) (xy 62.1315 -186.700582) (xy 62.061654 -186.730059)
			(xy 61.989071 -186.751945) (xy 61.914573 -186.765992) (xy 61.839003 -186.772041) (xy 61.763219 -186.770022)
			(xy 61.688079 -186.75996) (xy 61.614434 -186.741968) (xy 61.543118 -186.71625) (xy 61.474941 -186.683098)
			(xy 61.410673 -186.642886) (xy 61.351044 -186.596071) (xy 61.296728 -186.543183) (xy 61.248342 -186.484821)
			(xy 61.206434 -186.421646) (xy 61.171478 -186.354375) (xy 61.143871 -186.28377) (xy 61.123925 -186.210629)
			(xy 61.111866 -186.135784) (xy 61.107831 -186.06008) (xy 59.991752 -186.06008) (xy 59.991248 -186.097986)
			(xy 59.983189 -186.173367) (xy 59.967164 -186.247465) (xy 59.943354 -186.31944) (xy 59.912028 -186.388476)
			(xy 59.873541 -186.453791) (xy 59.82833 -186.514646) (xy 59.776906 -186.57035) (xy 59.719853 -186.620272)
			(xy 59.657817 -186.663847) (xy 59.5915 -186.700582) (xy 59.521654 -186.730059) (xy 59.449071 -186.751945)
			(xy 59.374573 -186.765992) (xy 59.299003 -186.772041) (xy 59.223219 -186.770022) (xy 59.148079 -186.75996)
			(xy 59.074434 -186.741968) (xy 59.003118 -186.71625) (xy 58.934941 -186.683098) (xy 58.870673 -186.642886)
			(xy 58.811044 -186.596071) (xy 58.756728 -186.543183) (xy 58.708342 -186.484821) (xy 58.666434 -186.421646)
			(xy 58.631478 -186.354375) (xy 58.603871 -186.28377) (xy 58.583925 -186.210629) (xy 58.571866 -186.135784)
			(xy 58.567831 -186.06008) (xy 57.451752 -186.06008) (xy 57.451248 -186.097986) (xy 57.443189 -186.173367)
			(xy 57.427164 -186.247465) (xy 57.403354 -186.31944) (xy 57.372028 -186.388476) (xy 57.333541 -186.453791)
			(xy 57.28833 -186.514646) (xy 57.236906 -186.57035) (xy 57.179853 -186.620272) (xy 57.117817 -186.663847)
			(xy 57.0515 -186.700582) (xy 56.981654 -186.730059) (xy 56.909071 -186.751945) (xy 56.834573 -186.765992)
			(xy 56.759003 -186.772041) (xy 56.683219 -186.770022) (xy 56.608079 -186.75996) (xy 56.534434 -186.741968)
			(xy 56.463118 -186.71625) (xy 56.394941 -186.683098) (xy 56.330673 -186.642886) (xy 56.271044 -186.596071)
			(xy 56.216728 -186.543183) (xy 56.168342 -186.484821) (xy 56.126434 -186.421646) (xy 56.091478 -186.354375)
			(xy 56.063871 -186.28377) (xy 56.043925 -186.210629) (xy 56.031866 -186.135784) (xy 56.027831 -186.06008)
			(xy 54.911752 -186.06008) (xy 54.911248 -186.097986) (xy 54.903189 -186.173367) (xy 54.887164 -186.247465)
			(xy 54.863354 -186.31944) (xy 54.832028 -186.388476) (xy 54.793541 -186.453791) (xy 54.74833 -186.514646)
			(xy 54.696906 -186.57035) (xy 54.639853 -186.620272) (xy 54.577817 -186.663847) (xy 54.5115 -186.700582)
			(xy 54.441654 -186.730059) (xy 54.369071 -186.751945) (xy 54.294573 -186.765992) (xy 54.219003 -186.772041)
			(xy 54.143219 -186.770022) (xy 54.068079 -186.75996) (xy 53.994434 -186.741968) (xy 53.923118 -186.71625)
			(xy 53.854941 -186.683098) (xy 53.790673 -186.642886) (xy 53.731044 -186.596071) (xy 53.676728 -186.543183)
			(xy 53.628342 -186.484821) (xy 53.586434 -186.421646) (xy 53.551478 -186.354375) (xy 53.523871 -186.28377)
			(xy 53.503925 -186.210629) (xy 53.491866 -186.135784) (xy 53.487831 -186.06008) (xy 52.371752 -186.06008)
			(xy 52.371248 -186.097986) (xy 52.363189 -186.173367) (xy 52.347164 -186.247465) (xy 52.323354 -186.31944)
			(xy 52.292028 -186.388476) (xy 52.253541 -186.453791) (xy 52.20833 -186.514646) (xy 52.156906 -186.57035)
			(xy 52.099853 -186.620272) (xy 52.037817 -186.663847) (xy 51.9715 -186.700582) (xy 51.901654 -186.730059)
			(xy 51.829071 -186.751945) (xy 51.754573 -186.765992) (xy 51.679003 -186.772041) (xy 51.603219 -186.770022)
			(xy 51.528079 -186.75996) (xy 51.454434 -186.741968) (xy 51.383118 -186.71625) (xy 51.314941 -186.683098)
			(xy 51.250673 -186.642886) (xy 51.191044 -186.596071) (xy 51.136728 -186.543183) (xy 51.088342 -186.484821)
			(xy 51.046434 -186.421646) (xy 51.011478 -186.354375) (xy 50.983871 -186.28377) (xy 50.963925 -186.210629)
			(xy 50.951866 -186.135784) (xy 50.947831 -186.06008) (xy 49.831752 -186.06008) (xy 49.831248 -186.097986)
			(xy 49.823189 -186.173367) (xy 49.807164 -186.247465) (xy 49.783354 -186.31944) (xy 49.752028 -186.388476)
			(xy 49.713541 -186.453791) (xy 49.66833 -186.514646) (xy 49.616906 -186.57035) (xy 49.559853 -186.620272)
			(xy 49.497817 -186.663847) (xy 49.4315 -186.700582) (xy 49.361654 -186.730059) (xy 49.289071 -186.751945)
			(xy 49.214573 -186.765992) (xy 49.139003 -186.772041) (xy 49.063219 -186.770022) (xy 48.988079 -186.75996)
			(xy 48.914434 -186.741968) (xy 48.843118 -186.71625) (xy 48.774941 -186.683098) (xy 48.710673 -186.642886)
			(xy 48.651044 -186.596071) (xy 48.596728 -186.543183) (xy 48.548342 -186.484821) (xy 48.506434 -186.421646)
			(xy 48.471478 -186.354375) (xy 48.443871 -186.28377) (xy 48.423925 -186.210629) (xy 48.411866 -186.135784)
			(xy 48.407831 -186.06008) (xy 47.291752 -186.06008) (xy 47.291248 -186.097986) (xy 47.283189 -186.173367)
			(xy 47.267164 -186.247465) (xy 47.243354 -186.31944) (xy 47.212028 -186.388476) (xy 47.173541 -186.453791)
			(xy 47.12833 -186.514646) (xy 47.076906 -186.57035) (xy 47.019853 -186.620272) (xy 46.957817 -186.663847)
			(xy 46.8915 -186.700582) (xy 46.821654 -186.730059) (xy 46.749071 -186.751945) (xy 46.674573 -186.765992)
			(xy 46.599003 -186.772041) (xy 46.523219 -186.770022) (xy 46.448079 -186.75996) (xy 46.374434 -186.741968)
			(xy 46.303118 -186.71625) (xy 46.234941 -186.683098) (xy 46.170673 -186.642886) (xy 46.111044 -186.596071)
			(xy 46.056728 -186.543183) (xy 46.008342 -186.484821) (xy 45.966434 -186.421646) (xy 45.931478 -186.354375)
			(xy 45.903871 -186.28377) (xy 45.883925 -186.210629) (xy 45.871866 -186.135784) (xy 45.867831 -186.06008)
			(xy 44.751752 -186.06008) (xy 44.751248 -186.097986) (xy 44.743189 -186.173367) (xy 44.727164 -186.247465)
			(xy 44.703354 -186.31944) (xy 44.672028 -186.388476) (xy 44.633541 -186.453791) (xy 44.58833 -186.514646)
			(xy 44.536906 -186.57035) (xy 44.479853 -186.620272) (xy 44.417817 -186.663847) (xy 44.3515 -186.700582)
			(xy 44.281654 -186.730059) (xy 44.209071 -186.751945) (xy 44.134573 -186.765992) (xy 44.059003 -186.772041)
			(xy 43.983219 -186.770022) (xy 43.908079 -186.75996) (xy 43.834434 -186.741968) (xy 43.763118 -186.71625)
			(xy 43.694941 -186.683098) (xy 43.630673 -186.642886) (xy 43.571044 -186.596071) (xy 43.516728 -186.543183)
			(xy 43.468342 -186.484821) (xy 43.426434 -186.421646) (xy 43.391478 -186.354375) (xy 43.363871 -186.28377)
			(xy 43.343925 -186.210629) (xy 43.331866 -186.135784) (xy 43.327831 -186.06008) (xy 42.502858 -186.06008)
			(xy 42.502576 -186.060305) (xy 42.407033 -186.126254) (xy 42.307168 -186.185454) (xy 42.203456 -186.237623)
			(xy 42.096393 -186.282512) (xy 41.986487 -186.319908) (xy 41.874263 -186.349633) (xy 41.760257 -186.371544)
			(xy 41.64501 -186.385537) (xy 41.529072 -186.391546) (xy 41.412996 -186.389543) (xy 41.297334 -186.379535)
			(xy 41.182639 -186.361572) (xy 41.069456 -186.335739) (xy 40.958325 -186.302159) (xy 40.849776 -186.260991)
			(xy 40.744326 -186.212433) (xy 40.642477 -186.156716) (xy 40.544714 -186.094104) (xy 40.451504 -186.024897)
			(xy 40.363291 -185.949424) (xy 40.280495 -185.868045) (xy 40.203511 -185.781148) (xy 40.132706 -185.689147)
			(xy 40.068416 -185.59248) (xy 40.010949 -185.491608) (xy 39.960578 -185.387011) (xy 39.917543 -185.279188)
			(xy 39.882049 -185.168654) (xy 39.854266 -185.055934) (xy 39.834326 -184.941566) (xy 39.822324 -184.826094)
			(xy 39.818317 -184.71007) (xy 36.065119 -184.71007) (xy 35.997482 -184.751949) (xy 35.919693 -184.790683)
			(xy 35.838661 -184.822075) (xy 35.755079 -184.845856) (xy 35.669659 -184.861824) (xy 35.58313 -184.869842)
			(xy 35.49623 -184.869842) (xy 35.409701 -184.861824) (xy 35.324281 -184.845856) (xy 35.240699 -184.822075)
			(xy 35.159667 -184.790683) (xy 35.081878 -184.751949) (xy 35.007994 -184.706202) (xy 34.938647 -184.653833)
			(xy 34.874427 -184.595289) (xy 34.815883 -184.531069) (xy 34.763514 -184.461722) (xy 34.717767 -184.387838)
			(xy 34.679033 -184.310049) (xy 34.647641 -184.229017) (xy 34.62386 -184.145435) (xy 34.607892 -184.060015)
			(xy 34.599874 -183.973486) (xy 31.399486 -183.973486) (xy 31.391468 -184.060015) (xy 31.3755 -184.145435)
			(xy 31.351719 -184.229017) (xy 31.320327 -184.310049) (xy 31.281593 -184.387838) (xy 31.235846 -184.461722)
			(xy 31.183477 -184.531069) (xy 31.124933 -184.595289) (xy 31.060713 -184.653833) (xy 30.991366 -184.706202)
			(xy 30.917482 -184.751949) (xy 30.839693 -184.790683) (xy 30.758661 -184.822075) (xy 30.675079 -184.845856)
			(xy 30.589659 -184.861824) (xy 30.50313 -184.869842) (xy 30.41623 -184.869842) (xy 30.329701 -184.861824)
			(xy 30.244281 -184.845856) (xy 30.160699 -184.822075) (xy 30.079667 -184.790683) (xy 30.001878 -184.751949)
			(xy 29.927994 -184.706202) (xy 29.858647 -184.653833) (xy 29.794427 -184.595289) (xy 29.735883 -184.531069)
			(xy 29.683514 -184.461722) (xy 29.637767 -184.387838) (xy 29.599033 -184.310049) (xy 29.567641 -184.229017)
			(xy 29.54386 -184.145435) (xy 29.527892 -184.060015) (xy 29.519874 -183.973486) (xy 29.168344 -183.973486)
			(xy 29.168344 -186.513486) (xy 29.519874 -186.513486) (xy 29.519874 -186.426586) (xy 29.527892 -186.340057)
			(xy 29.54386 -186.254637) (xy 29.567641 -186.171055) (xy 29.599033 -186.090023) (xy 29.637767 -186.012234)
			(xy 29.683514 -185.93835) (xy 29.735883 -185.869003) (xy 29.794427 -185.804783) (xy 29.858647 -185.746239)
			(xy 29.927994 -185.69387) (xy 30.001878 -185.648123) (xy 30.079667 -185.609389) (xy 30.160699 -185.577997)
			(xy 30.244281 -185.554216) (xy 30.329701 -185.538248) (xy 30.41623 -185.53023) (xy 30.50313 -185.53023)
			(xy 30.589659 -185.538248) (xy 30.675079 -185.554216) (xy 30.758661 -185.577997) (xy 30.839693 -185.609389)
			(xy 30.917482 -185.648123) (xy 30.991366 -185.69387) (xy 31.060713 -185.746239) (xy 31.124933 -185.804783)
			(xy 31.183477 -185.869003) (xy 31.235846 -185.93835) (xy 31.281593 -186.012234) (xy 31.320327 -186.090023)
			(xy 31.351719 -186.171055) (xy 31.3755 -186.254637) (xy 31.391468 -186.340057) (xy 31.399486 -186.426586)
			(xy 31.399988 -186.470036) (xy 31.399486 -186.513486) (xy 34.599874 -186.513486) (xy 34.599874 -186.426586)
			(xy 34.607892 -186.340057) (xy 34.62386 -186.254637) (xy 34.647641 -186.171055) (xy 34.679033 -186.090023)
			(xy 34.717767 -186.012234) (xy 34.763514 -185.93835) (xy 34.815883 -185.869003) (xy 34.874427 -185.804783)
			(xy 34.938647 -185.746239) (xy 35.007994 -185.69387) (xy 35.081878 -185.648123) (xy 35.159667 -185.609389)
			(xy 35.240699 -185.577997) (xy 35.324281 -185.554216) (xy 35.409701 -185.538248) (xy 35.49623 -185.53023)
			(xy 35.58313 -185.53023) (xy 35.669659 -185.538248) (xy 35.755079 -185.554216) (xy 35.838661 -185.577997)
			(xy 35.919693 -185.609389) (xy 35.997482 -185.648123) (xy 36.071366 -185.69387) (xy 36.140713 -185.746239)
			(xy 36.204933 -185.804783) (xy 36.263477 -185.869003) (xy 36.315846 -185.93835) (xy 36.361593 -186.012234)
			(xy 36.400327 -186.090023) (xy 36.431719 -186.171055) (xy 36.4555 -186.254637) (xy 36.471468 -186.340057)
			(xy 36.479486 -186.426586) (xy 36.479988 -186.470036) (xy 36.479486 -186.513486) (xy 36.471468 -186.600015)
			(xy 36.4555 -186.685435) (xy 36.431719 -186.769017) (xy 36.400327 -186.850049) (xy 36.361593 -186.927838)
			(xy 36.315846 -187.001722) (xy 36.263477 -187.071069) (xy 36.204933 -187.135289) (xy 36.140713 -187.193833)
			(xy 36.071366 -187.246202) (xy 35.997482 -187.291949) (xy 35.919693 -187.330683) (xy 35.838661 -187.362075)
			(xy 35.755079 -187.385856) (xy 35.669659 -187.401824) (xy 35.58313 -187.409842) (xy 35.49623 -187.409842)
			(xy 35.409701 -187.401824) (xy 35.324281 -187.385856) (xy 35.240699 -187.362075) (xy 35.159667 -187.330683)
			(xy 35.081878 -187.291949) (xy 35.007994 -187.246202) (xy 34.938647 -187.193833) (xy 34.874427 -187.135289)
			(xy 34.815883 -187.071069) (xy 34.763514 -187.001722) (xy 34.717767 -186.927838) (xy 34.679033 -186.850049)
			(xy 34.647641 -186.769017) (xy 34.62386 -186.685435) (xy 34.607892 -186.600015) (xy 34.599874 -186.513486)
			(xy 31.399486 -186.513486) (xy 31.391468 -186.600015) (xy 31.3755 -186.685435) (xy 31.351719 -186.769017)
			(xy 31.320327 -186.850049) (xy 31.281593 -186.927838) (xy 31.235846 -187.001722) (xy 31.183477 -187.071069)
			(xy 31.124933 -187.135289) (xy 31.060713 -187.193833) (xy 30.991366 -187.246202) (xy 30.917482 -187.291949)
			(xy 30.839693 -187.330683) (xy 30.758661 -187.362075) (xy 30.675079 -187.385856) (xy 30.589659 -187.401824)
			(xy 30.50313 -187.409842) (xy 30.41623 -187.409842) (xy 30.329701 -187.401824) (xy 30.244281 -187.385856)
			(xy 30.160699 -187.362075) (xy 30.079667 -187.330683) (xy 30.001878 -187.291949) (xy 29.927994 -187.246202)
			(xy 29.858647 -187.193833) (xy 29.794427 -187.135289) (xy 29.735883 -187.071069) (xy 29.683514 -187.001722)
			(xy 29.637767 -186.927838) (xy 29.599033 -186.850049) (xy 29.567641 -186.769017) (xy 29.54386 -186.685435)
			(xy 29.527892 -186.600015) (xy 29.519874 -186.513486) (xy 29.168344 -186.513486) (xy 29.168344 -187.864242)
			(xy 28.461716 -188.57087) (xy 28.461716 -189.053486) (xy 29.519874 -189.053486) (xy 29.519874 -188.966586)
			(xy 29.527892 -188.880057) (xy 29.54386 -188.794637) (xy 29.567641 -188.711055) (xy 29.599033 -188.630023)
			(xy 29.637767 -188.552234) (xy 29.683514 -188.47835) (xy 29.735883 -188.409003) (xy 29.794427 -188.344783)
			(xy 29.858647 -188.286239) (xy 29.927994 -188.23387) (xy 30.001878 -188.188123) (xy 30.079667 -188.149389)
			(xy 30.160699 -188.117997) (xy 30.244281 -188.094216) (xy 30.329701 -188.078248) (xy 30.41623 -188.07023)
			(xy 30.50313 -188.07023) (xy 30.589659 -188.078248) (xy 30.675079 -188.094216) (xy 30.758661 -188.117997)
			(xy 30.839693 -188.149389) (xy 30.917482 -188.188123) (xy 30.991366 -188.23387) (xy 31.060713 -188.286239)
			(xy 31.124933 -188.344783) (xy 31.183477 -188.409003) (xy 31.235846 -188.47835) (xy 31.281593 -188.552234)
			(xy 31.320327 -188.630023) (xy 31.351719 -188.711055) (xy 31.3755 -188.794637) (xy 31.391468 -188.880057)
			(xy 31.399486 -188.966586) (xy 31.399988 -189.010036) (xy 31.399486 -189.053486) (xy 34.599874 -189.053486)
			(xy 34.599874 -188.966586) (xy 34.607892 -188.880057) (xy 34.62386 -188.794637) (xy 34.647641 -188.711055)
			(xy 34.679033 -188.630023) (xy 34.717767 -188.552234) (xy 34.763514 -188.47835) (xy 34.815883 -188.409003)
			(xy 34.874427 -188.344783) (xy 34.938647 -188.286239) (xy 35.007994 -188.23387) (xy 35.081878 -188.188123)
			(xy 35.159667 -188.149389) (xy 35.240699 -188.117997) (xy 35.324281 -188.094216) (xy 35.409701 -188.078248)
			(xy 35.49623 -188.07023) (xy 35.58313 -188.07023) (xy 35.669659 -188.078248) (xy 35.755079 -188.094216)
			(xy 35.838661 -188.117997) (xy 35.919693 -188.149389) (xy 35.997482 -188.188123) (xy 36.071366 -188.23387)
			(xy 36.140713 -188.286239) (xy 36.204933 -188.344783) (xy 36.263477 -188.409003) (xy 36.315846 -188.47835)
			(xy 36.361593 -188.552234) (xy 36.400327 -188.630023) (xy 36.431719 -188.711055) (xy 36.4555 -188.794637)
			(xy 36.471468 -188.880057) (xy 36.479486 -188.966586) (xy 36.479988 -189.010036) (xy 36.479486 -189.053486)
			(xy 36.471468 -189.140015) (xy 36.4555 -189.225435) (xy 36.431719 -189.309017) (xy 36.400327 -189.390049)
			(xy 36.361593 -189.467838) (xy 36.315846 -189.541722) (xy 36.263477 -189.611069) (xy 36.204933 -189.675289)
			(xy 36.140713 -189.733833) (xy 36.071366 -189.786202) (xy 35.997482 -189.831949) (xy 35.919693 -189.870683)
			(xy 35.838661 -189.902075) (xy 35.755079 -189.925856) (xy 35.669659 -189.941824) (xy 35.58313 -189.949842)
			(xy 35.49623 -189.949842) (xy 35.409701 -189.941824) (xy 35.324281 -189.925856) (xy 35.240699 -189.902075)
			(xy 35.159667 -189.870683) (xy 35.081878 -189.831949) (xy 35.007994 -189.786202) (xy 34.938647 -189.733833)
			(xy 34.874427 -189.675289) (xy 34.815883 -189.611069) (xy 34.763514 -189.541722) (xy 34.717767 -189.467838)
			(xy 34.679033 -189.390049) (xy 34.647641 -189.309017) (xy 34.62386 -189.225435) (xy 34.607892 -189.140015)
			(xy 34.599874 -189.053486) (xy 31.399486 -189.053486) (xy 31.391468 -189.140015) (xy 31.3755 -189.225435)
			(xy 31.351719 -189.309017) (xy 31.320327 -189.390049) (xy 31.281593 -189.467838) (xy 31.235846 -189.541722)
			(xy 31.183477 -189.611069) (xy 31.124933 -189.675289) (xy 31.060713 -189.733833) (xy 30.991366 -189.786202)
			(xy 30.917482 -189.831949) (xy 30.839693 -189.870683) (xy 30.758661 -189.902075) (xy 30.675079 -189.925856)
			(xy 30.589659 -189.941824) (xy 30.50313 -189.949842) (xy 30.41623 -189.949842) (xy 30.329701 -189.941824)
			(xy 30.244281 -189.925856) (xy 30.160699 -189.902075) (xy 30.079667 -189.870683) (xy 30.001878 -189.831949)
			(xy 29.927994 -189.786202) (xy 29.858647 -189.733833) (xy 29.794427 -189.675289) (xy 29.735883 -189.611069)
			(xy 29.683514 -189.541722) (xy 29.637767 -189.467838) (xy 29.599033 -189.390049) (xy 29.567641 -189.309017)
			(xy 29.54386 -189.225435) (xy 29.527892 -189.140015) (xy 29.519874 -189.053486) (xy 28.461716 -189.053486)
			(xy 28.461716 -191.593486) (xy 29.519874 -191.593486) (xy 29.519874 -191.506586) (xy 29.527892 -191.420057)
			(xy 29.54386 -191.334637) (xy 29.567641 -191.251055) (xy 29.599033 -191.170023) (xy 29.637767 -191.092234)
			(xy 29.683514 -191.01835) (xy 29.735883 -190.949003) (xy 29.794427 -190.884783) (xy 29.858647 -190.826239)
			(xy 29.927994 -190.77387) (xy 30.001878 -190.728123) (xy 30.079667 -190.689389) (xy 30.160699 -190.657997)
			(xy 30.244281 -190.634216) (xy 30.329701 -190.618248) (xy 30.41623 -190.61023) (xy 30.50313 -190.61023)
			(xy 30.589659 -190.618248) (xy 30.675079 -190.634216) (xy 30.758661 -190.657997) (xy 30.839693 -190.689389)
			(xy 30.917482 -190.728123) (xy 30.991366 -190.77387) (xy 31.060713 -190.826239) (xy 31.124933 -190.884783)
			(xy 31.183477 -190.949003) (xy 31.235846 -191.01835) (xy 31.281593 -191.092234) (xy 31.320327 -191.170023)
			(xy 31.351719 -191.251055) (xy 31.3755 -191.334637) (xy 31.391468 -191.420057) (xy 31.399486 -191.506586)
			(xy 31.399988 -191.550036) (xy 31.399486 -191.593486) (xy 34.599874 -191.593486) (xy 34.599874 -191.506586)
			(xy 34.607892 -191.420057) (xy 34.62386 -191.334637) (xy 34.647641 -191.251055) (xy 34.679033 -191.170023)
			(xy 34.717767 -191.092234) (xy 34.763514 -191.01835) (xy 34.815883 -190.949003) (xy 34.874427 -190.884783)
			(xy 34.938647 -190.826239) (xy 35.007994 -190.77387) (xy 35.081878 -190.728123) (xy 35.159667 -190.689389)
			(xy 35.240699 -190.657997) (xy 35.324281 -190.634216) (xy 35.409701 -190.618248) (xy 35.49623 -190.61023)
			(xy 35.58313 -190.61023) (xy 35.669659 -190.618248) (xy 35.755079 -190.634216) (xy 35.838661 -190.657997)
			(xy 35.919693 -190.689389) (xy 35.997482 -190.728123) (xy 36.065119 -190.770002) (xy 39.396922 -190.770002)
			(xy 39.400993 -190.71438) (xy 39.413119 -190.659943) (xy 39.433042 -190.607852) (xy 39.460338 -190.559217)
			(xy 39.494424 -190.515074) (xy 39.534573 -190.476365) (xy 39.579931 -190.443914) (xy 39.629531 -190.418413)
			(xy 39.682315 -190.400406) (xy 39.737158 -190.390276) (xy 39.792892 -190.388239) (xy 39.848329 -190.394339)
			(xy 39.902286 -190.408445) (xy 39.953615 -190.430257) (xy 40.001221 -190.459311) (xy 40.044089 -190.494986)
			(xy 40.081306 -190.536523) (xy 40.112079 -190.583036) (xy 40.135751 -190.633533) (xy 40.151819 -190.68694)
			(xy 40.159939 -190.742116) (xy 40.160448 -190.770002) (xy 40.159939 -190.797888) (xy 40.151819 -190.853064)
			(xy 40.135751 -190.906471) (xy 40.112079 -190.956968) (xy 40.081306 -191.003481) (xy 40.044089 -191.045018)
			(xy 40.001221 -191.080693) (xy 39.953615 -191.109747) (xy 39.902286 -191.131559) (xy 39.848329 -191.145665)
			(xy 39.792892 -191.151765) (xy 39.737158 -191.149728) (xy 39.682315 -191.139598) (xy 39.629531 -191.121591)
			(xy 39.579931 -191.09609) (xy 39.534573 -191.063639) (xy 39.494424 -191.02493) (xy 39.460338 -190.980787)
			(xy 39.433042 -190.932152) (xy 39.413119 -190.880061) (xy 39.400993 -190.825624) (xy 39.396922 -190.770002)
			(xy 36.065119 -190.770002) (xy 36.071366 -190.77387) (xy 36.140713 -190.826239) (xy 36.204933 -190.884783)
			(xy 36.263477 -190.949003) (xy 36.315846 -191.01835) (xy 36.361593 -191.092234) (xy 36.400327 -191.170023)
			(xy 36.431719 -191.251055) (xy 36.4555 -191.334637) (xy 36.471468 -191.420057) (xy 36.479486 -191.506586)
			(xy 36.479988 -191.550036) (xy 36.479486 -191.593486) (xy 36.471468 -191.680015) (xy 36.4555 -191.765435)
			(xy 36.431719 -191.849017) (xy 36.400327 -191.930049) (xy 36.361593 -192.007838) (xy 36.315846 -192.081722)
			(xy 36.263477 -192.151069) (xy 36.204933 -192.215289) (xy 36.203848 -192.216278) (xy 40.721786 -192.216278)
			(xy 40.725857 -192.160656) (xy 40.737983 -192.106219) (xy 40.757906 -192.054128) (xy 40.785202 -192.005493)
			(xy 40.819288 -191.96135) (xy 40.859437 -191.922641) (xy 40.904795 -191.89019) (xy 40.954395 -191.864689)
			(xy 41.007179 -191.846682) (xy 41.062022 -191.836552) (xy 41.117756 -191.834515) (xy 41.173193 -191.840615)
			(xy 41.22715 -191.854721) (xy 41.278479 -191.876533) (xy 41.326085 -191.905587) (xy 41.368953 -191.941262)
			(xy 41.40617 -191.982799) (xy 41.436943 -192.029312) (xy 41.460615 -192.079809) (xy 41.476683 -192.133216)
			(xy 41.484803 -192.188392) (xy 41.485312 -192.216278) (xy 41.484803 -192.244164) (xy 41.476683 -192.29934)
			(xy 41.460615 -192.352747) (xy 41.436943 -192.403244) (xy 41.40617 -192.449757) (xy 41.368953 -192.491294)
			(xy 41.326085 -192.526969) (xy 41.278479 -192.556023) (xy 41.22715 -192.577835) (xy 41.173193 -192.591941)
			(xy 41.117756 -192.598041) (xy 41.062022 -192.596004) (xy 41.007179 -192.585874) (xy 40.954395 -192.567867)
			(xy 40.904795 -192.542366) (xy 40.859437 -192.509915) (xy 40.819288 -192.471206) (xy 40.785202 -192.427063)
			(xy 40.757906 -192.378428) (xy 40.737983 -192.326337) (xy 40.725857 -192.2719) (xy 40.721786 -192.216278)
			(xy 36.203848 -192.216278) (xy 36.140713 -192.273833) (xy 36.071366 -192.326202) (xy 35.997482 -192.371949)
			(xy 35.919693 -192.410683) (xy 35.838661 -192.442075) (xy 35.755079 -192.465856) (xy 35.669659 -192.481824)
			(xy 35.58313 -192.489842) (xy 35.49623 -192.489842) (xy 35.409701 -192.481824) (xy 35.324281 -192.465856)
			(xy 35.240699 -192.442075) (xy 35.159667 -192.410683) (xy 35.081878 -192.371949) (xy 35.007994 -192.326202)
			(xy 34.938647 -192.273833) (xy 34.874427 -192.215289) (xy 34.815883 -192.151069) (xy 34.763514 -192.081722)
			(xy 34.717767 -192.007838) (xy 34.679033 -191.930049) (xy 34.647641 -191.849017) (xy 34.62386 -191.765435)
			(xy 34.607892 -191.680015) (xy 34.599874 -191.593486) (xy 31.399486 -191.593486) (xy 31.391468 -191.680015)
			(xy 31.3755 -191.765435) (xy 31.351719 -191.849017) (xy 31.320327 -191.930049) (xy 31.281593 -192.007838)
			(xy 31.235846 -192.081722) (xy 31.183477 -192.151069) (xy 31.124933 -192.215289) (xy 31.060713 -192.273833)
			(xy 30.991366 -192.326202) (xy 30.917482 -192.371949) (xy 30.839693 -192.410683) (xy 30.758661 -192.442075)
			(xy 30.675079 -192.465856) (xy 30.589659 -192.481824) (xy 30.50313 -192.489842) (xy 30.41623 -192.489842)
			(xy 30.329701 -192.481824) (xy 30.244281 -192.465856) (xy 30.160699 -192.442075) (xy 30.079667 -192.410683)
			(xy 30.001878 -192.371949) (xy 29.927994 -192.326202) (xy 29.858647 -192.273833) (xy 29.794427 -192.215289)
			(xy 29.735883 -192.151069) (xy 29.683514 -192.081722) (xy 29.637767 -192.007838) (xy 29.599033 -191.930049)
			(xy 29.567641 -191.849017) (xy 29.54386 -191.765435) (xy 29.527892 -191.680015) (xy 29.519874 -191.593486)
			(xy 28.461716 -191.593486) (xy 28.461716 -194.133486) (xy 29.519874 -194.133486) (xy 29.519874 -194.046586)
			(xy 29.527892 -193.960057) (xy 29.54386 -193.874637) (xy 29.567641 -193.791055) (xy 29.599033 -193.710023)
			(xy 29.637767 -193.632234) (xy 29.683514 -193.55835) (xy 29.735883 -193.489003) (xy 29.794427 -193.424783)
			(xy 29.858647 -193.366239) (xy 29.927994 -193.31387) (xy 30.001878 -193.268123) (xy 30.079667 -193.229389)
			(xy 30.160699 -193.197997) (xy 30.244281 -193.174216) (xy 30.329701 -193.158248) (xy 30.41623 -193.15023)
			(xy 30.50313 -193.15023) (xy 30.589659 -193.158248) (xy 30.675079 -193.174216) (xy 30.758661 -193.197997)
			(xy 30.839693 -193.229389) (xy 30.917482 -193.268123) (xy 30.991366 -193.31387) (xy 31.060713 -193.366239)
			(xy 31.124933 -193.424783) (xy 31.183477 -193.489003) (xy 31.235846 -193.55835) (xy 31.281593 -193.632234)
			(xy 31.320327 -193.710023) (xy 31.351719 -193.791055) (xy 31.3755 -193.874637) (xy 31.391468 -193.960057)
			(xy 31.399486 -194.046586) (xy 31.399988 -194.090036) (xy 31.399486 -194.133486) (xy 34.599874 -194.133486)
			(xy 34.599874 -194.046586) (xy 34.607892 -193.960057) (xy 34.62386 -193.874637) (xy 34.647641 -193.791055)
			(xy 34.679033 -193.710023) (xy 34.717767 -193.632234) (xy 34.763514 -193.55835) (xy 34.815883 -193.489003)
			(xy 34.874427 -193.424783) (xy 34.938647 -193.366239) (xy 35.007994 -193.31387) (xy 35.081878 -193.268123)
			(xy 35.159667 -193.229389) (xy 35.240699 -193.197997) (xy 35.324281 -193.174216) (xy 35.409701 -193.158248)
			(xy 35.49623 -193.15023) (xy 35.58313 -193.15023) (xy 35.669659 -193.158248) (xy 35.755079 -193.174216)
			(xy 35.838661 -193.197997) (xy 35.919693 -193.229389) (xy 35.997482 -193.268123) (xy 36.071366 -193.31387)
			(xy 36.140713 -193.366239) (xy 36.204933 -193.424783) (xy 36.263477 -193.489003) (xy 36.315846 -193.55835)
			(xy 36.361593 -193.632234) (xy 36.400327 -193.710023) (xy 36.431719 -193.791055) (xy 36.4555 -193.874637)
			(xy 36.471468 -193.960057) (xy 36.479486 -194.046586) (xy 36.479988 -194.090036) (xy 36.479703 -194.114674)
			(xy 40.675558 -194.114674) (xy 40.679629 -194.059052) (xy 40.691755 -194.004615) (xy 40.711678 -193.952524)
			(xy 40.738974 -193.903889) (xy 40.77306 -193.859746) (xy 40.813209 -193.821037) (xy 40.858567 -193.788586)
			(xy 40.908167 -193.763085) (xy 40.960951 -193.745078) (xy 41.015794 -193.734948) (xy 41.071528 -193.732911)
			(xy 41.126965 -193.739011) (xy 41.180922 -193.753117) (xy 41.232251 -193.774929) (xy 41.279857 -193.803983)
			(xy 41.322725 -193.839658) (xy 41.359942 -193.881195) (xy 41.390715 -193.927708) (xy 41.414387 -193.978205)
			(xy 41.430455 -194.031612) (xy 41.438575 -194.086788) (xy 41.439084 -194.114674) (xy 41.438575 -194.14256)
			(xy 41.430455 -194.197736) (xy 41.414387 -194.251143) (xy 41.390715 -194.30164) (xy 41.359942 -194.348153)
			(xy 41.322725 -194.38969) (xy 41.279857 -194.425365) (xy 41.232251 -194.454419) (xy 41.180922 -194.476231)
			(xy 41.126965 -194.490337) (xy 41.071528 -194.496437) (xy 41.015794 -194.4944) (xy 40.960951 -194.48427)
			(xy 40.908167 -194.466263) (xy 40.858567 -194.440762) (xy 40.813209 -194.408311) (xy 40.77306 -194.369602)
			(xy 40.738974 -194.325459) (xy 40.711678 -194.276824) (xy 40.691755 -194.224733) (xy 40.679629 -194.170296)
			(xy 40.675558 -194.114674) (xy 36.479703 -194.114674) (xy 36.479486 -194.133486) (xy 36.471468 -194.220015)
			(xy 36.4555 -194.305435) (xy 36.431719 -194.389017) (xy 36.400327 -194.470049) (xy 36.361593 -194.547838)
			(xy 36.315846 -194.621722) (xy 36.263477 -194.691069) (xy 36.204933 -194.755289) (xy 36.140713 -194.813833)
			(xy 36.071366 -194.866202) (xy 35.997482 -194.911949) (xy 35.919693 -194.950683) (xy 35.840605 -194.981322)
			(xy 70.276718 -194.981322) (xy 70.280789 -194.9257) (xy 70.292915 -194.871263) (xy 70.312838 -194.819172)
			(xy 70.340134 -194.770537) (xy 70.37422 -194.726394) (xy 70.414369 -194.687685) (xy 70.459727 -194.655234)
			(xy 70.509327 -194.629733) (xy 70.562111 -194.611726) (xy 70.616954 -194.601596) (xy 70.672688 -194.599559)
			(xy 70.728125 -194.605659) (xy 70.782082 -194.619765) (xy 70.833411 -194.641577) (xy 70.881017 -194.670631)
			(xy 70.923885 -194.706306) (xy 70.961102 -194.747843) (xy 70.991875 -194.794356) (xy 71.015547 -194.844853)
			(xy 71.031615 -194.89826) (xy 71.039735 -194.953436) (xy 71.040244 -194.981322) (xy 71.43318 -194.981322)
			(xy 71.437251 -194.9257) (xy 71.449377 -194.871263) (xy 71.4693 -194.819172) (xy 71.496596 -194.770537)
			(xy 71.530682 -194.726394) (xy 71.570831 -194.687685) (xy 71.616189 -194.655234) (xy 71.665789 -194.629733)
			(xy 71.718573 -194.611726) (xy 71.773416 -194.601596) (xy 71.82915 -194.599559) (xy 71.884587 -194.605659)
			(xy 71.938544 -194.619765) (xy 71.989873 -194.641577) (xy 72.037479 -194.670631) (xy 72.080347 -194.706306)
			(xy 72.117564 -194.747843) (xy 72.148337 -194.794356) (xy 72.172009 -194.844853) (xy 72.188077 -194.89826)
			(xy 72.196197 -194.953436) (xy 72.196706 -194.981322) (xy 72.196197 -195.009208) (xy 72.188077 -195.064384)
			(xy 72.172009 -195.117791) (xy 72.148337 -195.168288) (xy 72.117564 -195.214801) (xy 72.080347 -195.256338)
			(xy 72.037479 -195.292013) (xy 71.989873 -195.321067) (xy 71.938544 -195.342879) (xy 71.884587 -195.356985)
			(xy 71.82915 -195.363085) (xy 71.773416 -195.361048) (xy 71.718573 -195.350918) (xy 71.665789 -195.332911)
			(xy 71.616189 -195.30741) (xy 71.570831 -195.274959) (xy 71.530682 -195.23625) (xy 71.496596 -195.192107)
			(xy 71.4693 -195.143472) (xy 71.449377 -195.091381) (xy 71.437251 -195.036944) (xy 71.43318 -194.981322)
			(xy 71.040244 -194.981322) (xy 71.039735 -195.009208) (xy 71.031615 -195.064384) (xy 71.015547 -195.117791)
			(xy 70.991875 -195.168288) (xy 70.961102 -195.214801) (xy 70.923885 -195.256338) (xy 70.881017 -195.292013)
			(xy 70.833411 -195.321067) (xy 70.782082 -195.342879) (xy 70.728125 -195.356985) (xy 70.672688 -195.363085)
			(xy 70.616954 -195.361048) (xy 70.562111 -195.350918) (xy 70.509327 -195.332911) (xy 70.459727 -195.30741)
			(xy 70.414369 -195.274959) (xy 70.37422 -195.23625) (xy 70.340134 -195.192107) (xy 70.312838 -195.143472)
			(xy 70.292915 -195.091381) (xy 70.280789 -195.036944) (xy 70.276718 -194.981322) (xy 35.840605 -194.981322)
			(xy 35.838661 -194.982075) (xy 35.755079 -195.005856) (xy 35.669659 -195.021824) (xy 35.58313 -195.029842)
			(xy 35.49623 -195.029842) (xy 35.409701 -195.021824) (xy 35.324281 -195.005856) (xy 35.240699 -194.982075)
			(xy 35.159667 -194.950683) (xy 35.081878 -194.911949) (xy 35.007994 -194.866202) (xy 34.938647 -194.813833)
			(xy 34.874427 -194.755289) (xy 34.815883 -194.691069) (xy 34.763514 -194.621722) (xy 34.717767 -194.547838)
			(xy 34.679033 -194.470049) (xy 34.647641 -194.389017) (xy 34.62386 -194.305435) (xy 34.607892 -194.220015)
			(xy 34.599874 -194.133486) (xy 31.399486 -194.133486) (xy 31.391468 -194.220015) (xy 31.3755 -194.305435)
			(xy 31.351719 -194.389017) (xy 31.320327 -194.470049) (xy 31.281593 -194.547838) (xy 31.235846 -194.621722)
			(xy 31.183477 -194.691069) (xy 31.124933 -194.755289) (xy 31.060713 -194.813833) (xy 30.991366 -194.866202)
			(xy 30.917482 -194.911949) (xy 30.839693 -194.950683) (xy 30.758661 -194.982075) (xy 30.675079 -195.005856)
			(xy 30.589659 -195.021824) (xy 30.50313 -195.029842) (xy 30.41623 -195.029842) (xy 30.329701 -195.021824)
			(xy 30.244281 -195.005856) (xy 30.160699 -194.982075) (xy 30.079667 -194.950683) (xy 30.001878 -194.911949)
			(xy 29.927994 -194.866202) (xy 29.858647 -194.813833) (xy 29.794427 -194.755289) (xy 29.735883 -194.691069)
			(xy 29.683514 -194.621722) (xy 29.637767 -194.547838) (xy 29.599033 -194.470049) (xy 29.567641 -194.389017)
			(xy 29.54386 -194.305435) (xy 29.527892 -194.220015) (xy 29.519874 -194.133486) (xy 28.461716 -194.133486)
			(xy 28.461716 -194.723766) (xy 28.462211 -194.747063) (xy 28.470651 -194.792886) (xy 28.487309 -194.8364)
			(xy 28.511626 -194.876145) (xy 28.542785 -194.910787) (xy 28.579741 -194.939163) (xy 28.621254 -194.960321)
			(xy 28.66593 -194.97355) (xy 28.689046 -194.976496) (xy 28.716117 -194.979023) (xy 28.769201 -194.990773)
			(xy 28.820079 -195.009937) (xy 28.867723 -195.03613) (xy 28.911166 -195.068819) (xy 28.94953 -195.107344)
			(xy 28.982037 -195.150924) (xy 29.008029 -195.198677) (xy 29.026981 -195.249636) (xy 29.038507 -195.302768)
			(xy 29.042376 -195.356999) (xy 29.038508 -195.41123) (xy 29.026981 -195.464363) (xy 29.00803 -195.515321)
			(xy 28.982038 -195.563074) (xy 28.949531 -195.606654) (xy 28.911168 -195.645179) (xy 28.867724 -195.677869)
			(xy 28.820081 -195.704062) (xy 28.769202 -195.723227) (xy 28.716119 -195.734976) (xy 28.689046 -195.73748)
			(xy 28.665938 -195.740452) (xy 28.621281 -195.753712) (xy 28.579787 -195.774885) (xy 28.542843 -195.803261)
			(xy 28.511686 -195.837892) (xy 28.487358 -195.877619) (xy 28.470673 -195.921113) (xy 28.46219 -195.966918)
			(xy 28.461716 -195.99021) (xy 28.461716 -196.673486) (xy 29.519874 -196.673486) (xy 29.519874 -196.586586)
			(xy 29.527892 -196.500057) (xy 29.54386 -196.414637) (xy 29.567641 -196.331055) (xy 29.599033 -196.250023)
			(xy 29.637767 -196.172234) (xy 29.683514 -196.09835) (xy 29.735883 -196.029003) (xy 29.794427 -195.964783)
			(xy 29.858647 -195.906239) (xy 29.927994 -195.85387) (xy 30.001878 -195.808123) (xy 30.079667 -195.769389)
			(xy 30.160699 -195.737997) (xy 30.244281 -195.714216) (xy 30.329701 -195.698248) (xy 30.41623 -195.69023)
			(xy 30.50313 -195.69023) (xy 30.589659 -195.698248) (xy 30.675079 -195.714216) (xy 30.758661 -195.737997)
			(xy 30.839693 -195.769389) (xy 30.917482 -195.808123) (xy 30.991366 -195.85387) (xy 31.060713 -195.906239)
			(xy 31.124933 -195.964783) (xy 31.183477 -196.029003) (xy 31.235846 -196.09835) (xy 31.281593 -196.172234)
			(xy 31.320327 -196.250023) (xy 31.351719 -196.331055) (xy 31.3755 -196.414637) (xy 31.391468 -196.500057)
			(xy 31.399486 -196.586586) (xy 31.399988 -196.630036) (xy 31.399486 -196.673486) (xy 34.599874 -196.673486)
			(xy 34.599874 -196.586586) (xy 34.607892 -196.500057) (xy 34.62386 -196.414637) (xy 34.647641 -196.331055)
			(xy 34.679033 -196.250023) (xy 34.717767 -196.172234) (xy 34.763514 -196.09835) (xy 34.815883 -196.029003)
			(xy 34.874427 -195.964783) (xy 34.938647 -195.906239) (xy 35.007994 -195.85387) (xy 35.081878 -195.808123)
			(xy 35.159667 -195.769389) (xy 35.240699 -195.737997) (xy 35.324281 -195.714216) (xy 35.409701 -195.698248)
			(xy 35.49623 -195.69023) (xy 35.58313 -195.69023) (xy 35.669659 -195.698248) (xy 35.755079 -195.714216)
			(xy 35.838661 -195.737997) (xy 35.919693 -195.769389) (xy 35.997482 -195.808123) (xy 36.026148 -195.825872)
			(xy 68.988938 -195.825872) (xy 68.993009 -195.77025) (xy 69.005135 -195.715813) (xy 69.025058 -195.663722)
			(xy 69.052354 -195.615087) (xy 69.08644 -195.570944) (xy 69.126589 -195.532235) (xy 69.171947 -195.499784)
			(xy 69.221547 -195.474283) (xy 69.274331 -195.456276) (xy 69.329174 -195.446146) (xy 69.384908 -195.444109)
			(xy 69.440345 -195.450209) (xy 69.494302 -195.464315) (xy 69.545631 -195.486127) (xy 69.593237 -195.515181)
			(xy 69.636105 -195.550856) (xy 69.673322 -195.592393) (xy 69.704095 -195.638906) (xy 69.727767 -195.689403)
			(xy 69.743835 -195.74281) (xy 69.751955 -195.797986) (xy 69.752464 -195.825872) (xy 69.751955 -195.853758)
			(xy 69.743835 -195.908934) (xy 69.727767 -195.962341) (xy 69.704095 -196.012838) (xy 69.673322 -196.059351)
			(xy 69.636105 -196.100888) (xy 69.593237 -196.136563) (xy 69.545631 -196.165617) (xy 69.494302 -196.187429)
			(xy 69.440345 -196.201535) (xy 69.384908 -196.207635) (xy 69.329174 -196.205598) (xy 69.274331 -196.195468)
			(xy 69.221547 -196.177461) (xy 69.171947 -196.15196) (xy 69.126589 -196.119509) (xy 69.08644 -196.0808)
			(xy 69.052354 -196.036657) (xy 69.025058 -195.988022) (xy 69.005135 -195.935931) (xy 68.993009 -195.881494)
			(xy 68.988938 -195.825872) (xy 36.026148 -195.825872) (xy 36.071366 -195.85387) (xy 36.140713 -195.906239)
			(xy 36.204933 -195.964783) (xy 36.263477 -196.029003) (xy 36.315846 -196.09835) (xy 36.361593 -196.172234)
			(xy 36.400327 -196.250023) (xy 36.431719 -196.331055) (xy 36.4555 -196.414637) (xy 36.471468 -196.500057)
			(xy 36.479486 -196.586586) (xy 36.479988 -196.630036) (xy 36.479486 -196.673486) (xy 36.471468 -196.760015)
			(xy 36.460439 -196.819012) (xy 40.545256 -196.819012) (xy 40.549327 -196.76339) (xy 40.561453 -196.708953)
			(xy 40.581376 -196.656862) (xy 40.608672 -196.608227) (xy 40.642758 -196.564084) (xy 40.682907 -196.525375)
			(xy 40.728265 -196.492924) (xy 40.777865 -196.467423) (xy 40.830649 -196.449416) (xy 40.885492 -196.439286)
			(xy 40.941226 -196.437249) (xy 40.996663 -196.443349) (xy 41.05062 -196.457455) (xy 41.101949 -196.479267)
			(xy 41.149555 -196.508321) (xy 41.192423 -196.543996) (xy 41.22964 -196.585533) (xy 41.260413 -196.632046)
			(xy 41.284085 -196.682543) (xy 41.300153 -196.73595) (xy 41.305187 -196.770159) (xy 47.903374 -196.770159)
			(xy 47.903374 -196.689049) (xy 47.911324 -196.60833) (xy 47.927147 -196.528779) (xy 47.950692 -196.451163)
			(xy 47.981731 -196.376227) (xy 48.019966 -196.304695) (xy 48.065028 -196.237255) (xy 48.116483 -196.174556)
			(xy 48.173836 -196.117203) (xy 48.236535 -196.065748) (xy 48.303975 -196.020686) (xy 48.375507 -195.982451)
			(xy 48.450443 -195.951412) (xy 48.528059 -195.927867) (xy 48.60761 -195.912044) (xy 48.688329 -195.904094)
			(xy 48.769439 -195.904094) (xy 48.850158 -195.912044) (xy 48.929709 -195.927867) (xy 49.007325 -195.951412)
			(xy 49.082261 -195.982451) (xy 49.153793 -196.020686) (xy 49.221233 -196.065748) (xy 49.283932 -196.117203)
			(xy 49.341285 -196.174556) (xy 49.39274 -196.237255) (xy 49.437802 -196.304695) (xy 49.476037 -196.376227)
			(xy 49.507076 -196.451163) (xy 49.530621 -196.528779) (xy 49.546444 -196.60833) (xy 49.554394 -196.689049)
			(xy 49.554892 -196.729604) (xy 49.554394 -196.770159) (xy 49.546444 -196.850878) (xy 49.530621 -196.930429)
			(xy 49.507076 -197.008045) (xy 49.476037 -197.082981) (xy 49.437802 -197.154513) (xy 49.39274 -197.221953)
			(xy 49.341285 -197.284652) (xy 49.283932 -197.342005) (xy 49.221233 -197.39346) (xy 49.153793 -197.438522)
			(xy 49.082261 -197.476757) (xy 49.007325 -197.507796) (xy 48.929709 -197.531341) (xy 48.850158 -197.547164)
			(xy 48.769439 -197.555114) (xy 48.688329 -197.555114) (xy 48.60761 -197.547164) (xy 48.528059 -197.531341)
			(xy 48.450443 -197.507796) (xy 48.375507 -197.476757) (xy 48.303975 -197.438522) (xy 48.236535 -197.39346)
			(xy 48.173836 -197.342005) (xy 48.116483 -197.284652) (xy 48.065028 -197.221953) (xy 48.019966 -197.154513)
			(xy 47.981731 -197.082981) (xy 47.950692 -197.008045) (xy 47.927147 -196.930429) (xy 47.911324 -196.850878)
			(xy 47.903374 -196.770159) (xy 41.305187 -196.770159) (xy 41.308273 -196.791126) (xy 41.308782 -196.819012)
			(xy 41.308273 -196.846898) (xy 41.300153 -196.902074) (xy 41.284085 -196.955481) (xy 41.260413 -197.005978)
			(xy 41.22964 -197.052491) (xy 41.192423 -197.094028) (xy 41.149555 -197.129703) (xy 41.101949 -197.158757)
			(xy 41.05062 -197.180569) (xy 40.996663 -197.194675) (xy 40.941226 -197.200775) (xy 40.885492 -197.198738)
			(xy 40.830649 -197.188608) (xy 40.777865 -197.170601) (xy 40.728265 -197.1451) (xy 40.682907 -197.112649)
			(xy 40.642758 -197.07394) (xy 40.608672 -197.029797) (xy 40.581376 -196.981162) (xy 40.561453 -196.929071)
			(xy 40.549327 -196.874634) (xy 40.545256 -196.819012) (xy 36.460439 -196.819012) (xy 36.4555 -196.845435)
			(xy 36.431719 -196.929017) (xy 36.400327 -197.010049) (xy 36.361593 -197.087838) (xy 36.315846 -197.161722)
			(xy 36.263477 -197.231069) (xy 36.204933 -197.295289) (xy 36.140713 -197.353833) (xy 36.071366 -197.406202)
			(xy 35.997482 -197.451949) (xy 35.919693 -197.490683) (xy 35.838661 -197.522075) (xy 35.755079 -197.545856)
			(xy 35.669659 -197.561824) (xy 35.58313 -197.569842) (xy 35.49623 -197.569842) (xy 35.409701 -197.561824)
			(xy 35.324281 -197.545856) (xy 35.240699 -197.522075) (xy 35.159667 -197.490683) (xy 35.081878 -197.451949)
			(xy 35.007994 -197.406202) (xy 34.938647 -197.353833) (xy 34.874427 -197.295289) (xy 34.815883 -197.231069)
			(xy 34.763514 -197.161722) (xy 34.717767 -197.087838) (xy 34.679033 -197.010049) (xy 34.647641 -196.929017)
			(xy 34.62386 -196.845435) (xy 34.607892 -196.760015) (xy 34.599874 -196.673486) (xy 31.399486 -196.673486)
			(xy 31.391468 -196.760015) (xy 31.3755 -196.845435) (xy 31.351719 -196.929017) (xy 31.320327 -197.010049)
			(xy 31.281593 -197.087838) (xy 31.235846 -197.161722) (xy 31.183477 -197.231069) (xy 31.124933 -197.295289)
			(xy 31.060713 -197.353833) (xy 30.991366 -197.406202) (xy 30.917482 -197.451949) (xy 30.839693 -197.490683)
			(xy 30.758661 -197.522075) (xy 30.675079 -197.545856) (xy 30.589659 -197.561824) (xy 30.50313 -197.569842)
			(xy 30.41623 -197.569842) (xy 30.329701 -197.561824) (xy 30.244281 -197.545856) (xy 30.160699 -197.522075)
			(xy 30.079667 -197.490683) (xy 30.001878 -197.451949) (xy 29.927994 -197.406202) (xy 29.858647 -197.353833)
			(xy 29.794427 -197.295289) (xy 29.735883 -197.231069) (xy 29.683514 -197.161722) (xy 29.637767 -197.087838)
			(xy 29.599033 -197.010049) (xy 29.567641 -196.929017) (xy 29.54386 -196.845435) (xy 29.527892 -196.760015)
			(xy 29.519874 -196.673486) (xy 28.461716 -196.673486) (xy 28.461716 -199.213486) (xy 29.519874 -199.213486)
			(xy 29.519874 -199.126586) (xy 29.527892 -199.040057) (xy 29.54386 -198.954637) (xy 29.567641 -198.871055)
			(xy 29.599033 -198.790023) (xy 29.637767 -198.712234) (xy 29.683514 -198.63835) (xy 29.735883 -198.569003)
			(xy 29.794427 -198.504783) (xy 29.858647 -198.446239) (xy 29.927994 -198.39387) (xy 30.001878 -198.348123)
			(xy 30.079667 -198.309389) (xy 30.160699 -198.277997) (xy 30.244281 -198.254216) (xy 30.329701 -198.238248)
			(xy 30.41623 -198.23023) (xy 30.50313 -198.23023) (xy 30.589659 -198.238248) (xy 30.675079 -198.254216)
			(xy 30.758661 -198.277997) (xy 30.839693 -198.309389) (xy 30.917482 -198.348123) (xy 30.991366 -198.39387)
			(xy 31.060713 -198.446239) (xy 31.124933 -198.504783) (xy 31.183477 -198.569003) (xy 31.235846 -198.63835)
			(xy 31.281593 -198.712234) (xy 31.320327 -198.790023) (xy 31.351719 -198.871055) (xy 31.3755 -198.954637)
			(xy 31.391468 -199.040057) (xy 31.399486 -199.126586) (xy 31.399988 -199.170036) (xy 31.399486 -199.213486)
			(xy 34.599874 -199.213486) (xy 34.599874 -199.126586) (xy 34.607892 -199.040057) (xy 34.62386 -198.954637)
			(xy 34.647641 -198.871055) (xy 34.679033 -198.790023) (xy 34.717767 -198.712234) (xy 34.763514 -198.63835)
			(xy 34.815883 -198.569003) (xy 34.874427 -198.504783) (xy 34.938647 -198.446239) (xy 35.007994 -198.39387)
			(xy 35.081878 -198.348123) (xy 35.159667 -198.309389) (xy 35.240699 -198.277997) (xy 35.324281 -198.254216)
			(xy 35.409701 -198.238248) (xy 35.49623 -198.23023) (xy 35.58313 -198.23023) (xy 35.669659 -198.238248)
			(xy 35.755079 -198.254216) (xy 35.838661 -198.277997) (xy 35.919693 -198.309389) (xy 35.997482 -198.348123)
			(xy 36.031891 -198.369428) (xy 39.992806 -198.369428) (xy 39.996877 -198.313806) (xy 40.009003 -198.259369)
			(xy 40.028926 -198.207278) (xy 40.056222 -198.158643) (xy 40.090308 -198.1145) (xy 40.130457 -198.075791)
			(xy 40.175815 -198.04334) (xy 40.225415 -198.017839) (xy 40.278199 -197.999832) (xy 40.333042 -197.989702)
			(xy 40.388776 -197.987665) (xy 40.444213 -197.993765) (xy 40.49817 -198.007871) (xy 40.549499 -198.029683)
			(xy 40.597105 -198.058737) (xy 40.639973 -198.094412) (xy 40.67719 -198.135949) (xy 40.707963 -198.182462)
			(xy 40.731635 -198.232959) (xy 40.747703 -198.286366) (xy 40.755823 -198.341542) (xy 40.756332 -198.369428)
			(xy 40.755823 -198.397314) (xy 40.747703 -198.45249) (xy 40.731635 -198.505897) (xy 40.707963 -198.556394)
			(xy 40.67719 -198.602907) (xy 40.639973 -198.644444) (xy 40.597105 -198.680119) (xy 40.549499 -198.709173)
			(xy 40.49817 -198.730985) (xy 40.444213 -198.745091) (xy 40.388776 -198.751191) (xy 40.333042 -198.749154)
			(xy 40.278199 -198.739024) (xy 40.225415 -198.721017) (xy 40.175815 -198.695516) (xy 40.130457 -198.663065)
			(xy 40.090308 -198.624356) (xy 40.056222 -198.580213) (xy 40.028926 -198.531578) (xy 40.009003 -198.479487)
			(xy 39.996877 -198.42505) (xy 39.992806 -198.369428) (xy 36.031891 -198.369428) (xy 36.071366 -198.39387)
			(xy 36.140713 -198.446239) (xy 36.204933 -198.504783) (xy 36.263477 -198.569003) (xy 36.315846 -198.63835)
			(xy 36.361593 -198.712234) (xy 36.400327 -198.790023) (xy 36.431719 -198.871055) (xy 36.4555 -198.954637)
			(xy 36.471468 -199.040057) (xy 36.479486 -199.126586) (xy 36.479988 -199.170036) (xy 36.479486 -199.213486)
			(xy 36.471468 -199.300015) (xy 36.4555 -199.385435) (xy 36.431719 -199.469017) (xy 36.400327 -199.550049)
			(xy 36.361593 -199.627838) (xy 36.315846 -199.701722) (xy 36.263477 -199.771069) (xy 36.204933 -199.835289)
			(xy 36.140713 -199.893833) (xy 36.071366 -199.946202) (xy 36.034352 -199.96912) (xy 40.017444 -199.96912)
			(xy 40.021515 -199.913498) (xy 40.033641 -199.859061) (xy 40.053564 -199.80697) (xy 40.08086 -199.758335)
			(xy 40.114946 -199.714192) (xy 40.155095 -199.675483) (xy 40.200453 -199.643032) (xy 40.250053 -199.617531)
			(xy 40.302837 -199.599524) (xy 40.35768 -199.589394) (xy 40.413414 -199.587357) (xy 40.468851 -199.593457)
			(xy 40.522808 -199.607563) (xy 40.574137 -199.629375) (xy 40.621743 -199.658429) (xy 40.664611 -199.694104)
			(xy 40.701828 -199.735641) (xy 40.732601 -199.782154) (xy 40.756273 -199.832651) (xy 40.772341 -199.886058)
			(xy 40.780461 -199.941234) (xy 40.78097 -199.96912) (xy 40.780461 -199.997006) (xy 40.772341 -200.052182)
			(xy 40.756273 -200.105589) (xy 40.732601 -200.156086) (xy 40.701828 -200.202599) (xy 40.664611 -200.244136)
			(xy 40.621743 -200.279811) (xy 40.574137 -200.308865) (xy 40.522808 -200.330677) (xy 40.468851 -200.344783)
			(xy 40.413414 -200.350883) (xy 40.35768 -200.348846) (xy 40.302837 -200.338716) (xy 40.250053 -200.320709)
			(xy 40.200453 -200.295208) (xy 40.155095 -200.262757) (xy 40.114946 -200.224048) (xy 40.08086 -200.179905)
			(xy 40.053564 -200.13127) (xy 40.033641 -200.079179) (xy 40.021515 -200.024742) (xy 40.017444 -199.96912)
			(xy 36.034352 -199.96912) (xy 35.997482 -199.991949) (xy 35.919693 -200.030683) (xy 35.838661 -200.062075)
			(xy 35.755079 -200.085856) (xy 35.669659 -200.101824) (xy 35.58313 -200.109842) (xy 35.49623 -200.109842)
			(xy 35.409701 -200.101824) (xy 35.324281 -200.085856) (xy 35.240699 -200.062075) (xy 35.159667 -200.030683)
			(xy 35.081878 -199.991949) (xy 35.007994 -199.946202) (xy 34.938647 -199.893833) (xy 34.874427 -199.835289)
			(xy 34.815883 -199.771069) (xy 34.763514 -199.701722) (xy 34.717767 -199.627838) (xy 34.679033 -199.550049)
			(xy 34.647641 -199.469017) (xy 34.62386 -199.385435) (xy 34.607892 -199.300015) (xy 34.599874 -199.213486)
			(xy 31.399486 -199.213486) (xy 31.391468 -199.300015) (xy 31.3755 -199.385435) (xy 31.351719 -199.469017)
			(xy 31.320327 -199.550049) (xy 31.281593 -199.627838) (xy 31.235846 -199.701722) (xy 31.183477 -199.771069)
			(xy 31.124933 -199.835289) (xy 31.060713 -199.893833) (xy 30.991366 -199.946202) (xy 30.917482 -199.991949)
			(xy 30.839693 -200.030683) (xy 30.758661 -200.062075) (xy 30.675079 -200.085856) (xy 30.589659 -200.101824)
			(xy 30.50313 -200.109842) (xy 30.41623 -200.109842) (xy 30.329701 -200.101824) (xy 30.244281 -200.085856)
			(xy 30.160699 -200.062075) (xy 30.079667 -200.030683) (xy 30.001878 -199.991949) (xy 29.927994 -199.946202)
			(xy 29.858647 -199.893833) (xy 29.794427 -199.835289) (xy 29.735883 -199.771069) (xy 29.683514 -199.701722)
			(xy 29.637767 -199.627838) (xy 29.599033 -199.550049) (xy 29.567641 -199.469017) (xy 29.54386 -199.385435)
			(xy 29.527892 -199.300015) (xy 29.519874 -199.213486) (xy 28.461716 -199.213486) (xy 28.461716 -201.13625)
			(xy 28.462211 -201.15919) (xy 28.470454 -201.204324) (xy 28.486662 -201.247246) (xy 28.510309 -201.286563)
			(xy 28.540628 -201.320998) (xy 28.576634 -201.349433) (xy 28.617158 -201.370945) (xy 28.660885 -201.384836)
			(xy 28.706395 -201.390655) (xy 28.75221 -201.388212) (xy 28.774644 -201.383392) (xy 28.800869 -201.376431)
			(xy 28.854634 -201.369134) (xy 28.90889 -201.369527) (xy 28.962543 -201.377603) (xy 29.014512 -201.393197)
			(xy 29.063747 -201.415996) (xy 29.109256 -201.44554) (xy 29.150121 -201.481233) (xy 29.185517 -201.522355)
			(xy 29.214731 -201.568076) (xy 29.237173 -201.617475) (xy 29.252392 -201.669555) (xy 29.260079 -201.723265)
			(xy 29.26008 -201.753486) (xy 29.519874 -201.753486) (xy 29.519874 -201.666586) (xy 29.527892 -201.580057)
			(xy 29.54386 -201.494637) (xy 29.567641 -201.411055) (xy 29.599033 -201.330023) (xy 29.637767 -201.252234)
			(xy 29.683514 -201.17835) (xy 29.735883 -201.109003) (xy 29.794427 -201.044783) (xy 29.858647 -200.986239)
			(xy 29.927994 -200.93387) (xy 30.001878 -200.888123) (xy 30.079667 -200.849389) (xy 30.160699 -200.817997)
			(xy 30.244281 -200.794216) (xy 30.329701 -200.778248) (xy 30.41623 -200.77023) (xy 30.50313 -200.77023)
			(xy 30.589659 -200.778248) (xy 30.675079 -200.794216) (xy 30.758661 -200.817997) (xy 30.839693 -200.849389)
			(xy 30.917482 -200.888123) (xy 30.991366 -200.93387) (xy 31.060713 -200.986239) (xy 31.124933 -201.044783)
			(xy 31.183477 -201.109003) (xy 31.235846 -201.17835) (xy 31.281593 -201.252234) (xy 31.320327 -201.330023)
			(xy 31.351719 -201.411055) (xy 31.3755 -201.494637) (xy 31.391468 -201.580057) (xy 31.399486 -201.666586)
			(xy 31.399988 -201.710036) (xy 31.399486 -201.753486) (xy 34.599874 -201.753486) (xy 34.599874 -201.666586)
			(xy 34.607892 -201.580057) (xy 34.62386 -201.494637) (xy 34.647641 -201.411055) (xy 34.679033 -201.330023)
			(xy 34.717767 -201.252234) (xy 34.763514 -201.17835) (xy 34.815883 -201.109003) (xy 34.874427 -201.044783)
			(xy 34.938647 -200.986239) (xy 35.007994 -200.93387) (xy 35.081878 -200.888123) (xy 35.159667 -200.849389)
			(xy 35.240699 -200.817997) (xy 35.324281 -200.794216) (xy 35.409701 -200.778248) (xy 35.49623 -200.77023)
			(xy 35.58313 -200.77023) (xy 35.669659 -200.778248) (xy 35.755079 -200.794216) (xy 35.838661 -200.817997)
			(xy 35.919693 -200.849389) (xy 35.997482 -200.888123) (xy 36.071366 -200.93387) (xy 36.140713 -200.986239)
			(xy 36.204933 -201.044783) (xy 36.263477 -201.109003) (xy 36.315846 -201.17835) (xy 36.361593 -201.252234)
			(xy 36.400327 -201.330023) (xy 36.431719 -201.411055) (xy 36.4555 -201.494637) (xy 36.471468 -201.580057)
			(xy 36.479486 -201.666586) (xy 36.479988 -201.710036) (xy 36.479486 -201.753486) (xy 36.471468 -201.840015)
			(xy 36.4555 -201.925435) (xy 36.431719 -202.009017) (xy 36.400327 -202.090049) (xy 36.361593 -202.167838)
			(xy 36.315846 -202.241722) (xy 36.263477 -202.311069) (xy 36.204933 -202.375289) (xy 36.140713 -202.433833)
			(xy 36.071366 -202.486202) (xy 35.997482 -202.531949) (xy 35.919693 -202.570683) (xy 35.838661 -202.602075)
			(xy 35.755079 -202.625856) (xy 35.669659 -202.641824) (xy 35.58313 -202.649842) (xy 35.49623 -202.649842)
			(xy 35.409701 -202.641824) (xy 35.324281 -202.625856) (xy 35.240699 -202.602075) (xy 35.159667 -202.570683)
			(xy 35.081878 -202.531949) (xy 35.007994 -202.486202) (xy 34.938647 -202.433833) (xy 34.874427 -202.375289)
			(xy 34.815883 -202.311069) (xy 34.763514 -202.241722) (xy 34.717767 -202.167838) (xy 34.679033 -202.090049)
			(xy 34.647641 -202.009017) (xy 34.62386 -201.925435) (xy 34.607892 -201.840015) (xy 34.599874 -201.753486)
			(xy 31.399486 -201.753486) (xy 31.391468 -201.840015) (xy 31.3755 -201.925435) (xy 31.351719 -202.009017)
			(xy 31.320327 -202.090049) (xy 31.281593 -202.167838) (xy 31.235846 -202.241722) (xy 31.183477 -202.311069)
			(xy 31.124933 -202.375289) (xy 31.060713 -202.433833) (xy 30.991366 -202.486202) (xy 30.917482 -202.531949)
			(xy 30.839693 -202.570683) (xy 30.758661 -202.602075) (xy 30.675079 -202.625856) (xy 30.589659 -202.641824)
			(xy 30.50313 -202.649842) (xy 30.41623 -202.649842) (xy 30.329701 -202.641824) (xy 30.244281 -202.625856)
			(xy 30.160699 -202.602075) (xy 30.079667 -202.570683) (xy 30.001878 -202.531949) (xy 29.927994 -202.486202)
			(xy 29.858647 -202.433833) (xy 29.794427 -202.375289) (xy 29.735883 -202.311069) (xy 29.683514 -202.241722)
			(xy 29.637767 -202.167838) (xy 29.599033 -202.090049) (xy 29.567641 -202.009017) (xy 29.54386 -201.925435)
			(xy 29.527892 -201.840015) (xy 29.519874 -201.753486) (xy 29.26008 -201.753486) (xy 29.26008 -201.777523)
			(xy 29.252394 -201.831234) (xy 29.237178 -201.883314) (xy 29.214737 -201.932713) (xy 29.185524 -201.978436)
			(xy 29.150129 -202.019558) (xy 29.109266 -202.055253) (xy 29.063758 -202.084798) (xy 29.014523 -202.107599)
			(xy 28.962555 -202.123195) (xy 28.908902 -202.131272) (xy 28.854646 -202.131667) (xy 28.800881 -202.124371)
			(xy 28.774644 -202.117452) (xy 28.752212 -202.112606) (xy 28.706388 -202.110144) (xy 28.660868 -202.11595)
			(xy 28.617129 -202.129835) (xy 28.576595 -202.151348) (xy 28.540583 -202.17979) (xy 28.510263 -202.214236)
			(xy 28.48662 -202.253566) (xy 28.470424 -202.296503) (xy 28.462201 -202.341649) (xy 28.461716 -202.364594)
			(xy 28.461716 -204.293486) (xy 29.519874 -204.293486) (xy 29.519874 -204.206586) (xy 29.527892 -204.120057)
			(xy 29.54386 -204.034637) (xy 29.567641 -203.951055) (xy 29.599033 -203.870023) (xy 29.637767 -203.792234)
			(xy 29.683514 -203.71835) (xy 29.735883 -203.649003) (xy 29.794427 -203.584783) (xy 29.858647 -203.526239)
			(xy 29.927994 -203.47387) (xy 30.001878 -203.428123) (xy 30.079667 -203.389389) (xy 30.160699 -203.357997)
			(xy 30.244281 -203.334216) (xy 30.329701 -203.318248) (xy 30.41623 -203.31023) (xy 30.50313 -203.31023)
			(xy 30.589659 -203.318248) (xy 30.675079 -203.334216) (xy 30.758661 -203.357997) (xy 30.839693 -203.389389)
			(xy 30.917482 -203.428123) (xy 30.991366 -203.47387) (xy 31.060713 -203.526239) (xy 31.124933 -203.584783)
			(xy 31.183477 -203.649003) (xy 31.235846 -203.71835) (xy 31.281593 -203.792234) (xy 31.320327 -203.870023)
			(xy 31.351719 -203.951055) (xy 31.3755 -204.034637) (xy 31.391468 -204.120057) (xy 31.399486 -204.206586)
			(xy 31.399988 -204.250036) (xy 31.399486 -204.293486) (xy 34.599874 -204.293486) (xy 34.599874 -204.206586)
			(xy 34.607892 -204.120057) (xy 34.62386 -204.034637) (xy 34.647641 -203.951055) (xy 34.679033 -203.870023)
			(xy 34.717767 -203.792234) (xy 34.763514 -203.71835) (xy 34.815883 -203.649003) (xy 34.874427 -203.584783)
			(xy 34.938647 -203.526239) (xy 35.007994 -203.47387) (xy 35.081878 -203.428123) (xy 35.159667 -203.389389)
			(xy 35.240699 -203.357997) (xy 35.324281 -203.334216) (xy 35.409701 -203.318248) (xy 35.49623 -203.31023)
			(xy 35.58313 -203.31023) (xy 35.669659 -203.318248) (xy 35.755079 -203.334216) (xy 35.838661 -203.357997)
			(xy 35.919693 -203.389389) (xy 35.997482 -203.428123) (xy 36.071366 -203.47387) (xy 36.140713 -203.526239)
			(xy 36.204933 -203.584783) (xy 36.263477 -203.649003) (xy 36.315846 -203.71835) (xy 36.361593 -203.792234)
			(xy 36.400327 -203.870023) (xy 36.431719 -203.951055) (xy 36.4555 -204.034637) (xy 36.471468 -204.120057)
			(xy 36.479486 -204.206586) (xy 36.479988 -204.250036) (xy 36.479486 -204.293486) (xy 36.471468 -204.380015)
			(xy 36.4555 -204.465435) (xy 36.431719 -204.549017) (xy 36.400327 -204.630049) (xy 36.361593 -204.707838)
			(xy 36.315846 -204.781722) (xy 36.263477 -204.851069) (xy 36.204933 -204.915289) (xy 36.140713 -204.973833)
			(xy 36.071366 -205.026202) (xy 35.997482 -205.071949) (xy 35.919693 -205.110683) (xy 35.838661 -205.142075)
			(xy 35.755079 -205.165856) (xy 35.669659 -205.181824) (xy 35.58313 -205.189842) (xy 35.49623 -205.189842)
			(xy 35.409701 -205.181824) (xy 35.324281 -205.165856) (xy 35.240699 -205.142075) (xy 35.159667 -205.110683)
			(xy 35.081878 -205.071949) (xy 35.007994 -205.026202) (xy 34.938647 -204.973833) (xy 34.874427 -204.915289)
			(xy 34.815883 -204.851069) (xy 34.763514 -204.781722) (xy 34.717767 -204.707838) (xy 34.679033 -204.630049)
			(xy 34.647641 -204.549017) (xy 34.62386 -204.465435) (xy 34.607892 -204.380015) (xy 34.599874 -204.293486)
			(xy 31.399486 -204.293486) (xy 31.391468 -204.380015) (xy 31.3755 -204.465435) (xy 31.351719 -204.549017)
			(xy 31.320327 -204.630049) (xy 31.281593 -204.707838) (xy 31.235846 -204.781722) (xy 31.183477 -204.851069)
			(xy 31.124933 -204.915289) (xy 31.060713 -204.973833) (xy 30.991366 -205.026202) (xy 30.917482 -205.071949)
			(xy 30.839693 -205.110683) (xy 30.758661 -205.142075) (xy 30.675079 -205.165856) (xy 30.589659 -205.181824)
			(xy 30.50313 -205.189842) (xy 30.41623 -205.189842) (xy 30.329701 -205.181824) (xy 30.244281 -205.165856)
			(xy 30.160699 -205.142075) (xy 30.079667 -205.110683) (xy 30.001878 -205.071949) (xy 29.927994 -205.026202)
			(xy 29.858647 -204.973833) (xy 29.794427 -204.915289) (xy 29.735883 -204.851069) (xy 29.683514 -204.781722)
			(xy 29.637767 -204.707838) (xy 29.599033 -204.630049) (xy 29.567641 -204.549017) (xy 29.54386 -204.465435)
			(xy 29.527892 -204.380015) (xy 29.519874 -204.293486) (xy 28.461716 -204.293486) (xy 28.461716 -206.833486)
			(xy 29.519874 -206.833486) (xy 29.519874 -206.746586) (xy 29.527892 -206.660057) (xy 29.54386 -206.574637)
			(xy 29.567641 -206.491055) (xy 29.599033 -206.410023) (xy 29.637767 -206.332234) (xy 29.683514 -206.25835)
			(xy 29.735883 -206.189003) (xy 29.794427 -206.124783) (xy 29.858647 -206.066239) (xy 29.927994 -206.01387)
			(xy 30.001878 -205.968123) (xy 30.079667 -205.929389) (xy 30.160699 -205.897997) (xy 30.244281 -205.874216)
			(xy 30.329701 -205.858248) (xy 30.41623 -205.85023) (xy 30.50313 -205.85023) (xy 30.589659 -205.858248)
			(xy 30.675079 -205.874216) (xy 30.758661 -205.897997) (xy 30.839693 -205.929389) (xy 30.917482 -205.968123)
			(xy 30.991366 -206.01387) (xy 31.060713 -206.066239) (xy 31.124933 -206.124783) (xy 31.183477 -206.189003)
			(xy 31.235846 -206.25835) (xy 31.281593 -206.332234) (xy 31.320327 -206.410023) (xy 31.351719 -206.491055)
			(xy 31.3755 -206.574637) (xy 31.391468 -206.660057) (xy 31.399486 -206.746586) (xy 31.399988 -206.790036)
			(xy 31.399486 -206.833486) (xy 34.599874 -206.833486) (xy 34.599874 -206.746586) (xy 34.607892 -206.660057)
			(xy 34.62386 -206.574637) (xy 34.647641 -206.491055) (xy 34.679033 -206.410023) (xy 34.717767 -206.332234)
			(xy 34.763514 -206.25835) (xy 34.815883 -206.189003) (xy 34.874427 -206.124783) (xy 34.938647 -206.066239)
			(xy 35.007994 -206.01387) (xy 35.081878 -205.968123) (xy 35.159667 -205.929389) (xy 35.240699 -205.897997)
			(xy 35.324281 -205.874216) (xy 35.409701 -205.858248) (xy 35.49623 -205.85023) (xy 35.58313 -205.85023)
			(xy 35.669659 -205.858248) (xy 35.755079 -205.874216) (xy 35.838661 -205.897997) (xy 35.919693 -205.929389)
			(xy 35.997482 -205.968123) (xy 36.071366 -206.01387) (xy 36.140713 -206.066239) (xy 36.204933 -206.124783)
			(xy 36.263477 -206.189003) (xy 36.315846 -206.25835) (xy 36.339633 -206.296768) (xy 64.56248 -206.296768)
			(xy 64.566551 -206.241146) (xy 64.578677 -206.186709) (xy 64.5986 -206.134618) (xy 64.625896 -206.085983)
			(xy 64.659982 -206.04184) (xy 64.700131 -206.003131) (xy 64.745489 -205.97068) (xy 64.795089 -205.945179)
			(xy 64.847873 -205.927172) (xy 64.902716 -205.917042) (xy 64.95845 -205.915005) (xy 65.013887 -205.921105)
			(xy 65.067844 -205.935211) (xy 65.119173 -205.957023) (xy 65.166779 -205.986077) (xy 65.209647 -206.021752)
			(xy 65.246864 -206.063289) (xy 65.277637 -206.109802) (xy 65.301309 -206.160299) (xy 65.317377 -206.213706)
			(xy 65.325497 -206.268882) (xy 65.326006 -206.296768) (xy 68.215762 -206.296768) (xy 68.219833 -206.241146)
			(xy 68.231959 -206.186709) (xy 68.251882 -206.134618) (xy 68.279178 -206.085983) (xy 68.313264 -206.04184)
			(xy 68.353413 -206.003131) (xy 68.398771 -205.97068) (xy 68.448371 -205.945179) (xy 68.501155 -205.927172)
			(xy 68.555998 -205.917042) (xy 68.611732 -205.915005) (xy 68.667169 -205.921105) (xy 68.721126 -205.935211)
			(xy 68.772455 -205.957023) (xy 68.820061 -205.986077) (xy 68.862929 -206.021752) (xy 68.900146 -206.063289)
			(xy 68.930919 -206.109802) (xy 68.954591 -206.160299) (xy 68.970659 -206.213706) (xy 68.978779 -206.268882)
			(xy 68.979288 -206.296768) (xy 68.978779 -206.324654) (xy 68.970659 -206.37983) (xy 68.954591 -206.433237)
			(xy 68.930919 -206.483734) (xy 68.900146 -206.530247) (xy 68.862929 -206.571784) (xy 68.820061 -206.607459)
			(xy 68.772455 -206.636513) (xy 68.721126 -206.658325) (xy 68.667169 -206.672431) (xy 68.611732 -206.678531)
			(xy 68.555998 -206.676494) (xy 68.501155 -206.666364) (xy 68.448371 -206.648357) (xy 68.398771 -206.622856)
			(xy 68.353413 -206.590405) (xy 68.313264 -206.551696) (xy 68.279178 -206.507553) (xy 68.251882 -206.458918)
			(xy 68.231959 -206.406827) (xy 68.219833 -206.35239) (xy 68.215762 -206.296768) (xy 65.326006 -206.296768)
			(xy 65.325497 -206.324654) (xy 65.317377 -206.37983) (xy 65.301309 -206.433237) (xy 65.277637 -206.483734)
			(xy 65.246864 -206.530247) (xy 65.209647 -206.571784) (xy 65.166779 -206.607459) (xy 65.119173 -206.636513)
			(xy 65.067844 -206.658325) (xy 65.013887 -206.672431) (xy 64.95845 -206.678531) (xy 64.902716 -206.676494)
			(xy 64.847873 -206.666364) (xy 64.795089 -206.648357) (xy 64.745489 -206.622856) (xy 64.700131 -206.590405)
			(xy 64.659982 -206.551696) (xy 64.625896 -206.507553) (xy 64.5986 -206.458918) (xy 64.578677 -206.406827)
			(xy 64.566551 -206.35239) (xy 64.56248 -206.296768) (xy 36.339633 -206.296768) (xy 36.361593 -206.332234)
			(xy 36.400327 -206.410023) (xy 36.431719 -206.491055) (xy 36.4555 -206.574637) (xy 36.471468 -206.660057)
			(xy 36.479486 -206.746586) (xy 36.479988 -206.790036) (xy 36.479486 -206.833486) (xy 36.471468 -206.920015)
			(xy 36.4555 -207.005435) (xy 36.431719 -207.089017) (xy 36.400327 -207.170049) (xy 36.361593 -207.247838)
			(xy 36.315846 -207.321722) (xy 36.263477 -207.391069) (xy 36.204933 -207.455289) (xy 36.140713 -207.513833)
			(xy 36.071366 -207.566202) (xy 35.997482 -207.611949) (xy 35.919693 -207.650683) (xy 35.838661 -207.682075)
			(xy 35.755079 -207.705856) (xy 35.669659 -207.721824) (xy 35.58313 -207.729842) (xy 35.49623 -207.729842)
			(xy 35.409701 -207.721824) (xy 35.324281 -207.705856) (xy 35.240699 -207.682075) (xy 35.159667 -207.650683)
			(xy 35.081878 -207.611949) (xy 35.007994 -207.566202) (xy 34.938647 -207.513833) (xy 34.874427 -207.455289)
			(xy 34.815883 -207.391069) (xy 34.763514 -207.321722) (xy 34.717767 -207.247838) (xy 34.679033 -207.170049)
			(xy 34.647641 -207.089017) (xy 34.62386 -207.005435) (xy 34.607892 -206.920015) (xy 34.599874 -206.833486)
			(xy 31.399486 -206.833486) (xy 31.391468 -206.920015) (xy 31.3755 -207.005435) (xy 31.351719 -207.089017)
			(xy 31.320327 -207.170049) (xy 31.281593 -207.247838) (xy 31.235846 -207.321722) (xy 31.183477 -207.391069)
			(xy 31.124933 -207.455289) (xy 31.060713 -207.513833) (xy 30.991366 -207.566202) (xy 30.917482 -207.611949)
			(xy 30.839693 -207.650683) (xy 30.758661 -207.682075) (xy 30.675079 -207.705856) (xy 30.589659 -207.721824)
			(xy 30.50313 -207.729842) (xy 30.41623 -207.729842) (xy 30.329701 -207.721824) (xy 30.244281 -207.705856)
			(xy 30.160699 -207.682075) (xy 30.079667 -207.650683) (xy 30.001878 -207.611949) (xy 29.927994 -207.566202)
			(xy 29.858647 -207.513833) (xy 29.794427 -207.455289) (xy 29.735883 -207.391069) (xy 29.683514 -207.321722)
			(xy 29.637767 -207.247838) (xy 29.599033 -207.170049) (xy 29.567641 -207.089017) (xy 29.54386 -207.005435)
			(xy 29.527892 -206.920015) (xy 29.519874 -206.833486) (xy 28.461716 -206.833486) (xy 28.461716 -209.373486)
			(xy 29.519874 -209.373486) (xy 29.519874 -209.286586) (xy 29.527892 -209.200057) (xy 29.54386 -209.114637)
			(xy 29.567641 -209.031055) (xy 29.599033 -208.950023) (xy 29.637767 -208.872234) (xy 29.683514 -208.79835)
			(xy 29.735883 -208.729003) (xy 29.794427 -208.664783) (xy 29.858647 -208.606239) (xy 29.927994 -208.55387)
			(xy 30.001878 -208.508123) (xy 30.079667 -208.469389) (xy 30.160699 -208.437997) (xy 30.244281 -208.414216)
			(xy 30.329701 -208.398248) (xy 30.41623 -208.39023) (xy 30.50313 -208.39023) (xy 30.589659 -208.398248)
			(xy 30.675079 -208.414216) (xy 30.758661 -208.437997) (xy 30.839693 -208.469389) (xy 30.917482 -208.508123)
			(xy 30.991366 -208.55387) (xy 31.060713 -208.606239) (xy 31.124933 -208.664783) (xy 31.183477 -208.729003)
			(xy 31.235846 -208.79835) (xy 31.281593 -208.872234) (xy 31.320327 -208.950023) (xy 31.351719 -209.031055)
			(xy 31.3755 -209.114637) (xy 31.391468 -209.200057) (xy 31.399486 -209.286586) (xy 31.399988 -209.330036)
			(xy 31.399486 -209.373486) (xy 34.599874 -209.373486) (xy 34.599874 -209.286586) (xy 34.607892 -209.200057)
			(xy 34.62386 -209.114637) (xy 34.647641 -209.031055) (xy 34.679033 -208.950023) (xy 34.717767 -208.872234)
			(xy 34.763514 -208.79835) (xy 34.815883 -208.729003) (xy 34.874427 -208.664783) (xy 34.938647 -208.606239)
			(xy 35.007994 -208.55387) (xy 35.081878 -208.508123) (xy 35.159667 -208.469389) (xy 35.240699 -208.437997)
			(xy 35.324281 -208.414216) (xy 35.409701 -208.398248) (xy 35.49623 -208.39023) (xy 35.58313 -208.39023)
			(xy 35.669659 -208.398248) (xy 35.755079 -208.414216) (xy 35.838661 -208.437997) (xy 35.919693 -208.469389)
			(xy 35.997482 -208.508123) (xy 36.071366 -208.55387) (xy 36.140713 -208.606239) (xy 36.204933 -208.664783)
			(xy 36.263477 -208.729003) (xy 36.315846 -208.79835) (xy 36.361593 -208.872234) (xy 36.400327 -208.950023)
			(xy 36.422714 -209.007811) (xy 38.847768 -209.007811) (xy 38.847768 -208.936489) (xy 38.855754 -208.865615)
			(xy 38.871624 -208.79608) (xy 38.895181 -208.72876) (xy 38.926126 -208.664501) (xy 38.964072 -208.60411)
			(xy 39.008541 -208.548348) (xy 39.058974 -208.497915) (xy 39.114736 -208.453446) (xy 39.175127 -208.4155)
			(xy 39.239386 -208.384555) (xy 39.306706 -208.360998) (xy 39.376241 -208.345128) (xy 39.447115 -208.337142)
			(xy 39.518437 -208.337142) (xy 39.589311 -208.345128) (xy 39.658846 -208.360998) (xy 39.726166 -208.384555)
			(xy 39.790425 -208.4155) (xy 39.850816 -208.453446) (xy 39.906578 -208.497915) (xy 39.957011 -208.548348)
			(xy 40.00148 -208.60411) (xy 40.039426 -208.664501) (xy 40.070371 -208.72876) (xy 40.093928 -208.79608)
			(xy 40.109798 -208.865615) (xy 40.117784 -208.936489) (xy 40.118284 -208.97215) (xy 40.117784 -209.007811)
			(xy 40.73448 -209.007811) (xy 40.73448 -208.936489) (xy 40.742466 -208.865615) (xy 40.758336 -208.79608)
			(xy 40.781893 -208.72876) (xy 40.812838 -208.664501) (xy 40.850784 -208.60411) (xy 40.895253 -208.548348)
			(xy 40.945686 -208.497915) (xy 41.001448 -208.453446) (xy 41.061839 -208.4155) (xy 41.126098 -208.384555)
			(xy 41.193418 -208.360998) (xy 41.262953 -208.345128) (xy 41.333827 -208.337142) (xy 41.405149 -208.337142)
			(xy 41.476023 -208.345128) (xy 41.545558 -208.360998) (xy 41.612878 -208.384555) (xy 41.677137 -208.4155)
			(xy 41.737528 -208.453446) (xy 41.79329 -208.497915) (xy 41.843723 -208.548348) (xy 41.888192 -208.60411)
			(xy 41.926138 -208.664501) (xy 41.957083 -208.72876) (xy 41.98064 -208.79608) (xy 41.99651 -208.865615)
			(xy 42.004496 -208.936489) (xy 42.004996 -208.97215) (xy 42.004496 -209.007811) (xy 42.975522 -209.007811)
			(xy 42.975522 -208.936489) (xy 42.983508 -208.865615) (xy 42.999378 -208.79608) (xy 43.022935 -208.72876)
			(xy 43.05388 -208.664501) (xy 43.091826 -208.60411) (xy 43.136295 -208.548348) (xy 43.186728 -208.497915)
			(xy 43.24249 -208.453446) (xy 43.302881 -208.4155) (xy 43.36714 -208.384555) (xy 43.43446 -208.360998)
			(xy 43.503995 -208.345128) (xy 43.574869 -208.337142) (xy 43.646191 -208.337142) (xy 43.717065 -208.345128)
			(xy 43.7866 -208.360998) (xy 43.85392 -208.384555) (xy 43.918179 -208.4155) (xy 43.97857 -208.453446)
			(xy 44.034332 -208.497915) (xy 44.084765 -208.548348) (xy 44.129234 -208.60411) (xy 44.16718 -208.664501)
			(xy 44.198125 -208.72876) (xy 44.221682 -208.79608) (xy 44.237552 -208.865615) (xy 44.245538 -208.936489)
			(xy 44.246038 -208.97215) (xy 44.245538 -209.007811) (xy 44.879506 -209.007811) (xy 44.879506 -208.936489)
			(xy 44.887492 -208.865615) (xy 44.903362 -208.79608) (xy 44.926919 -208.72876) (xy 44.957864 -208.664501)
			(xy 44.99581 -208.60411) (xy 45.040279 -208.548348) (xy 45.090712 -208.497915) (xy 45.146474 -208.453446)
			(xy 45.206865 -208.4155) (xy 45.271124 -208.384555) (xy 45.338444 -208.360998) (xy 45.407979 -208.345128)
			(xy 45.478853 -208.337142) (xy 45.550175 -208.337142) (xy 45.621049 -208.345128) (xy 45.690584 -208.360998)
			(xy 45.757904 -208.384555) (xy 45.822163 -208.4155) (xy 45.882554 -208.453446) (xy 45.938316 -208.497915)
			(xy 45.988749 -208.548348) (xy 46.033218 -208.60411) (xy 46.071164 -208.664501) (xy 46.102109 -208.72876)
			(xy 46.125666 -208.79608) (xy 46.141536 -208.865615) (xy 46.149522 -208.936489) (xy 46.150022 -208.97215)
			(xy 46.149522 -209.007811) (xy 46.141536 -209.078685) (xy 46.125666 -209.14822) (xy 46.107196 -209.201004)
			(xy 64.60058 -209.201004) (xy 64.604651 -209.145382) (xy 64.616777 -209.090945) (xy 64.6367 -209.038854)
			(xy 64.663996 -208.990219) (xy 64.698082 -208.946076) (xy 64.738231 -208.907367) (xy 64.783589 -208.874916)
			(xy 64.833189 -208.849415) (xy 64.885973 -208.831408) (xy 64.940816 -208.821278) (xy 64.99655 -208.819241)
			(xy 65.051987 -208.825341) (xy 65.105944 -208.839447) (xy 65.157273 -208.861259) (xy 65.204879 -208.890313)
			(xy 65.247747 -208.925988) (xy 65.284964 -208.967525) (xy 65.315737 -209.014038) (xy 65.339409 -209.064535)
			(xy 65.355477 -209.117942) (xy 65.363597 -209.173118) (xy 65.364106 -209.201004) (xy 65.363597 -209.22889)
			(xy 65.355477 -209.284066) (xy 65.339409 -209.337473) (xy 65.315737 -209.38797) (xy 65.284964 -209.434483)
			(xy 65.247747 -209.47602) (xy 65.204879 -209.511695) (xy 65.157273 -209.540749) (xy 65.105944 -209.562561)
			(xy 65.051987 -209.576667) (xy 64.99655 -209.582767) (xy 64.940816 -209.58073) (xy 64.885973 -209.5706)
			(xy 64.833189 -209.552593) (xy 64.783589 -209.527092) (xy 64.738231 -209.494641) (xy 64.698082 -209.455932)
			(xy 64.663996 -209.411789) (xy 64.6367 -209.363154) (xy 64.616777 -209.311063) (xy 64.604651 -209.256626)
			(xy 64.60058 -209.201004) (xy 46.107196 -209.201004) (xy 46.102109 -209.21554) (xy 46.071164 -209.279799)
			(xy 46.033218 -209.34019) (xy 45.988749 -209.395952) (xy 45.938316 -209.446385) (xy 45.882554 -209.490854)
			(xy 45.822163 -209.5288) (xy 45.757904 -209.559745) (xy 45.690584 -209.583302) (xy 45.621049 -209.599172)
			(xy 45.550175 -209.607158) (xy 45.478853 -209.607158) (xy 45.407979 -209.599172) (xy 45.338444 -209.583302)
			(xy 45.271124 -209.559745) (xy 45.206865 -209.5288) (xy 45.146474 -209.490854) (xy 45.090712 -209.446385)
			(xy 45.040279 -209.395952) (xy 44.99581 -209.34019) (xy 44.957864 -209.279799) (xy 44.926919 -209.21554)
			(xy 44.903362 -209.14822) (xy 44.887492 -209.078685) (xy 44.879506 -209.007811) (xy 44.245538 -209.007811)
			(xy 44.237552 -209.078685) (xy 44.221682 -209.14822) (xy 44.198125 -209.21554) (xy 44.16718 -209.279799)
			(xy 44.129234 -209.34019) (xy 44.084765 -209.395952) (xy 44.034332 -209.446385) (xy 43.97857 -209.490854)
			(xy 43.918179 -209.5288) (xy 43.85392 -209.559745) (xy 43.7866 -209.583302) (xy 43.717065 -209.599172)
			(xy 43.646191 -209.607158) (xy 43.574869 -209.607158) (xy 43.503995 -209.599172) (xy 43.43446 -209.583302)
			(xy 43.36714 -209.559745) (xy 43.302881 -209.5288) (xy 43.24249 -209.490854) (xy 43.186728 -209.446385)
			(xy 43.136295 -209.395952) (xy 43.091826 -209.34019) (xy 43.05388 -209.279799) (xy 43.022935 -209.21554)
			(xy 42.999378 -209.14822) (xy 42.983508 -209.078685) (xy 42.975522 -209.007811) (xy 42.004496 -209.007811)
			(xy 41.99651 -209.078685) (xy 41.98064 -209.14822) (xy 41.957083 -209.21554) (xy 41.926138 -209.279799)
			(xy 41.888192 -209.34019) (xy 41.843723 -209.395952) (xy 41.79329 -209.446385) (xy 41.737528 -209.490854)
			(xy 41.677137 -209.5288) (xy 41.612878 -209.559745) (xy 41.545558 -209.583302) (xy 41.476023 -209.599172)
			(xy 41.405149 -209.607158) (xy 41.333827 -209.607158) (xy 41.262953 -209.599172) (xy 41.193418 -209.583302)
			(xy 41.126098 -209.559745) (xy 41.061839 -209.5288) (xy 41.001448 -209.490854) (xy 40.945686 -209.446385)
			(xy 40.895253 -209.395952) (xy 40.850784 -209.34019) (xy 40.812838 -209.279799) (xy 40.781893 -209.21554)
			(xy 40.758336 -209.14822) (xy 40.742466 -209.078685) (xy 40.73448 -209.007811) (xy 40.117784 -209.007811)
			(xy 40.109798 -209.078685) (xy 40.093928 -209.14822) (xy 40.070371 -209.21554) (xy 40.039426 -209.279799)
			(xy 40.00148 -209.34019) (xy 39.957011 -209.395952) (xy 39.906578 -209.446385) (xy 39.850816 -209.490854)
			(xy 39.790425 -209.5288) (xy 39.726166 -209.559745) (xy 39.658846 -209.583302) (xy 39.589311 -209.599172)
			(xy 39.518437 -209.607158) (xy 39.447115 -209.607158) (xy 39.376241 -209.599172) (xy 39.306706 -209.583302)
			(xy 39.239386 -209.559745) (xy 39.175127 -209.5288) (xy 39.114736 -209.490854) (xy 39.058974 -209.446385)
			(xy 39.008541 -209.395952) (xy 38.964072 -209.34019) (xy 38.926126 -209.279799) (xy 38.895181 -209.21554)
			(xy 38.871624 -209.14822) (xy 38.855754 -209.078685) (xy 38.847768 -209.007811) (xy 36.422714 -209.007811)
			(xy 36.431719 -209.031055) (xy 36.4555 -209.114637) (xy 36.471468 -209.200057) (xy 36.479486 -209.286586)
			(xy 36.479988 -209.330036) (xy 36.479486 -209.373486) (xy 36.471468 -209.460015) (xy 36.4555 -209.545435)
			(xy 36.431719 -209.629017) (xy 36.400327 -209.710049) (xy 36.361593 -209.787838) (xy 36.315846 -209.861722)
			(xy 36.263477 -209.931069) (xy 36.204933 -209.995289) (xy 36.140713 -210.053833) (xy 36.080034 -210.099656)
			(xy 72.868035 -210.099656) (xy 72.872042 -209.896906) (xy 72.884055 -209.694472) (xy 72.904056 -209.492671)
			(xy 72.932015 -209.291817) (xy 72.967886 -209.092225) (xy 73.011615 -208.894206) (xy 73.063133 -208.698069)
			(xy 73.122359 -208.504121) (xy 73.189201 -208.312663) (xy 73.263555 -208.123996) (xy 73.345304 -207.938414)
			(xy 73.434322 -207.756206) (xy 73.530468 -207.577657) (xy 73.633593 -207.403046) (xy 73.743536 -207.232646)
			(xy 73.860125 -207.066722) (xy 73.983178 -206.905533) (xy 74.112503 -206.749332) (xy 74.247898 -206.598362)
			(xy 74.389151 -206.452858) (xy 74.536043 -206.313049) (xy 74.688343 -206.179152) (xy 74.845814 -206.051377)
			(xy 75.008211 -205.929922) (xy 75.175278 -205.814978) (xy 75.346757 -205.706724) (xy 75.522378 -205.605329)
			(xy 75.701868 -205.510951) (xy 75.884946 -205.423739) (xy 76.071327 -205.343827) (xy 76.26072 -205.27134)
			(xy 76.452828 -205.206393) (xy 76.647352 -205.149085) (xy 76.843988 -205.099508) (xy 77.04243 -205.057737)
			(xy 77.242367 -205.023839) (xy 77.443486 -204.997867) (xy 77.645475 -204.97986) (xy 77.848018 -204.969847)
			(xy 78.050798 -204.967843) (xy 78.253499 -204.973853) (xy 78.455804 -204.987865) (xy 78.657398 -205.00986)
			(xy 78.857965 -205.039801) (xy 79.057193 -205.077642) (xy 79.254771 -205.123325) (xy 79.450389 -205.176778)
			(xy 79.643743 -205.237917) (xy 79.834531 -205.306648) (xy 80.022454 -205.382862) (xy 80.20722 -205.466441)
			(xy 80.388539 -205.557254) (xy 80.56613 -205.655159) (xy 80.739713 -205.760004) (xy 80.909019 -205.871625)
			(xy 81.073784 -205.989847) (xy 81.233749 -206.114487) (xy 81.388665 -206.245348) (xy 81.53829 -206.382228)
			(xy 81.68239 -206.524912) (xy 81.820742 -206.673178) (xy 81.953127 -206.826794) (xy 82.079341 -206.985519)
			(xy 82.199185 -207.149108) (xy 82.312473 -207.317303) (xy 82.419028 -207.489842) (xy 82.518683 -207.666457)
			(xy 82.611283 -207.84687) (xy 82.696683 -208.030801) (xy 82.77475 -208.217962) (xy 82.845362 -208.408062)
			(xy 82.908408 -208.600802) (xy 82.963791 -208.795883) (xy 83.011423 -208.993) (xy 83.051231 -209.191844)
			(xy 83.083153 -209.392106) (xy 83.107137 -209.593472) (xy 83.123148 -209.795629) (xy 83.131159 -209.998261)
			(xy 83.13166 -210.099656) (xy 83.131159 -210.201051) (xy 83.123148 -210.403683) (xy 83.107137 -210.60584)
			(xy 83.083153 -210.807206) (xy 83.051231 -211.007468) (xy 83.011423 -211.206312) (xy 82.963791 -211.403429)
			(xy 82.908408 -211.59851) (xy 82.845362 -211.79125) (xy 82.77475 -211.98135) (xy 82.696683 -212.168511)
			(xy 82.611283 -212.352442) (xy 82.518683 -212.532855) (xy 82.419028 -212.70947) (xy 82.312473 -212.882009)
			(xy 82.199185 -213.050204) (xy 82.079341 -213.213793) (xy 81.953127 -213.372518) (xy 81.820742 -213.526134)
			(xy 81.68239 -213.6744) (xy 81.53829 -213.817084) (xy 81.388665 -213.953964) (xy 81.233749 -214.084825)
			(xy 81.073784 -214.209465) (xy 80.909019 -214.327687) (xy 80.739713 -214.439308) (xy 80.56613 -214.544153)
			(xy 80.388539 -214.642058) (xy 80.20722 -214.732871) (xy 80.022454 -214.81645) (xy 79.834531 -214.892664)
			(xy 79.643743 -214.961395) (xy 79.450389 -215.022534) (xy 79.254771 -215.075987) (xy 79.057193 -215.12167)
			(xy 78.857965 -215.159511) (xy 78.657398 -215.189452) (xy 78.455804 -215.211447) (xy 78.253499 -215.225459)
			(xy 78.050798 -215.231469) (xy 77.848018 -215.229465) (xy 77.645475 -215.219452) (xy 77.443486 -215.201445)
			(xy 77.242367 -215.175473) (xy 77.04243 -215.141575) (xy 76.843988 -215.099804) (xy 76.647352 -215.050227)
			(xy 76.452828 -214.992919) (xy 76.26072 -214.927972) (xy 76.071327 -214.855485) (xy 75.884946 -214.775573)
			(xy 75.701868 -214.688361) (xy 75.522378 -214.593983) (xy 75.346757 -214.492588) (xy 75.175278 -214.384334)
			(xy 75.008211 -214.26939) (xy 74.845814 -214.147935) (xy 74.688343 -214.02016) (xy 74.536043 -213.886263)
			(xy 74.389151 -213.746454) (xy 74.247898 -213.60095) (xy 74.112503 -213.44998) (xy 73.983178 -213.293779)
			(xy 73.860125 -213.13259) (xy 73.743536 -212.966666) (xy 73.633593 -212.796266) (xy 73.530468 -212.621655)
			(xy 73.434322 -212.443106) (xy 73.345304 -212.260898) (xy 73.263555 -212.075316) (xy 73.189201 -211.886649)
			(xy 73.122359 -211.695191) (xy 73.063133 -211.501243) (xy 73.011615 -211.305106) (xy 72.967886 -211.107087)
			(xy 72.932015 -210.907495) (xy 72.904056 -210.706641) (xy 72.884055 -210.50484) (xy 72.872042 -210.302406)
			(xy 72.868035 -210.099656) (xy 36.080034 -210.099656) (xy 36.071366 -210.106202) (xy 35.997482 -210.151949)
			(xy 35.919693 -210.190683) (xy 35.838661 -210.222075) (xy 35.755079 -210.245856) (xy 35.669659 -210.261824)
			(xy 35.58313 -210.269842) (xy 35.49623 -210.269842) (xy 35.409701 -210.261824) (xy 35.324281 -210.245856)
			(xy 35.240699 -210.222075) (xy 35.159667 -210.190683) (xy 35.081878 -210.151949) (xy 35.007994 -210.106202)
			(xy 34.938647 -210.053833) (xy 34.874427 -209.995289) (xy 34.815883 -209.931069) (xy 34.763514 -209.861722)
			(xy 34.717767 -209.787838) (xy 34.679033 -209.710049) (xy 34.647641 -209.629017) (xy 34.62386 -209.545435)
			(xy 34.607892 -209.460015) (xy 34.599874 -209.373486) (xy 31.399486 -209.373486) (xy 31.391468 -209.460015)
			(xy 31.3755 -209.545435) (xy 31.351719 -209.629017) (xy 31.320327 -209.710049) (xy 31.281593 -209.787838)
			(xy 31.235846 -209.861722) (xy 31.183477 -209.931069) (xy 31.124933 -209.995289) (xy 31.060713 -210.053833)
			(xy 30.991366 -210.106202) (xy 30.917482 -210.151949) (xy 30.839693 -210.190683) (xy 30.758661 -210.222075)
			(xy 30.675079 -210.245856) (xy 30.589659 -210.261824) (xy 30.50313 -210.269842) (xy 30.41623 -210.269842)
			(xy 30.329701 -210.261824) (xy 30.244281 -210.245856) (xy 30.160699 -210.222075) (xy 30.079667 -210.190683)
			(xy 30.001878 -210.151949) (xy 29.927994 -210.106202) (xy 29.858647 -210.053833) (xy 29.794427 -209.995289)
			(xy 29.735883 -209.931069) (xy 29.683514 -209.861722) (xy 29.637767 -209.787838) (xy 29.599033 -209.710049)
			(xy 29.567641 -209.629017) (xy 29.54386 -209.545435) (xy 29.527892 -209.460015) (xy 29.519874 -209.373486)
			(xy 28.461716 -209.373486) (xy 28.461716 -210.908747) (xy 38.847768 -210.908747) (xy 38.847768 -210.837425)
			(xy 38.855754 -210.766551) (xy 38.871624 -210.697016) (xy 38.895181 -210.629696) (xy 38.926126 -210.565437)
			(xy 38.964072 -210.505046) (xy 39.008541 -210.449284) (xy 39.058974 -210.398851) (xy 39.114736 -210.354382)
			(xy 39.175127 -210.316436) (xy 39.239386 -210.285491) (xy 39.306706 -210.261934) (xy 39.376241 -210.246064)
			(xy 39.447115 -210.238078) (xy 39.518437 -210.238078) (xy 39.589311 -210.246064) (xy 39.658846 -210.261934)
			(xy 39.726166 -210.285491) (xy 39.790425 -210.316436) (xy 39.850816 -210.354382) (xy 39.906578 -210.398851)
			(xy 39.957011 -210.449284) (xy 40.00148 -210.505046) (xy 40.039426 -210.565437) (xy 40.070371 -210.629696)
			(xy 40.093928 -210.697016) (xy 40.109798 -210.766551) (xy 40.117784 -210.837425) (xy 40.118284 -210.873086)
			(xy 40.117784 -210.908747) (xy 40.73448 -210.908747) (xy 40.73448 -210.837425) (xy 40.742466 -210.766551)
			(xy 40.758336 -210.697016) (xy 40.781893 -210.629696) (xy 40.812838 -210.565437) (xy 40.850784 -210.505046)
			(xy 40.895253 -210.449284) (xy 40.945686 -210.398851) (xy 41.001448 -210.354382) (xy 41.061839 -210.316436)
			(xy 41.126098 -210.285491) (xy 41.193418 -210.261934) (xy 41.262953 -210.246064) (xy 41.333827 -210.238078)
			(xy 41.405149 -210.238078) (xy 41.476023 -210.246064) (xy 41.545558 -210.261934) (xy 41.612878 -210.285491)
			(xy 41.677137 -210.316436) (xy 41.737528 -210.354382) (xy 41.79329 -210.398851) (xy 41.843723 -210.449284)
			(xy 41.888192 -210.505046) (xy 41.926138 -210.565437) (xy 41.957083 -210.629696) (xy 41.98064 -210.697016)
			(xy 41.99651 -210.766551) (xy 42.004496 -210.837425) (xy 42.004996 -210.873086) (xy 42.004496 -210.908747)
			(xy 42.975522 -210.908747) (xy 42.975522 -210.837425) (xy 42.983508 -210.766551) (xy 42.999378 -210.697016)
			(xy 43.022935 -210.629696) (xy 43.05388 -210.565437) (xy 43.091826 -210.505046) (xy 43.136295 -210.449284)
			(xy 43.186728 -210.398851) (xy 43.24249 -210.354382) (xy 43.302881 -210.316436) (xy 43.36714 -210.285491)
			(xy 43.43446 -210.261934) (xy 43.503995 -210.246064) (xy 43.574869 -210.238078) (xy 43.646191 -210.238078)
			(xy 43.717065 -210.246064) (xy 43.7866 -210.261934) (xy 43.85392 -210.285491) (xy 43.918179 -210.316436)
			(xy 43.97857 -210.354382) (xy 44.034332 -210.398851) (xy 44.084765 -210.449284) (xy 44.129234 -210.505046)
			(xy 44.16718 -210.565437) (xy 44.198125 -210.629696) (xy 44.221682 -210.697016) (xy 44.237552 -210.766551)
			(xy 44.245538 -210.837425) (xy 44.246038 -210.873086) (xy 44.245538 -210.908747) (xy 44.879506 -210.908747)
			(xy 44.879506 -210.837425) (xy 44.887492 -210.766551) (xy 44.903362 -210.697016) (xy 44.926919 -210.629696)
			(xy 44.957864 -210.565437) (xy 44.99581 -210.505046) (xy 45.040279 -210.449284) (xy 45.090712 -210.398851)
			(xy 45.146474 -210.354382) (xy 45.206865 -210.316436) (xy 45.271124 -210.285491) (xy 45.338444 -210.261934)
			(xy 45.407979 -210.246064) (xy 45.478853 -210.238078) (xy 45.550175 -210.238078) (xy 45.621049 -210.246064)
			(xy 45.690584 -210.261934) (xy 45.757904 -210.285491) (xy 45.822163 -210.316436) (xy 45.882554 -210.354382)
			(xy 45.938316 -210.398851) (xy 45.988749 -210.449284) (xy 46.033218 -210.505046) (xy 46.071164 -210.565437)
			(xy 46.102109 -210.629696) (xy 46.125666 -210.697016) (xy 46.141536 -210.766551) (xy 46.149522 -210.837425)
			(xy 46.150022 -210.873086) (xy 46.149522 -210.908747) (xy 46.141536 -210.979621) (xy 46.125666 -211.049156)
			(xy 46.102109 -211.116476) (xy 46.071164 -211.180735) (xy 46.033218 -211.241126) (xy 45.988749 -211.296888)
			(xy 45.938316 -211.347321) (xy 45.882554 -211.39179) (xy 45.822163 -211.429736) (xy 45.757904 -211.460681)
			(xy 45.690584 -211.484238) (xy 45.621049 -211.500108) (xy 45.550175 -211.508094) (xy 45.478853 -211.508094)
			(xy 45.407979 -211.500108) (xy 45.338444 -211.484238) (xy 45.271124 -211.460681) (xy 45.206865 -211.429736)
			(xy 45.146474 -211.39179) (xy 45.090712 -211.347321) (xy 45.040279 -211.296888) (xy 44.99581 -211.241126)
			(xy 44.957864 -211.180735) (xy 44.926919 -211.116476) (xy 44.903362 -211.049156) (xy 44.887492 -210.979621)
			(xy 44.879506 -210.908747) (xy 44.245538 -210.908747) (xy 44.237552 -210.979621) (xy 44.221682 -211.049156)
			(xy 44.198125 -211.116476) (xy 44.16718 -211.180735) (xy 44.129234 -211.241126) (xy 44.084765 -211.296888)
			(xy 44.034332 -211.347321) (xy 43.97857 -211.39179) (xy 43.918179 -211.429736) (xy 43.85392 -211.460681)
			(xy 43.7866 -211.484238) (xy 43.717065 -211.500108) (xy 43.646191 -211.508094) (xy 43.574869 -211.508094)
			(xy 43.503995 -211.500108) (xy 43.43446 -211.484238) (xy 43.36714 -211.460681) (xy 43.302881 -211.429736)
			(xy 43.24249 -211.39179) (xy 43.186728 -211.347321) (xy 43.136295 -211.296888) (xy 43.091826 -211.241126)
			(xy 43.05388 -211.180735) (xy 43.022935 -211.116476) (xy 42.999378 -211.049156) (xy 42.983508 -210.979621)
			(xy 42.975522 -210.908747) (xy 42.004496 -210.908747) (xy 41.99651 -210.979621) (xy 41.98064 -211.049156)
			(xy 41.957083 -211.116476) (xy 41.926138 -211.180735) (xy 41.888192 -211.241126) (xy 41.843723 -211.296888)
			(xy 41.79329 -211.347321) (xy 41.737528 -211.39179) (xy 41.677137 -211.429736) (xy 41.612878 -211.460681)
			(xy 41.545558 -211.484238) (xy 41.476023 -211.500108) (xy 41.405149 -211.508094) (xy 41.333827 -211.508094)
			(xy 41.262953 -211.500108) (xy 41.193418 -211.484238) (xy 41.126098 -211.460681) (xy 41.061839 -211.429736)
			(xy 41.001448 -211.39179) (xy 40.945686 -211.347321) (xy 40.895253 -211.296888) (xy 40.850784 -211.241126)
			(xy 40.812838 -211.180735) (xy 40.781893 -211.116476) (xy 40.758336 -211.049156) (xy 40.742466 -210.979621)
			(xy 40.73448 -210.908747) (xy 40.117784 -210.908747) (xy 40.109798 -210.979621) (xy 40.093928 -211.049156)
			(xy 40.070371 -211.116476) (xy 40.039426 -211.180735) (xy 40.00148 -211.241126) (xy 39.957011 -211.296888)
			(xy 39.906578 -211.347321) (xy 39.850816 -211.39179) (xy 39.790425 -211.429736) (xy 39.726166 -211.460681)
			(xy 39.658846 -211.484238) (xy 39.589311 -211.500108) (xy 39.518437 -211.508094) (xy 39.447115 -211.508094)
			(xy 39.376241 -211.500108) (xy 39.306706 -211.484238) (xy 39.239386 -211.460681) (xy 39.175127 -211.429736)
			(xy 39.114736 -211.39179) (xy 39.058974 -211.347321) (xy 39.008541 -211.296888) (xy 38.964072 -211.241126)
			(xy 38.926126 -211.180735) (xy 38.895181 -211.116476) (xy 38.871624 -211.049156) (xy 38.855754 -210.979621)
			(xy 38.847768 -210.908747) (xy 28.461716 -210.908747) (xy 28.461716 -211.913486) (xy 29.519874 -211.913486)
			(xy 29.519874 -211.826586) (xy 29.527892 -211.740057) (xy 29.54386 -211.654637) (xy 29.567641 -211.571055)
			(xy 29.599033 -211.490023) (xy 29.637767 -211.412234) (xy 29.683514 -211.33835) (xy 29.735883 -211.269003)
			(xy 29.794427 -211.204783) (xy 29.858647 -211.146239) (xy 29.927994 -211.09387) (xy 30.001878 -211.048123)
			(xy 30.079667 -211.009389) (xy 30.160699 -210.977997) (xy 30.244281 -210.954216) (xy 30.329701 -210.938248)
			(xy 30.41623 -210.93023) (xy 30.50313 -210.93023) (xy 30.589659 -210.938248) (xy 30.675079 -210.954216)
			(xy 30.758661 -210.977997) (xy 30.839693 -211.009389) (xy 30.917482 -211.048123) (xy 30.991366 -211.09387)
			(xy 31.060713 -211.146239) (xy 31.124933 -211.204783) (xy 31.183477 -211.269003) (xy 31.235846 -211.33835)
			(xy 31.281593 -211.412234) (xy 31.320327 -211.490023) (xy 31.351719 -211.571055) (xy 31.3755 -211.654637)
			(xy 31.391468 -211.740057) (xy 31.399486 -211.826586) (xy 31.399988 -211.870036) (xy 31.399486 -211.913486)
			(xy 34.599874 -211.913486) (xy 34.599874 -211.826586) (xy 34.607892 -211.740057) (xy 34.62386 -211.654637)
			(xy 34.647641 -211.571055) (xy 34.679033 -211.490023) (xy 34.717767 -211.412234) (xy 34.763514 -211.33835)
			(xy 34.815883 -211.269003) (xy 34.874427 -211.204783) (xy 34.938647 -211.146239) (xy 35.007994 -211.09387)
			(xy 35.081878 -211.048123) (xy 35.159667 -211.009389) (xy 35.240699 -210.977997) (xy 35.324281 -210.954216)
			(xy 35.409701 -210.938248) (xy 35.49623 -210.93023) (xy 35.58313 -210.93023) (xy 35.669659 -210.938248)
			(xy 35.755079 -210.954216) (xy 35.838661 -210.977997) (xy 35.919693 -211.009389) (xy 35.997482 -211.048123)
			(xy 36.071366 -211.09387) (xy 36.140713 -211.146239) (xy 36.204933 -211.204783) (xy 36.263477 -211.269003)
			(xy 36.315846 -211.33835) (xy 36.361593 -211.412234) (xy 36.400327 -211.490023) (xy 36.431719 -211.571055)
			(xy 36.4555 -211.654637) (xy 36.471468 -211.740057) (xy 36.479486 -211.826586) (xy 36.479988 -211.870036)
			(xy 36.479486 -211.913486) (xy 36.471468 -212.000015) (xy 36.4555 -212.085435) (xy 36.431719 -212.169017)
			(xy 36.400327 -212.250049) (xy 36.361593 -212.327838) (xy 36.315846 -212.401722) (xy 36.263477 -212.471069)
			(xy 36.204933 -212.535289) (xy 36.151634 -212.583877) (xy 38.847768 -212.583877) (xy 38.847768 -212.512555)
			(xy 38.855754 -212.441681) (xy 38.871624 -212.372146) (xy 38.895181 -212.304826) (xy 38.926126 -212.240567)
			(xy 38.964072 -212.180176) (xy 39.008541 -212.124414) (xy 39.058974 -212.073981) (xy 39.114736 -212.029512)
			(xy 39.175127 -211.991566) (xy 39.239386 -211.960621) (xy 39.306706 -211.937064) (xy 39.376241 -211.921194)
			(xy 39.447115 -211.913208) (xy 39.518437 -211.913208) (xy 39.589311 -211.921194) (xy 39.658846 -211.937064)
			(xy 39.726166 -211.960621) (xy 39.790425 -211.991566) (xy 39.850816 -212.029512) (xy 39.906578 -212.073981)
			(xy 39.957011 -212.124414) (xy 40.00148 -212.180176) (xy 40.039426 -212.240567) (xy 40.070371 -212.304826)
			(xy 40.093928 -212.372146) (xy 40.109798 -212.441681) (xy 40.117784 -212.512555) (xy 40.118284 -212.548216)
			(xy 40.117784 -212.583877) (xy 40.73448 -212.583877) (xy 40.73448 -212.512555) (xy 40.742466 -212.441681)
			(xy 40.758336 -212.372146) (xy 40.781893 -212.304826) (xy 40.812838 -212.240567) (xy 40.850784 -212.180176)
			(xy 40.895253 -212.124414) (xy 40.945686 -212.073981) (xy 41.001448 -212.029512) (xy 41.061839 -211.991566)
			(xy 41.126098 -211.960621) (xy 41.193418 -211.937064) (xy 41.262953 -211.921194) (xy 41.333827 -211.913208)
			(xy 41.405149 -211.913208) (xy 41.476023 -211.921194) (xy 41.545558 -211.937064) (xy 41.612878 -211.960621)
			(xy 41.677137 -211.991566) (xy 41.737528 -212.029512) (xy 41.79329 -212.073981) (xy 41.843723 -212.124414)
			(xy 41.888192 -212.180176) (xy 41.926138 -212.240567) (xy 41.957083 -212.304826) (xy 41.98064 -212.372146)
			(xy 41.99651 -212.441681) (xy 42.004496 -212.512555) (xy 42.004996 -212.548216) (xy 42.004496 -212.583877)
			(xy 42.975522 -212.583877) (xy 42.975522 -212.512555) (xy 42.983508 -212.441681) (xy 42.999378 -212.372146)
			(xy 43.022935 -212.304826) (xy 43.05388 -212.240567) (xy 43.091826 -212.180176) (xy 43.136295 -212.124414)
			(xy 43.186728 -212.073981) (xy 43.24249 -212.029512) (xy 43.302881 -211.991566) (xy 43.36714 -211.960621)
			(xy 43.43446 -211.937064) (xy 43.503995 -211.921194) (xy 43.574869 -211.913208) (xy 43.646191 -211.913208)
			(xy 43.717065 -211.921194) (xy 43.7866 -211.937064) (xy 43.85392 -211.960621) (xy 43.918179 -211.991566)
			(xy 43.97857 -212.029512) (xy 44.034332 -212.073981) (xy 44.084765 -212.124414) (xy 44.129234 -212.180176)
			(xy 44.16718 -212.240567) (xy 44.198125 -212.304826) (xy 44.221682 -212.372146) (xy 44.237552 -212.441681)
			(xy 44.245538 -212.512555) (xy 44.246038 -212.548216) (xy 44.245538 -212.583877) (xy 44.879506 -212.583877)
			(xy 44.879506 -212.512555) (xy 44.887492 -212.441681) (xy 44.903362 -212.372146) (xy 44.926919 -212.304826)
			(xy 44.957864 -212.240567) (xy 44.99581 -212.180176) (xy 45.040279 -212.124414) (xy 45.090712 -212.073981)
			(xy 45.146474 -212.029512) (xy 45.206865 -211.991566) (xy 45.271124 -211.960621) (xy 45.338444 -211.937064)
			(xy 45.407979 -211.921194) (xy 45.478853 -211.913208) (xy 45.550175 -211.913208) (xy 45.621049 -211.921194)
			(xy 45.690584 -211.937064) (xy 45.757904 -211.960621) (xy 45.822163 -211.991566) (xy 45.882554 -212.029512)
			(xy 45.938316 -212.073981) (xy 45.988749 -212.124414) (xy 46.033218 -212.180176) (xy 46.071164 -212.240567)
			(xy 46.102109 -212.304826) (xy 46.125666 -212.372146) (xy 46.141536 -212.441681) (xy 46.149522 -212.512555)
			(xy 46.150022 -212.548216) (xy 46.149522 -212.583877) (xy 46.141536 -212.654751) (xy 46.125666 -212.724286)
			(xy 46.102109 -212.791606) (xy 46.071164 -212.855865) (xy 46.033218 -212.916256) (xy 45.988749 -212.972018)
			(xy 45.938316 -213.022451) (xy 45.882554 -213.06692) (xy 45.822163 -213.104866) (xy 45.757904 -213.135811)
			(xy 45.690584 -213.159368) (xy 45.621049 -213.175238) (xy 45.550175 -213.183224) (xy 45.478853 -213.183224)
			(xy 45.407979 -213.175238) (xy 45.338444 -213.159368) (xy 45.271124 -213.135811) (xy 45.206865 -213.104866)
			(xy 45.146474 -213.06692) (xy 45.090712 -213.022451) (xy 45.040279 -212.972018) (xy 44.99581 -212.916256)
			(xy 44.957864 -212.855865) (xy 44.926919 -212.791606) (xy 44.903362 -212.724286) (xy 44.887492 -212.654751)
			(xy 44.879506 -212.583877) (xy 44.245538 -212.583877) (xy 44.237552 -212.654751) (xy 44.221682 -212.724286)
			(xy 44.198125 -212.791606) (xy 44.16718 -212.855865) (xy 44.129234 -212.916256) (xy 44.084765 -212.972018)
			(xy 44.034332 -213.022451) (xy 43.97857 -213.06692) (xy 43.918179 -213.104866) (xy 43.85392 -213.135811)
			(xy 43.7866 -213.159368) (xy 43.717065 -213.175238) (xy 43.646191 -213.183224) (xy 43.574869 -213.183224)
			(xy 43.503995 -213.175238) (xy 43.43446 -213.159368) (xy 43.36714 -213.135811) (xy 43.302881 -213.104866)
			(xy 43.24249 -213.06692) (xy 43.186728 -213.022451) (xy 43.136295 -212.972018) (xy 43.091826 -212.916256)
			(xy 43.05388 -212.855865) (xy 43.022935 -212.791606) (xy 42.999378 -212.724286) (xy 42.983508 -212.654751)
			(xy 42.975522 -212.583877) (xy 42.004496 -212.583877) (xy 41.99651 -212.654751) (xy 41.98064 -212.724286)
			(xy 41.957083 -212.791606) (xy 41.926138 -212.855865) (xy 41.888192 -212.916256) (xy 41.843723 -212.972018)
			(xy 41.79329 -213.022451) (xy 41.737528 -213.06692) (xy 41.677137 -213.104866) (xy 41.612878 -213.135811)
			(xy 41.545558 -213.159368) (xy 41.476023 -213.175238) (xy 41.405149 -213.183224) (xy 41.333827 -213.183224)
			(xy 41.262953 -213.175238) (xy 41.193418 -213.159368) (xy 41.126098 -213.135811) (xy 41.061839 -213.104866)
			(xy 41.001448 -213.06692) (xy 40.945686 -213.022451) (xy 40.895253 -212.972018) (xy 40.850784 -212.916256)
			(xy 40.812838 -212.855865) (xy 40.781893 -212.791606) (xy 40.758336 -212.724286) (xy 40.742466 -212.654751)
			(xy 40.73448 -212.583877) (xy 40.117784 -212.583877) (xy 40.109798 -212.654751) (xy 40.093928 -212.724286)
			(xy 40.070371 -212.791606) (xy 40.039426 -212.855865) (xy 40.00148 -212.916256) (xy 39.957011 -212.972018)
			(xy 39.906578 -213.022451) (xy 39.850816 -213.06692) (xy 39.790425 -213.104866) (xy 39.726166 -213.135811)
			(xy 39.658846 -213.159368) (xy 39.589311 -213.175238) (xy 39.518437 -213.183224) (xy 39.447115 -213.183224)
			(xy 39.376241 -213.175238) (xy 39.306706 -213.159368) (xy 39.239386 -213.135811) (xy 39.175127 -213.104866)
			(xy 39.114736 -213.06692) (xy 39.058974 -213.022451) (xy 39.008541 -212.972018) (xy 38.964072 -212.916256)
			(xy 38.926126 -212.855865) (xy 38.895181 -212.791606) (xy 38.871624 -212.724286) (xy 38.855754 -212.654751)
			(xy 38.847768 -212.583877) (xy 36.151634 -212.583877) (xy 36.140713 -212.593833) (xy 36.071366 -212.646202)
			(xy 35.997482 -212.691949) (xy 35.919693 -212.730683) (xy 35.838661 -212.762075) (xy 35.755079 -212.785856)
			(xy 35.669659 -212.801824) (xy 35.58313 -212.809842) (xy 35.49623 -212.809842) (xy 35.409701 -212.801824)
			(xy 35.324281 -212.785856) (xy 35.240699 -212.762075) (xy 35.159667 -212.730683) (xy 35.081878 -212.691949)
			(xy 35.007994 -212.646202) (xy 34.938647 -212.593833) (xy 34.874427 -212.535289) (xy 34.815883 -212.471069)
			(xy 34.763514 -212.401722) (xy 34.717767 -212.327838) (xy 34.679033 -212.250049) (xy 34.647641 -212.169017)
			(xy 34.62386 -212.085435) (xy 34.607892 -212.000015) (xy 34.599874 -211.913486) (xy 31.399486 -211.913486)
			(xy 31.391468 -212.000015) (xy 31.3755 -212.085435) (xy 31.351719 -212.169017) (xy 31.320327 -212.250049)
			(xy 31.281593 -212.327838) (xy 31.235846 -212.401722) (xy 31.183477 -212.471069) (xy 31.124933 -212.535289)
			(xy 31.060713 -212.593833) (xy 30.991366 -212.646202) (xy 30.917482 -212.691949) (xy 30.839693 -212.730683)
			(xy 30.758661 -212.762075) (xy 30.675079 -212.785856) (xy 30.589659 -212.801824) (xy 30.50313 -212.809842)
			(xy 30.41623 -212.809842) (xy 30.329701 -212.801824) (xy 30.244281 -212.785856) (xy 30.160699 -212.762075)
			(xy 30.079667 -212.730683) (xy 30.001878 -212.691949) (xy 29.927994 -212.646202) (xy 29.858647 -212.593833)
			(xy 29.794427 -212.535289) (xy 29.735883 -212.471069) (xy 29.683514 -212.401722) (xy 29.637767 -212.327838)
			(xy 29.599033 -212.250049) (xy 29.567641 -212.169017) (xy 29.54386 -212.085435) (xy 29.527892 -212.000015)
			(xy 29.519874 -211.913486) (xy 28.461716 -211.913486) (xy 28.461716 -214.453486) (xy 29.519874 -214.453486)
			(xy 29.519874 -214.366586) (xy 29.527892 -214.280057) (xy 29.54386 -214.194637) (xy 29.567641 -214.111055)
			(xy 29.599033 -214.030023) (xy 29.637767 -213.952234) (xy 29.683514 -213.87835) (xy 29.735883 -213.809003)
			(xy 29.794427 -213.744783) (xy 29.858647 -213.686239) (xy 29.927994 -213.63387) (xy 30.001878 -213.588123)
			(xy 30.079667 -213.549389) (xy 30.160699 -213.517997) (xy 30.244281 -213.494216) (xy 30.329701 -213.478248)
			(xy 30.41623 -213.47023) (xy 30.50313 -213.47023) (xy 30.589659 -213.478248) (xy 30.675079 -213.494216)
			(xy 30.758661 -213.517997) (xy 30.839693 -213.549389) (xy 30.917482 -213.588123) (xy 30.991366 -213.63387)
			(xy 31.060713 -213.686239) (xy 31.124933 -213.744783) (xy 31.183477 -213.809003) (xy 31.235846 -213.87835)
			(xy 31.281593 -213.952234) (xy 31.320327 -214.030023) (xy 31.351719 -214.111055) (xy 31.3755 -214.194637)
			(xy 31.391468 -214.280057) (xy 31.399486 -214.366586) (xy 31.399988 -214.410036) (xy 31.399486 -214.453486)
			(xy 34.599874 -214.453486) (xy 34.599874 -214.366586) (xy 34.607892 -214.280057) (xy 34.62386 -214.194637)
			(xy 34.647641 -214.111055) (xy 34.679033 -214.030023) (xy 34.717767 -213.952234) (xy 34.763514 -213.87835)
			(xy 34.815883 -213.809003) (xy 34.874427 -213.744783) (xy 34.938647 -213.686239) (xy 35.007994 -213.63387)
			(xy 35.081878 -213.588123) (xy 35.159667 -213.549389) (xy 35.240699 -213.517997) (xy 35.324281 -213.494216)
			(xy 35.409701 -213.478248) (xy 35.49623 -213.47023) (xy 35.58313 -213.47023) (xy 35.669659 -213.478248)
			(xy 35.755079 -213.494216) (xy 35.838661 -213.517997) (xy 35.919693 -213.549389) (xy 35.997482 -213.588123)
			(xy 36.071366 -213.63387) (xy 36.140713 -213.686239) (xy 36.204933 -213.744783) (xy 36.263477 -213.809003)
			(xy 36.315846 -213.87835) (xy 36.361593 -213.952234) (xy 36.400327 -214.030023) (xy 36.431719 -214.111055)
			(xy 36.4555 -214.194637) (xy 36.471468 -214.280057) (xy 36.479486 -214.366586) (xy 36.479988 -214.410036)
			(xy 36.479486 -214.453486) (xy 36.471468 -214.540015) (xy 36.46118 -214.595049) (xy 38.804334 -214.595049)
			(xy 38.804334 -214.523727) (xy 38.81232 -214.452853) (xy 38.82819 -214.383318) (xy 38.851747 -214.315998)
			(xy 38.882692 -214.251739) (xy 38.920638 -214.191348) (xy 38.965107 -214.135586) (xy 39.01554 -214.085153)
			(xy 39.071302 -214.040684) (xy 39.131693 -214.002738) (xy 39.195952 -213.971793) (xy 39.263272 -213.948236)
			(xy 39.332807 -213.932366) (xy 39.403681 -213.92438) (xy 39.475003 -213.92438) (xy 39.545877 -213.932366)
			(xy 39.615412 -213.948236) (xy 39.682732 -213.971793) (xy 39.746991 -214.002738) (xy 39.807382 -214.040684)
			(xy 39.863144 -214.085153) (xy 39.913577 -214.135586) (xy 39.958046 -214.191348) (xy 39.995992 -214.251739)
			(xy 40.026937 -214.315998) (xy 40.050494 -214.383318) (xy 40.066364 -214.452853) (xy 40.07435 -214.523727)
			(xy 40.07485 -214.559388) (xy 40.07435 -214.595049) (xy 40.691046 -214.595049) (xy 40.691046 -214.523727)
			(xy 40.699032 -214.452853) (xy 40.714902 -214.383318) (xy 40.738459 -214.315998) (xy 40.769404 -214.251739)
			(xy 40.80735 -214.191348) (xy 40.851819 -214.135586) (xy 40.902252 -214.085153) (xy 40.958014 -214.040684)
			(xy 41.018405 -214.002738) (xy 41.082664 -213.971793) (xy 41.149984 -213.948236) (xy 41.219519 -213.932366)
			(xy 41.290393 -213.92438) (xy 41.361715 -213.92438) (xy 41.432589 -213.932366) (xy 41.502124 -213.948236)
			(xy 41.569444 -213.971793) (xy 41.633703 -214.002738) (xy 41.694094 -214.040684) (xy 41.749856 -214.085153)
			(xy 41.800289 -214.135586) (xy 41.844758 -214.191348) (xy 41.882704 -214.251739) (xy 41.913649 -214.315998)
			(xy 41.937206 -214.383318) (xy 41.953076 -214.452853) (xy 41.961062 -214.523727) (xy 41.961562 -214.559388)
			(xy 41.961062 -214.595049) (xy 42.932088 -214.595049) (xy 42.932088 -214.523727) (xy 42.940074 -214.452853)
			(xy 42.955944 -214.383318) (xy 42.979501 -214.315998) (xy 43.010446 -214.251739) (xy 43.048392 -214.191348)
			(xy 43.092861 -214.135586) (xy 43.143294 -214.085153) (xy 43.199056 -214.040684) (xy 43.259447 -214.002738)
			(xy 43.323706 -213.971793) (xy 43.391026 -213.948236) (xy 43.460561 -213.932366) (xy 43.531435 -213.92438)
			(xy 43.602757 -213.92438) (xy 43.673631 -213.932366) (xy 43.743166 -213.948236) (xy 43.810486 -213.971793)
			(xy 43.874745 -214.002738) (xy 43.935136 -214.040684) (xy 43.990898 -214.085153) (xy 44.041331 -214.135586)
			(xy 44.0858 -214.191348) (xy 44.123746 -214.251739) (xy 44.154691 -214.315998) (xy 44.178248 -214.383318)
			(xy 44.194118 -214.452853) (xy 44.202104 -214.523727) (xy 44.202604 -214.559388) (xy 44.202104 -214.595049)
			(xy 44.836072 -214.595049) (xy 44.836072 -214.523727) (xy 44.844058 -214.452853) (xy 44.859928 -214.383318)
			(xy 44.883485 -214.315998) (xy 44.91443 -214.251739) (xy 44.952376 -214.191348) (xy 44.996845 -214.135586)
			(xy 45.047278 -214.085153) (xy 45.10304 -214.040684) (xy 45.163431 -214.002738) (xy 45.22769 -213.971793)
			(xy 45.29501 -213.948236) (xy 45.364545 -213.932366) (xy 45.435419 -213.92438) (xy 45.506741 -213.92438)
			(xy 45.577615 -213.932366) (xy 45.64715 -213.948236) (xy 45.71447 -213.971793) (xy 45.778729 -214.002738)
			(xy 45.83912 -214.040684) (xy 45.894882 -214.085153) (xy 45.945315 -214.135586) (xy 45.989784 -214.191348)
			(xy 46.02773 -214.251739) (xy 46.058675 -214.315998) (xy 46.082232 -214.383318) (xy 46.098102 -214.452853)
			(xy 46.106088 -214.523727) (xy 46.106588 -214.559388) (xy 46.106088 -214.595049) (xy 46.098102 -214.665923)
			(xy 46.082232 -214.735458) (xy 46.058675 -214.802778) (xy 46.02773 -214.867037) (xy 45.989784 -214.927428)
			(xy 45.945315 -214.98319) (xy 45.894882 -215.033623) (xy 45.83912 -215.078092) (xy 45.778729 -215.116038)
			(xy 45.71447 -215.146983) (xy 45.64715 -215.17054) (xy 45.577615 -215.18641) (xy 45.506741 -215.194396)
			(xy 45.435419 -215.194396) (xy 45.364545 -215.18641) (xy 45.29501 -215.17054) (xy 45.22769 -215.146983)
			(xy 45.163431 -215.116038) (xy 45.10304 -215.078092) (xy 45.047278 -215.033623) (xy 44.996845 -214.98319)
			(xy 44.952376 -214.927428) (xy 44.91443 -214.867037) (xy 44.883485 -214.802778) (xy 44.859928 -214.735458)
			(xy 44.844058 -214.665923) (xy 44.836072 -214.595049) (xy 44.202104 -214.595049) (xy 44.194118 -214.665923)
			(xy 44.178248 -214.735458) (xy 44.154691 -214.802778) (xy 44.123746 -214.867037) (xy 44.0858 -214.927428)
			(xy 44.041331 -214.98319) (xy 43.990898 -215.033623) (xy 43.935136 -215.078092) (xy 43.874745 -215.116038)
			(xy 43.810486 -215.146983) (xy 43.743166 -215.17054) (xy 43.673631 -215.18641) (xy 43.602757 -215.194396)
			(xy 43.531435 -215.194396) (xy 43.460561 -215.18641) (xy 43.391026 -215.17054) (xy 43.323706 -215.146983)
			(xy 43.259447 -215.116038) (xy 43.199056 -215.078092) (xy 43.143294 -215.033623) (xy 43.092861 -214.98319)
			(xy 43.048392 -214.927428) (xy 43.010446 -214.867037) (xy 42.979501 -214.802778) (xy 42.955944 -214.735458)
			(xy 42.940074 -214.665923) (xy 42.932088 -214.595049) (xy 41.961062 -214.595049) (xy 41.953076 -214.665923)
			(xy 41.937206 -214.735458) (xy 41.913649 -214.802778) (xy 41.882704 -214.867037) (xy 41.844758 -214.927428)
			(xy 41.800289 -214.98319) (xy 41.749856 -215.033623) (xy 41.694094 -215.078092) (xy 41.633703 -215.116038)
			(xy 41.569444 -215.146983) (xy 41.502124 -215.17054) (xy 41.432589 -215.18641) (xy 41.361715 -215.194396)
			(xy 41.290393 -215.194396) (xy 41.219519 -215.18641) (xy 41.149984 -215.17054) (xy 41.082664 -215.146983)
			(xy 41.018405 -215.116038) (xy 40.958014 -215.078092) (xy 40.902252 -215.033623) (xy 40.851819 -214.98319)
			(xy 40.80735 -214.927428) (xy 40.769404 -214.867037) (xy 40.738459 -214.802778) (xy 40.714902 -214.735458)
			(xy 40.699032 -214.665923) (xy 40.691046 -214.595049) (xy 40.07435 -214.595049) (xy 40.066364 -214.665923)
			(xy 40.050494 -214.735458) (xy 40.026937 -214.802778) (xy 39.995992 -214.867037) (xy 39.958046 -214.927428)
			(xy 39.913577 -214.98319) (xy 39.863144 -215.033623) (xy 39.807382 -215.078092) (xy 39.746991 -215.116038)
			(xy 39.682732 -215.146983) (xy 39.615412 -215.17054) (xy 39.545877 -215.18641) (xy 39.475003 -215.194396)
			(xy 39.403681 -215.194396) (xy 39.332807 -215.18641) (xy 39.263272 -215.17054) (xy 39.195952 -215.146983)
			(xy 39.131693 -215.116038) (xy 39.071302 -215.078092) (xy 39.01554 -215.033623) (xy 38.965107 -214.98319)
			(xy 38.920638 -214.927428) (xy 38.882692 -214.867037) (xy 38.851747 -214.802778) (xy 38.82819 -214.735458)
			(xy 38.81232 -214.665923) (xy 38.804334 -214.595049) (xy 36.46118 -214.595049) (xy 36.4555 -214.625435)
			(xy 36.431719 -214.709017) (xy 36.400327 -214.790049) (xy 36.361593 -214.867838) (xy 36.315846 -214.941722)
			(xy 36.263477 -215.011069) (xy 36.204933 -215.075289) (xy 36.140713 -215.133833) (xy 36.071366 -215.186202)
			(xy 35.997482 -215.231949) (xy 35.919693 -215.270683) (xy 35.838661 -215.302075) (xy 35.755079 -215.325856)
			(xy 35.669659 -215.341824) (xy 35.58313 -215.349842) (xy 35.49623 -215.349842) (xy 35.409701 -215.341824)
			(xy 35.324281 -215.325856) (xy 35.240699 -215.302075) (xy 35.159667 -215.270683) (xy 35.081878 -215.231949)
			(xy 35.007994 -215.186202) (xy 34.938647 -215.133833) (xy 34.874427 -215.075289) (xy 34.815883 -215.011069)
			(xy 34.763514 -214.941722) (xy 34.717767 -214.867838) (xy 34.679033 -214.790049) (xy 34.647641 -214.709017)
			(xy 34.62386 -214.625435) (xy 34.607892 -214.540015) (xy 34.599874 -214.453486) (xy 31.399486 -214.453486)
			(xy 31.391468 -214.540015) (xy 31.3755 -214.625435) (xy 31.351719 -214.709017) (xy 31.320327 -214.790049)
			(xy 31.281593 -214.867838) (xy 31.235846 -214.941722) (xy 31.183477 -215.011069) (xy 31.124933 -215.075289)
			(xy 31.060713 -215.133833) (xy 30.991366 -215.186202) (xy 30.917482 -215.231949) (xy 30.839693 -215.270683)
			(xy 30.758661 -215.302075) (xy 30.675079 -215.325856) (xy 30.589659 -215.341824) (xy 30.50313 -215.349842)
			(xy 30.41623 -215.349842) (xy 30.329701 -215.341824) (xy 30.244281 -215.325856) (xy 30.160699 -215.302075)
			(xy 30.079667 -215.270683) (xy 30.001878 -215.231949) (xy 29.927994 -215.186202) (xy 29.858647 -215.133833)
			(xy 29.794427 -215.075289) (xy 29.735883 -215.011069) (xy 29.683514 -214.941722) (xy 29.637767 -214.867838)
			(xy 29.599033 -214.790049) (xy 29.567641 -214.709017) (xy 29.54386 -214.625435) (xy 29.527892 -214.540015)
			(xy 29.519874 -214.453486) (xy 28.461716 -214.453486) (xy 28.461716 -216.993486) (xy 29.519874 -216.993486)
			(xy 29.519874 -216.906586) (xy 29.527892 -216.820057) (xy 29.54386 -216.734637) (xy 29.567641 -216.651055)
			(xy 29.599033 -216.570023) (xy 29.637767 -216.492234) (xy 29.683514 -216.41835) (xy 29.735883 -216.349003)
			(xy 29.794427 -216.284783) (xy 29.858647 -216.226239) (xy 29.927994 -216.17387) (xy 30.001878 -216.128123)
			(xy 30.079667 -216.089389) (xy 30.160699 -216.057997) (xy 30.244281 -216.034216) (xy 30.329701 -216.018248)
			(xy 30.41623 -216.01023) (xy 30.50313 -216.01023) (xy 30.589659 -216.018248) (xy 30.675079 -216.034216)
			(xy 30.758661 -216.057997) (xy 30.839693 -216.089389) (xy 30.917482 -216.128123) (xy 30.991366 -216.17387)
			(xy 31.060713 -216.226239) (xy 31.124933 -216.284783) (xy 31.183477 -216.349003) (xy 31.235846 -216.41835)
			(xy 31.281593 -216.492234) (xy 31.320327 -216.570023) (xy 31.351719 -216.651055) (xy 31.3755 -216.734637)
			(xy 31.391468 -216.820057) (xy 31.399486 -216.906586) (xy 31.399988 -216.950036) (xy 31.399486 -216.993486)
			(xy 34.599874 -216.993486) (xy 34.599874 -216.906586) (xy 34.607892 -216.820057) (xy 34.62386 -216.734637)
			(xy 34.647641 -216.651055) (xy 34.679033 -216.570023) (xy 34.717767 -216.492234) (xy 34.763514 -216.41835)
			(xy 34.815883 -216.349003) (xy 34.874427 -216.284783) (xy 34.938647 -216.226239) (xy 35.007994 -216.17387)
			(xy 35.081878 -216.128123) (xy 35.159667 -216.089389) (xy 35.240699 -216.057997) (xy 35.324281 -216.034216)
			(xy 35.409701 -216.018248) (xy 35.49623 -216.01023) (xy 35.58313 -216.01023) (xy 35.669659 -216.018248)
			(xy 35.755079 -216.034216) (xy 35.838661 -216.057997) (xy 35.919693 -216.089389) (xy 35.997482 -216.128123)
			(xy 36.071366 -216.17387) (xy 36.140713 -216.226239) (xy 36.204933 -216.284783) (xy 36.263477 -216.349003)
			(xy 36.315846 -216.41835) (xy 36.357467 -216.485571) (xy 38.804334 -216.485571) (xy 38.804334 -216.414249)
			(xy 38.81232 -216.343375) (xy 38.82819 -216.27384) (xy 38.851747 -216.20652) (xy 38.882692 -216.142261)
			(xy 38.920638 -216.08187) (xy 38.965107 -216.026108) (xy 39.01554 -215.975675) (xy 39.071302 -215.931206)
			(xy 39.131693 -215.89326) (xy 39.195952 -215.862315) (xy 39.263272 -215.838758) (xy 39.332807 -215.822888)
			(xy 39.403681 -215.814902) (xy 39.475003 -215.814902) (xy 39.545877 -215.822888) (xy 39.615412 -215.838758)
			(xy 39.682732 -215.862315) (xy 39.746991 -215.89326) (xy 39.807382 -215.931206) (xy 39.863144 -215.975675)
			(xy 39.913577 -216.026108) (xy 39.958046 -216.08187) (xy 39.995992 -216.142261) (xy 40.026937 -216.20652)
			(xy 40.050494 -216.27384) (xy 40.066364 -216.343375) (xy 40.07435 -216.414249) (xy 40.07485 -216.44991)
			(xy 40.07435 -216.485571) (xy 40.691046 -216.485571) (xy 40.691046 -216.414249) (xy 40.699032 -216.343375)
			(xy 40.714902 -216.27384) (xy 40.738459 -216.20652) (xy 40.769404 -216.142261) (xy 40.80735 -216.08187)
			(xy 40.851819 -216.026108) (xy 40.902252 -215.975675) (xy 40.958014 -215.931206) (xy 41.018405 -215.89326)
			(xy 41.082664 -215.862315) (xy 41.149984 -215.838758) (xy 41.219519 -215.822888) (xy 41.290393 -215.814902)
			(xy 41.361715 -215.814902) (xy 41.432589 -215.822888) (xy 41.502124 -215.838758) (xy 41.569444 -215.862315)
			(xy 41.633703 -215.89326) (xy 41.694094 -215.931206) (xy 41.749856 -215.975675) (xy 41.800289 -216.026108)
			(xy 41.844758 -216.08187) (xy 41.882704 -216.142261) (xy 41.913649 -216.20652) (xy 41.937206 -216.27384)
			(xy 41.953076 -216.343375) (xy 41.961062 -216.414249) (xy 41.961562 -216.44991) (xy 41.961062 -216.485571)
			(xy 42.932088 -216.485571) (xy 42.932088 -216.414249) (xy 42.940074 -216.343375) (xy 42.955944 -216.27384)
			(xy 42.979501 -216.20652) (xy 43.010446 -216.142261) (xy 43.048392 -216.08187) (xy 43.092861 -216.026108)
			(xy 43.143294 -215.975675) (xy 43.199056 -215.931206) (xy 43.259447 -215.89326) (xy 43.323706 -215.862315)
			(xy 43.391026 -215.838758) (xy 43.460561 -215.822888) (xy 43.531435 -215.814902) (xy 43.602757 -215.814902)
			(xy 43.673631 -215.822888) (xy 43.743166 -215.838758) (xy 43.810486 -215.862315) (xy 43.874745 -215.89326)
			(xy 43.935136 -215.931206) (xy 43.990898 -215.975675) (xy 44.041331 -216.026108) (xy 44.0858 -216.08187)
			(xy 44.123746 -216.142261) (xy 44.154691 -216.20652) (xy 44.178248 -216.27384) (xy 44.194118 -216.343375)
			(xy 44.202104 -216.414249) (xy 44.202604 -216.44991) (xy 44.202104 -216.485571) (xy 44.836072 -216.485571)
			(xy 44.836072 -216.414249) (xy 44.844058 -216.343375) (xy 44.859928 -216.27384) (xy 44.883485 -216.20652)
			(xy 44.91443 -216.142261) (xy 44.952376 -216.08187) (xy 44.996845 -216.026108) (xy 45.047278 -215.975675)
			(xy 45.10304 -215.931206) (xy 45.163431 -215.89326) (xy 45.22769 -215.862315) (xy 45.29501 -215.838758)
			(xy 45.364545 -215.822888) (xy 45.435419 -215.814902) (xy 45.506741 -215.814902) (xy 45.577615 -215.822888)
			(xy 45.64715 -215.838758) (xy 45.71447 -215.862315) (xy 45.778729 -215.89326) (xy 45.83912 -215.931206)
			(xy 45.894882 -215.975675) (xy 45.945315 -216.026108) (xy 45.989784 -216.08187) (xy 46.02773 -216.142261)
			(xy 46.058675 -216.20652) (xy 46.082232 -216.27384) (xy 46.098102 -216.343375) (xy 46.106088 -216.414249)
			(xy 46.106588 -216.44991) (xy 46.106088 -216.485571) (xy 46.098102 -216.556445) (xy 46.082232 -216.62598)
			(xy 46.058675 -216.6933) (xy 46.02773 -216.757559) (xy 45.989784 -216.81795) (xy 45.945315 -216.873712)
			(xy 45.894882 -216.924145) (xy 45.83912 -216.968614) (xy 45.778729 -217.00656) (xy 45.71447 -217.037505)
			(xy 45.64715 -217.061062) (xy 45.577615 -217.076932) (xy 45.506741 -217.084918) (xy 45.435419 -217.084918)
			(xy 45.364545 -217.076932) (xy 45.29501 -217.061062) (xy 45.22769 -217.037505) (xy 45.163431 -217.00656)
			(xy 45.10304 -216.968614) (xy 45.047278 -216.924145) (xy 44.996845 -216.873712) (xy 44.952376 -216.81795)
			(xy 44.91443 -216.757559) (xy 44.883485 -216.6933) (xy 44.859928 -216.62598) (xy 44.844058 -216.556445)
			(xy 44.836072 -216.485571) (xy 44.202104 -216.485571) (xy 44.194118 -216.556445) (xy 44.178248 -216.62598)
			(xy 44.154691 -216.6933) (xy 44.123746 -216.757559) (xy 44.0858 -216.81795) (xy 44.041331 -216.873712)
			(xy 43.990898 -216.924145) (xy 43.935136 -216.968614) (xy 43.874745 -217.00656) (xy 43.810486 -217.037505)
			(xy 43.743166 -217.061062) (xy 43.673631 -217.076932) (xy 43.602757 -217.084918) (xy 43.531435 -217.084918)
			(xy 43.460561 -217.076932) (xy 43.391026 -217.061062) (xy 43.323706 -217.037505) (xy 43.259447 -217.00656)
			(xy 43.199056 -216.968614) (xy 43.143294 -216.924145) (xy 43.092861 -216.873712) (xy 43.048392 -216.81795)
			(xy 43.010446 -216.757559) (xy 42.979501 -216.6933) (xy 42.955944 -216.62598) (xy 42.940074 -216.556445)
			(xy 42.932088 -216.485571) (xy 41.961062 -216.485571) (xy 41.953076 -216.556445) (xy 41.937206 -216.62598)
			(xy 41.913649 -216.6933) (xy 41.882704 -216.757559) (xy 41.844758 -216.81795) (xy 41.800289 -216.873712)
			(xy 41.749856 -216.924145) (xy 41.694094 -216.968614) (xy 41.633703 -217.00656) (xy 41.569444 -217.037505)
			(xy 41.502124 -217.061062) (xy 41.432589 -217.076932) (xy 41.361715 -217.084918) (xy 41.290393 -217.084918)
			(xy 41.219519 -217.076932) (xy 41.149984 -217.061062) (xy 41.082664 -217.037505) (xy 41.018405 -217.00656)
			(xy 40.958014 -216.968614) (xy 40.902252 -216.924145) (xy 40.851819 -216.873712) (xy 40.80735 -216.81795)
			(xy 40.769404 -216.757559) (xy 40.738459 -216.6933) (xy 40.714902 -216.62598) (xy 40.699032 -216.556445)
			(xy 40.691046 -216.485571) (xy 40.07435 -216.485571) (xy 40.066364 -216.556445) (xy 40.050494 -216.62598)
			(xy 40.026937 -216.6933) (xy 39.995992 -216.757559) (xy 39.958046 -216.81795) (xy 39.913577 -216.873712)
			(xy 39.863144 -216.924145) (xy 39.807382 -216.968614) (xy 39.746991 -217.00656) (xy 39.682732 -217.037505)
			(xy 39.615412 -217.061062) (xy 39.545877 -217.076932) (xy 39.475003 -217.084918) (xy 39.403681 -217.084918)
			(xy 39.332807 -217.076932) (xy 39.263272 -217.061062) (xy 39.195952 -217.037505) (xy 39.131693 -217.00656)
			(xy 39.071302 -216.968614) (xy 39.01554 -216.924145) (xy 38.965107 -216.873712) (xy 38.920638 -216.81795)
			(xy 38.882692 -216.757559) (xy 38.851747 -216.6933) (xy 38.82819 -216.62598) (xy 38.81232 -216.556445)
			(xy 38.804334 -216.485571) (xy 36.357467 -216.485571) (xy 36.361593 -216.492234) (xy 36.400327 -216.570023)
			(xy 36.431719 -216.651055) (xy 36.4555 -216.734637) (xy 36.471468 -216.820057) (xy 36.479486 -216.906586)
			(xy 36.479988 -216.950036) (xy 36.479486 -216.993486) (xy 36.471468 -217.080015) (xy 36.4555 -217.165435)
			(xy 36.431719 -217.249017) (xy 36.400327 -217.330049) (xy 36.361593 -217.407838) (xy 36.315846 -217.481722)
			(xy 36.282007 -217.526531) (xy 47.842414 -217.526531) (xy 47.842414 -217.445421) (xy 47.850364 -217.364702)
			(xy 47.866187 -217.285151) (xy 47.889732 -217.207535) (xy 47.920771 -217.132599) (xy 47.959006 -217.061067)
			(xy 48.004068 -216.993627) (xy 48.055523 -216.930928) (xy 48.112876 -216.873575) (xy 48.175575 -216.82212)
			(xy 48.243015 -216.777058) (xy 48.314547 -216.738823) (xy 48.389483 -216.707784) (xy 48.467099 -216.684239)
			(xy 48.54665 -216.668416) (xy 48.627369 -216.660466) (xy 48.708479 -216.660466) (xy 48.789198 -216.668416)
			(xy 48.868749 -216.684239) (xy 48.946365 -216.707784) (xy 49.021301 -216.738823) (xy 49.092833 -216.777058)
			(xy 49.160273 -216.82212) (xy 49.222972 -216.873575) (xy 49.280325 -216.930928) (xy 49.33178 -216.993627)
			(xy 49.376842 -217.061067) (xy 49.415077 -217.132599) (xy 49.446116 -217.207535) (xy 49.469661 -217.285151)
			(xy 49.485484 -217.364702) (xy 49.493434 -217.445421) (xy 49.493932 -217.485976) (xy 49.493434 -217.526531)
			(xy 49.485484 -217.60725) (xy 49.469661 -217.686801) (xy 49.446116 -217.764417) (xy 49.415077 -217.839353)
			(xy 49.376842 -217.910885) (xy 49.33178 -217.978325) (xy 49.280325 -218.041024) (xy 49.222972 -218.098377)
			(xy 49.160273 -218.149832) (xy 49.092833 -218.194894) (xy 49.021301 -218.233129) (xy 48.946365 -218.264168)
			(xy 48.868749 -218.287713) (xy 48.789198 -218.303536) (xy 48.708479 -218.311486) (xy 48.627369 -218.311486)
			(xy 48.54665 -218.303536) (xy 48.467099 -218.287713) (xy 48.389483 -218.264168) (xy 48.314547 -218.233129)
			(xy 48.243015 -218.194894) (xy 48.175575 -218.149832) (xy 48.112876 -218.098377) (xy 48.055523 -218.041024)
			(xy 48.004068 -217.978325) (xy 47.959006 -217.910885) (xy 47.920771 -217.839353) (xy 47.889732 -217.764417)
			(xy 47.866187 -217.686801) (xy 47.850364 -217.60725) (xy 47.842414 -217.526531) (xy 36.282007 -217.526531)
			(xy 36.263477 -217.551069) (xy 36.204933 -217.615289) (xy 36.140713 -217.673833) (xy 36.071366 -217.726202)
			(xy 35.997482 -217.771949) (xy 35.919693 -217.810683) (xy 35.838661 -217.842075) (xy 35.755079 -217.865856)
			(xy 35.669659 -217.881824) (xy 35.58313 -217.889842) (xy 35.49623 -217.889842) (xy 35.409701 -217.881824)
			(xy 35.324281 -217.865856) (xy 35.240699 -217.842075) (xy 35.159667 -217.810683) (xy 35.081878 -217.771949)
			(xy 35.007994 -217.726202) (xy 34.938647 -217.673833) (xy 34.874427 -217.615289) (xy 34.815883 -217.551069)
			(xy 34.763514 -217.481722) (xy 34.717767 -217.407838) (xy 34.679033 -217.330049) (xy 34.647641 -217.249017)
			(xy 34.62386 -217.165435) (xy 34.607892 -217.080015) (xy 34.599874 -216.993486) (xy 31.399486 -216.993486)
			(xy 31.391468 -217.080015) (xy 31.3755 -217.165435) (xy 31.351719 -217.249017) (xy 31.320327 -217.330049)
			(xy 31.281593 -217.407838) (xy 31.235846 -217.481722) (xy 31.183477 -217.551069) (xy 31.124933 -217.615289)
			(xy 31.060713 -217.673833) (xy 30.991366 -217.726202) (xy 30.917482 -217.771949) (xy 30.839693 -217.810683)
			(xy 30.758661 -217.842075) (xy 30.675079 -217.865856) (xy 30.589659 -217.881824) (xy 30.50313 -217.889842)
			(xy 30.41623 -217.889842) (xy 30.329701 -217.881824) (xy 30.244281 -217.865856) (xy 30.160699 -217.842075)
			(xy 30.079667 -217.810683) (xy 30.001878 -217.771949) (xy 29.927994 -217.726202) (xy 29.858647 -217.673833)
			(xy 29.794427 -217.615289) (xy 29.735883 -217.551069) (xy 29.683514 -217.481722) (xy 29.637767 -217.407838)
			(xy 29.599033 -217.330049) (xy 29.567641 -217.249017) (xy 29.54386 -217.165435) (xy 29.527892 -217.080015)
			(xy 29.519874 -216.993486) (xy 28.461716 -216.993486) (xy 28.461716 -218.526715) (xy 38.804334 -218.526715)
			(xy 38.804334 -218.455393) (xy 38.81232 -218.384519) (xy 38.82819 -218.314984) (xy 38.851747 -218.247664)
			(xy 38.882692 -218.183405) (xy 38.920638 -218.123014) (xy 38.965107 -218.067252) (xy 39.01554 -218.016819)
			(xy 39.071302 -217.97235) (xy 39.131693 -217.934404) (xy 39.195952 -217.903459) (xy 39.263272 -217.879902)
			(xy 39.332807 -217.864032) (xy 39.403681 -217.856046) (xy 39.475003 -217.856046) (xy 39.545877 -217.864032)
			(xy 39.615412 -217.879902) (xy 39.682732 -217.903459) (xy 39.746991 -217.934404) (xy 39.807382 -217.97235)
			(xy 39.863144 -218.016819) (xy 39.913577 -218.067252) (xy 39.958046 -218.123014) (xy 39.995992 -218.183405)
			(xy 40.026937 -218.247664) (xy 40.050494 -218.314984) (xy 40.066364 -218.384519) (xy 40.07435 -218.455393)
			(xy 40.07485 -218.491054) (xy 40.07435 -218.526715) (xy 40.691046 -218.526715) (xy 40.691046 -218.455393)
			(xy 40.699032 -218.384519) (xy 40.714902 -218.314984) (xy 40.738459 -218.247664) (xy 40.769404 -218.183405)
			(xy 40.80735 -218.123014) (xy 40.851819 -218.067252) (xy 40.902252 -218.016819) (xy 40.958014 -217.97235)
			(xy 41.018405 -217.934404) (xy 41.082664 -217.903459) (xy 41.149984 -217.879902) (xy 41.219519 -217.864032)
			(xy 41.290393 -217.856046) (xy 41.361715 -217.856046) (xy 41.432589 -217.864032) (xy 41.502124 -217.879902)
			(xy 41.569444 -217.903459) (xy 41.633703 -217.934404) (xy 41.694094 -217.97235) (xy 41.749856 -218.016819)
			(xy 41.800289 -218.067252) (xy 41.844758 -218.123014) (xy 41.882704 -218.183405) (xy 41.913649 -218.247664)
			(xy 41.937206 -218.314984) (xy 41.953076 -218.384519) (xy 41.961062 -218.455393) (xy 41.961562 -218.491054)
			(xy 41.961062 -218.526715) (xy 42.932088 -218.526715) (xy 42.932088 -218.455393) (xy 42.940074 -218.384519)
			(xy 42.955944 -218.314984) (xy 42.979501 -218.247664) (xy 43.010446 -218.183405) (xy 43.048392 -218.123014)
			(xy 43.092861 -218.067252) (xy 43.143294 -218.016819) (xy 43.199056 -217.97235) (xy 43.259447 -217.934404)
			(xy 43.323706 -217.903459) (xy 43.391026 -217.879902) (xy 43.460561 -217.864032) (xy 43.531435 -217.856046)
			(xy 43.602757 -217.856046) (xy 43.673631 -217.864032) (xy 43.743166 -217.879902) (xy 43.810486 -217.903459)
			(xy 43.874745 -217.934404) (xy 43.935136 -217.97235) (xy 43.990898 -218.016819) (xy 44.041331 -218.067252)
			(xy 44.0858 -218.123014) (xy 44.123746 -218.183405) (xy 44.154691 -218.247664) (xy 44.178248 -218.314984)
			(xy 44.194118 -218.384519) (xy 44.202104 -218.455393) (xy 44.202604 -218.491054) (xy 44.202104 -218.526715)
			(xy 44.836072 -218.526715) (xy 44.836072 -218.455393) (xy 44.844058 -218.384519) (xy 44.859928 -218.314984)
			(xy 44.883485 -218.247664) (xy 44.91443 -218.183405) (xy 44.952376 -218.123014) (xy 44.996845 -218.067252)
			(xy 45.047278 -218.016819) (xy 45.10304 -217.97235) (xy 45.163431 -217.934404) (xy 45.22769 -217.903459)
			(xy 45.29501 -217.879902) (xy 45.364545 -217.864032) (xy 45.435419 -217.856046) (xy 45.506741 -217.856046)
			(xy 45.577615 -217.864032) (xy 45.64715 -217.879902) (xy 45.71447 -217.903459) (xy 45.778729 -217.934404)
			(xy 45.83912 -217.97235) (xy 45.894882 -218.016819) (xy 45.945315 -218.067252) (xy 45.989784 -218.123014)
			(xy 46.02773 -218.183405) (xy 46.058675 -218.247664) (xy 46.082232 -218.314984) (xy 46.098102 -218.384519)
			(xy 46.106088 -218.455393) (xy 46.106588 -218.491054) (xy 46.106088 -218.526715) (xy 46.098102 -218.597589)
			(xy 46.082232 -218.667124) (xy 46.058675 -218.734444) (xy 46.02773 -218.798703) (xy 45.989784 -218.859094)
			(xy 45.945315 -218.914856) (xy 45.894882 -218.965289) (xy 45.83912 -219.009758) (xy 45.794307 -219.037916)
			(xy 68.751956 -219.037916) (xy 68.756027 -218.982294) (xy 68.768153 -218.927857) (xy 68.788076 -218.875766)
			(xy 68.815372 -218.827131) (xy 68.849458 -218.782988) (xy 68.889607 -218.744279) (xy 68.934965 -218.711828)
			(xy 68.984565 -218.686327) (xy 69.037349 -218.66832) (xy 69.092192 -218.65819) (xy 69.147926 -218.656153)
			(xy 69.203363 -218.662253) (xy 69.25732 -218.676359) (xy 69.308649 -218.698171) (xy 69.356255 -218.727225)
			(xy 69.399123 -218.7629) (xy 69.43634 -218.804437) (xy 69.467113 -218.85095) (xy 69.490785 -218.901447)
			(xy 69.506853 -218.954854) (xy 69.514973 -219.01003) (xy 69.515482 -219.037916) (xy 69.514973 -219.065802)
			(xy 69.514068 -219.071952) (xy 69.896226 -219.071952) (xy 69.900297 -219.01633) (xy 69.912423 -218.961893)
			(xy 69.932346 -218.909802) (xy 69.959642 -218.861167) (xy 69.993728 -218.817024) (xy 70.033877 -218.778315)
			(xy 70.079235 -218.745864) (xy 70.128835 -218.720363) (xy 70.181619 -218.702356) (xy 70.236462 -218.692226)
			(xy 70.292196 -218.690189) (xy 70.347633 -218.696289) (xy 70.40159 -218.710395) (xy 70.452919 -218.732207)
			(xy 70.500525 -218.761261) (xy 70.543393 -218.796936) (xy 70.58061 -218.838473) (xy 70.611383 -218.884986)
			(xy 70.635055 -218.935483) (xy 70.651123 -218.98889) (xy 70.653964 -219.008198) (xy 71.069452 -219.008198)
			(xy 71.073523 -218.952576) (xy 71.085649 -218.898139) (xy 71.105572 -218.846048) (xy 71.132868 -218.797413)
			(xy 71.166954 -218.75327) (xy 71.207103 -218.714561) (xy 71.252461 -218.68211) (xy 71.302061 -218.656609)
			(xy 71.354845 -218.638602) (xy 71.409688 -218.628472) (xy 71.465422 -218.626435) (xy 71.520859 -218.632535)
			(xy 71.574816 -218.646641) (xy 71.626145 -218.668453) (xy 71.673751 -218.697507) (xy 71.716619 -218.733182)
			(xy 71.753836 -218.774719) (xy 71.784609 -218.821232) (xy 71.808281 -218.871729) (xy 71.824349 -218.925136)
			(xy 71.832469 -218.980312) (xy 71.832978 -219.008198) (xy 72.208134 -219.008198) (xy 72.212205 -218.952576)
			(xy 72.224331 -218.898139) (xy 72.244254 -218.846048) (xy 72.27155 -218.797413) (xy 72.305636 -218.75327)
			(xy 72.345785 -218.714561) (xy 72.391143 -218.68211) (xy 72.440743 -218.656609) (xy 72.493527 -218.638602)
			(xy 72.54837 -218.628472) (xy 72.604104 -218.626435) (xy 72.659541 -218.632535) (xy 72.713498 -218.646641)
			(xy 72.764827 -218.668453) (xy 72.812433 -218.697507) (xy 72.855301 -218.733182) (xy 72.892518 -218.774719)
			(xy 72.923291 -218.821232) (xy 72.946963 -218.871729) (xy 72.963031 -218.925136) (xy 72.971151 -218.980312)
			(xy 72.97166 -219.008198) (xy 72.971151 -219.036084) (xy 72.963031 -219.09126) (xy 72.946963 -219.144667)
			(xy 72.923291 -219.195164) (xy 72.892518 -219.241677) (xy 72.855301 -219.283214) (xy 72.812433 -219.318889)
			(xy 72.764827 -219.347943) (xy 72.713498 -219.369755) (xy 72.659541 -219.383861) (xy 72.604104 -219.389961)
			(xy 72.54837 -219.387924) (xy 72.493527 -219.377794) (xy 72.440743 -219.359787) (xy 72.391143 -219.334286)
			(xy 72.345785 -219.301835) (xy 72.305636 -219.263126) (xy 72.27155 -219.218983) (xy 72.244254 -219.170348)
			(xy 72.224331 -219.118257) (xy 72.212205 -219.06382) (xy 72.208134 -219.008198) (xy 71.832978 -219.008198)
			(xy 71.832469 -219.036084) (xy 71.824349 -219.09126) (xy 71.808281 -219.144667) (xy 71.784609 -219.195164)
			(xy 71.753836 -219.241677) (xy 71.716619 -219.283214) (xy 71.673751 -219.318889) (xy 71.626145 -219.347943)
			(xy 71.574816 -219.369755) (xy 71.520859 -219.383861) (xy 71.465422 -219.389961) (xy 71.409688 -219.387924)
			(xy 71.354845 -219.377794) (xy 71.302061 -219.359787) (xy 71.252461 -219.334286) (xy 71.207103 -219.301835)
			(xy 71.166954 -219.263126) (xy 71.132868 -219.218983) (xy 71.105572 -219.170348) (xy 71.085649 -219.118257)
			(xy 71.073523 -219.06382) (xy 71.069452 -219.008198) (xy 70.653964 -219.008198) (xy 70.659243 -219.044066)
			(xy 70.659752 -219.071952) (xy 70.659243 -219.099838) (xy 70.651123 -219.155014) (xy 70.635055 -219.208421)
			(xy 70.611383 -219.258918) (xy 70.58061 -219.305431) (xy 70.543393 -219.346968) (xy 70.500525 -219.382643)
			(xy 70.452919 -219.411697) (xy 70.40159 -219.433509) (xy 70.347633 -219.447615) (xy 70.292196 -219.453715)
			(xy 70.236462 -219.451678) (xy 70.181619 -219.441548) (xy 70.128835 -219.423541) (xy 70.079235 -219.39804)
			(xy 70.033877 -219.365589) (xy 69.993728 -219.32688) (xy 69.959642 -219.282737) (xy 69.932346 -219.234102)
			(xy 69.912423 -219.182011) (xy 69.900297 -219.127574) (xy 69.896226 -219.071952) (xy 69.514068 -219.071952)
			(xy 69.506853 -219.120978) (xy 69.490785 -219.174385) (xy 69.467113 -219.224882) (xy 69.43634 -219.271395)
			(xy 69.399123 -219.312932) (xy 69.356255 -219.348607) (xy 69.308649 -219.377661) (xy 69.25732 -219.399473)
			(xy 69.203363 -219.413579) (xy 69.147926 -219.419679) (xy 69.092192 -219.417642) (xy 69.037349 -219.407512)
			(xy 68.984565 -219.389505) (xy 68.934965 -219.364004) (xy 68.889607 -219.331553) (xy 68.849458 -219.292844)
			(xy 68.815372 -219.248701) (xy 68.788076 -219.200066) (xy 68.768153 -219.147975) (xy 68.756027 -219.093538)
			(xy 68.751956 -219.037916) (xy 45.794307 -219.037916) (xy 45.778729 -219.047704) (xy 45.71447 -219.078649)
			(xy 45.64715 -219.102206) (xy 45.577615 -219.118076) (xy 45.506741 -219.126062) (xy 45.435419 -219.126062)
			(xy 45.364545 -219.118076) (xy 45.29501 -219.102206) (xy 45.22769 -219.078649) (xy 45.163431 -219.047704)
			(xy 45.10304 -219.009758) (xy 45.047278 -218.965289) (xy 44.996845 -218.914856) (xy 44.952376 -218.859094)
			(xy 44.91443 -218.798703) (xy 44.883485 -218.734444) (xy 44.859928 -218.667124) (xy 44.844058 -218.597589)
			(xy 44.836072 -218.526715) (xy 44.202104 -218.526715) (xy 44.194118 -218.597589) (xy 44.178248 -218.667124)
			(xy 44.154691 -218.734444) (xy 44.123746 -218.798703) (xy 44.0858 -218.859094) (xy 44.041331 -218.914856)
			(xy 43.990898 -218.965289) (xy 43.935136 -219.009758) (xy 43.874745 -219.047704) (xy 43.810486 -219.078649)
			(xy 43.743166 -219.102206) (xy 43.673631 -219.118076) (xy 43.602757 -219.126062) (xy 43.531435 -219.126062)
			(xy 43.460561 -219.118076) (xy 43.391026 -219.102206) (xy 43.323706 -219.078649) (xy 43.259447 -219.047704)
			(xy 43.199056 -219.009758) (xy 43.143294 -218.965289) (xy 43.092861 -218.914856) (xy 43.048392 -218.859094)
			(xy 43.010446 -218.798703) (xy 42.979501 -218.734444) (xy 42.955944 -218.667124) (xy 42.940074 -218.597589)
			(xy 42.932088 -218.526715) (xy 41.961062 -218.526715) (xy 41.953076 -218.597589) (xy 41.937206 -218.667124)
			(xy 41.913649 -218.734444) (xy 41.882704 -218.798703) (xy 41.844758 -218.859094) (xy 41.800289 -218.914856)
			(xy 41.749856 -218.965289) (xy 41.694094 -219.009758) (xy 41.633703 -219.047704) (xy 41.569444 -219.078649)
			(xy 41.502124 -219.102206) (xy 41.432589 -219.118076) (xy 41.361715 -219.126062) (xy 41.290393 -219.126062)
			(xy 41.219519 -219.118076) (xy 41.149984 -219.102206) (xy 41.082664 -219.078649) (xy 41.018405 -219.047704)
			(xy 40.958014 -219.009758) (xy 40.902252 -218.965289) (xy 40.851819 -218.914856) (xy 40.80735 -218.859094)
			(xy 40.769404 -218.798703) (xy 40.738459 -218.734444) (xy 40.714902 -218.667124) (xy 40.699032 -218.597589)
			(xy 40.691046 -218.526715) (xy 40.07435 -218.526715) (xy 40.066364 -218.597589) (xy 40.050494 -218.667124)
			(xy 40.026937 -218.734444) (xy 39.995992 -218.798703) (xy 39.958046 -218.859094) (xy 39.913577 -218.914856)
			(xy 39.863144 -218.965289) (xy 39.807382 -219.009758) (xy 39.746991 -219.047704) (xy 39.682732 -219.078649)
			(xy 39.615412 -219.102206) (xy 39.545877 -219.118076) (xy 39.475003 -219.126062) (xy 39.403681 -219.126062)
			(xy 39.332807 -219.118076) (xy 39.263272 -219.102206) (xy 39.195952 -219.078649) (xy 39.131693 -219.047704)
			(xy 39.071302 -219.009758) (xy 39.01554 -218.965289) (xy 38.965107 -218.914856) (xy 38.920638 -218.859094)
			(xy 38.882692 -218.798703) (xy 38.851747 -218.734444) (xy 38.82819 -218.667124) (xy 38.81232 -218.597589)
			(xy 38.804334 -218.526715) (xy 28.461716 -218.526715) (xy 28.461716 -219.533486) (xy 29.519874 -219.533486)
			(xy 29.519874 -219.446586) (xy 29.527892 -219.360057) (xy 29.54386 -219.274637) (xy 29.567641 -219.191055)
			(xy 29.599033 -219.110023) (xy 29.637767 -219.032234) (xy 29.683514 -218.95835) (xy 29.735883 -218.889003)
			(xy 29.794427 -218.824783) (xy 29.858647 -218.766239) (xy 29.927994 -218.71387) (xy 30.001878 -218.668123)
			(xy 30.079667 -218.629389) (xy 30.160699 -218.597997) (xy 30.244281 -218.574216) (xy 30.329701 -218.558248)
			(xy 30.41623 -218.55023) (xy 30.50313 -218.55023) (xy 30.589659 -218.558248) (xy 30.675079 -218.574216)
			(xy 30.758661 -218.597997) (xy 30.839693 -218.629389) (xy 30.917482 -218.668123) (xy 30.991366 -218.71387)
			(xy 31.060713 -218.766239) (xy 31.124933 -218.824783) (xy 31.183477 -218.889003) (xy 31.235846 -218.95835)
			(xy 31.281593 -219.032234) (xy 31.320327 -219.110023) (xy 31.351719 -219.191055) (xy 31.3755 -219.274637)
			(xy 31.391468 -219.360057) (xy 31.399486 -219.446586) (xy 31.399988 -219.490036) (xy 31.399486 -219.533486)
			(xy 34.599874 -219.533486) (xy 34.599874 -219.446586) (xy 34.607892 -219.360057) (xy 34.62386 -219.274637)
			(xy 34.647641 -219.191055) (xy 34.679033 -219.110023) (xy 34.717767 -219.032234) (xy 34.763514 -218.95835)
			(xy 34.815883 -218.889003) (xy 34.874427 -218.824783) (xy 34.938647 -218.766239) (xy 35.007994 -218.71387)
			(xy 35.081878 -218.668123) (xy 35.159667 -218.629389) (xy 35.240699 -218.597997) (xy 35.324281 -218.574216)
			(xy 35.409701 -218.558248) (xy 35.49623 -218.55023) (xy 35.58313 -218.55023) (xy 35.669659 -218.558248)
			(xy 35.755079 -218.574216) (xy 35.838661 -218.597997) (xy 35.919693 -218.629389) (xy 35.997482 -218.668123)
			(xy 36.071366 -218.71387) (xy 36.140713 -218.766239) (xy 36.204933 -218.824783) (xy 36.263477 -218.889003)
			(xy 36.315846 -218.95835) (xy 36.361593 -219.032234) (xy 36.400327 -219.110023) (xy 36.431719 -219.191055)
			(xy 36.4555 -219.274637) (xy 36.471468 -219.360057) (xy 36.479486 -219.446586) (xy 36.479988 -219.490036)
			(xy 36.479486 -219.533486) (xy 36.471468 -219.620015) (xy 36.4555 -219.705435) (xy 36.431719 -219.789017)
			(xy 36.400327 -219.870049) (xy 36.361593 -219.947838) (xy 36.315846 -220.021722) (xy 36.263477 -220.091069)
			(xy 36.204933 -220.155289) (xy 36.140713 -220.213833) (xy 36.071366 -220.266202) (xy 35.997482 -220.311949)
			(xy 35.919693 -220.350683) (xy 35.838661 -220.382075) (xy 35.755079 -220.405856) (xy 35.669659 -220.421824)
			(xy 35.58313 -220.429842) (xy 35.49623 -220.429842) (xy 35.409701 -220.421824) (xy 35.324281 -220.405856)
			(xy 35.240699 -220.382075) (xy 35.159667 -220.350683) (xy 35.081878 -220.311949) (xy 35.007994 -220.266202)
			(xy 34.938647 -220.213833) (xy 34.874427 -220.155289) (xy 34.815883 -220.091069) (xy 34.763514 -220.021722)
			(xy 34.717767 -219.947838) (xy 34.679033 -219.870049) (xy 34.647641 -219.789017) (xy 34.62386 -219.705435)
			(xy 34.607892 -219.620015) (xy 34.599874 -219.533486) (xy 31.399486 -219.533486) (xy 31.391468 -219.620015)
			(xy 31.3755 -219.705435) (xy 31.351719 -219.789017) (xy 31.320327 -219.870049) (xy 31.281593 -219.947838)
			(xy 31.235846 -220.021722) (xy 31.183477 -220.091069) (xy 31.124933 -220.155289) (xy 31.060713 -220.213833)
			(xy 30.991366 -220.266202) (xy 30.917482 -220.311949) (xy 30.839693 -220.350683) (xy 30.758661 -220.382075)
			(xy 30.675079 -220.405856) (xy 30.589659 -220.421824) (xy 30.50313 -220.429842) (xy 30.41623 -220.429842)
			(xy 30.329701 -220.421824) (xy 30.244281 -220.405856) (xy 30.160699 -220.382075) (xy 30.079667 -220.350683)
			(xy 30.001878 -220.311949) (xy 29.927994 -220.266202) (xy 29.858647 -220.213833) (xy 29.794427 -220.155289)
			(xy 29.735883 -220.091069) (xy 29.683514 -220.021722) (xy 29.637767 -219.947838) (xy 29.599033 -219.870049)
			(xy 29.567641 -219.789017) (xy 29.54386 -219.705435) (xy 29.527892 -219.620015) (xy 29.519874 -219.533486)
			(xy 28.461716 -219.533486) (xy 28.461716 -220.436541) (xy 38.804334 -220.436541) (xy 38.804334 -220.365219)
			(xy 38.81232 -220.294345) (xy 38.82819 -220.22481) (xy 38.851747 -220.15749) (xy 38.882692 -220.093231)
			(xy 38.920638 -220.03284) (xy 38.965107 -219.977078) (xy 39.01554 -219.926645) (xy 39.071302 -219.882176)
			(xy 39.131693 -219.84423) (xy 39.195952 -219.813285) (xy 39.263272 -219.789728) (xy 39.332807 -219.773858)
			(xy 39.403681 -219.765872) (xy 39.475003 -219.765872) (xy 39.545877 -219.773858) (xy 39.615412 -219.789728)
			(xy 39.682732 -219.813285) (xy 39.746991 -219.84423) (xy 39.807382 -219.882176) (xy 39.863144 -219.926645)
			(xy 39.913577 -219.977078) (xy 39.958046 -220.03284) (xy 39.995992 -220.093231) (xy 40.026937 -220.15749)
			(xy 40.050494 -220.22481) (xy 40.066364 -220.294345) (xy 40.07435 -220.365219) (xy 40.07485 -220.40088)
			(xy 40.07435 -220.436541) (xy 40.691046 -220.436541) (xy 40.691046 -220.365219) (xy 40.699032 -220.294345)
			(xy 40.714902 -220.22481) (xy 40.738459 -220.15749) (xy 40.769404 -220.093231) (xy 40.80735 -220.03284)
			(xy 40.851819 -219.977078) (xy 40.902252 -219.926645) (xy 40.958014 -219.882176) (xy 41.018405 -219.84423)
			(xy 41.082664 -219.813285) (xy 41.149984 -219.789728) (xy 41.219519 -219.773858) (xy 41.290393 -219.765872)
			(xy 41.361715 -219.765872) (xy 41.432589 -219.773858) (xy 41.502124 -219.789728) (xy 41.569444 -219.813285)
			(xy 41.633703 -219.84423) (xy 41.694094 -219.882176) (xy 41.749856 -219.926645) (xy 41.800289 -219.977078)
			(xy 41.844758 -220.03284) (xy 41.882704 -220.093231) (xy 41.913649 -220.15749) (xy 41.937206 -220.22481)
			(xy 41.953076 -220.294345) (xy 41.961062 -220.365219) (xy 41.961562 -220.40088) (xy 41.961062 -220.436541)
			(xy 42.932088 -220.436541) (xy 42.932088 -220.365219) (xy 42.940074 -220.294345) (xy 42.955944 -220.22481)
			(xy 42.979501 -220.15749) (xy 43.010446 -220.093231) (xy 43.048392 -220.03284) (xy 43.092861 -219.977078)
			(xy 43.143294 -219.926645) (xy 43.199056 -219.882176) (xy 43.259447 -219.84423) (xy 43.323706 -219.813285)
			(xy 43.391026 -219.789728) (xy 43.460561 -219.773858) (xy 43.531435 -219.765872) (xy 43.602757 -219.765872)
			(xy 43.673631 -219.773858) (xy 43.743166 -219.789728) (xy 43.810486 -219.813285) (xy 43.874745 -219.84423)
			(xy 43.935136 -219.882176) (xy 43.990898 -219.926645) (xy 44.041331 -219.977078) (xy 44.0858 -220.03284)
			(xy 44.123746 -220.093231) (xy 44.154691 -220.15749) (xy 44.178248 -220.22481) (xy 44.194118 -220.294345)
			(xy 44.202104 -220.365219) (xy 44.202604 -220.40088) (xy 44.202104 -220.436541) (xy 44.836072 -220.436541)
			(xy 44.836072 -220.365219) (xy 44.844058 -220.294345) (xy 44.859928 -220.22481) (xy 44.883485 -220.15749)
			(xy 44.91443 -220.093231) (xy 44.952376 -220.03284) (xy 44.996845 -219.977078) (xy 45.047278 -219.926645)
			(xy 45.10304 -219.882176) (xy 45.163431 -219.84423) (xy 45.22769 -219.813285) (xy 45.29501 -219.789728)
			(xy 45.364545 -219.773858) (xy 45.435419 -219.765872) (xy 45.506741 -219.765872) (xy 45.577615 -219.773858)
			(xy 45.64715 -219.789728) (xy 45.71447 -219.813285) (xy 45.778729 -219.84423) (xy 45.83912 -219.882176)
			(xy 45.894882 -219.926645) (xy 45.945315 -219.977078) (xy 45.989784 -220.03284) (xy 46.02773 -220.093231)
			(xy 46.058675 -220.15749) (xy 46.082232 -220.22481) (xy 46.098102 -220.294345) (xy 46.106088 -220.365219)
			(xy 46.106588 -220.40088) (xy 46.106088 -220.436541) (xy 46.098102 -220.507415) (xy 46.082232 -220.57695)
			(xy 46.058675 -220.64427) (xy 46.02773 -220.708529) (xy 45.989784 -220.76892) (xy 45.945315 -220.824682)
			(xy 45.894882 -220.875115) (xy 45.83912 -220.919584) (xy 45.778729 -220.95753) (xy 45.71447 -220.988475)
			(xy 45.64715 -221.012032) (xy 45.577615 -221.027902) (xy 45.506741 -221.035888) (xy 45.435419 -221.035888)
			(xy 45.364545 -221.027902) (xy 45.29501 -221.012032) (xy 45.22769 -220.988475) (xy 45.163431 -220.95753)
			(xy 45.10304 -220.919584) (xy 45.047278 -220.875115) (xy 44.996845 -220.824682) (xy 44.952376 -220.76892)
			(xy 44.91443 -220.708529) (xy 44.883485 -220.64427) (xy 44.859928 -220.57695) (xy 44.844058 -220.507415)
			(xy 44.836072 -220.436541) (xy 44.202104 -220.436541) (xy 44.194118 -220.507415) (xy 44.178248 -220.57695)
			(xy 44.154691 -220.64427) (xy 44.123746 -220.708529) (xy 44.0858 -220.76892) (xy 44.041331 -220.824682)
			(xy 43.990898 -220.875115) (xy 43.935136 -220.919584) (xy 43.874745 -220.95753) (xy 43.810486 -220.988475)
			(xy 43.743166 -221.012032) (xy 43.673631 -221.027902) (xy 43.602757 -221.035888) (xy 43.531435 -221.035888)
			(xy 43.460561 -221.027902) (xy 43.391026 -221.012032) (xy 43.323706 -220.988475) (xy 43.259447 -220.95753)
			(xy 43.199056 -220.919584) (xy 43.143294 -220.875115) (xy 43.092861 -220.824682) (xy 43.048392 -220.76892)
			(xy 43.010446 -220.708529) (xy 42.979501 -220.64427) (xy 42.955944 -220.57695) (xy 42.940074 -220.507415)
			(xy 42.932088 -220.436541) (xy 41.961062 -220.436541) (xy 41.953076 -220.507415) (xy 41.937206 -220.57695)
			(xy 41.913649 -220.64427) (xy 41.882704 -220.708529) (xy 41.844758 -220.76892) (xy 41.800289 -220.824682)
			(xy 41.749856 -220.875115) (xy 41.694094 -220.919584) (xy 41.633703 -220.95753) (xy 41.569444 -220.988475)
			(xy 41.502124 -221.012032) (xy 41.432589 -221.027902) (xy 41.361715 -221.035888) (xy 41.290393 -221.035888)
			(xy 41.219519 -221.027902) (xy 41.149984 -221.012032) (xy 41.082664 -220.988475) (xy 41.018405 -220.95753)
			(xy 40.958014 -220.919584) (xy 40.902252 -220.875115) (xy 40.851819 -220.824682) (xy 40.80735 -220.76892)
			(xy 40.769404 -220.708529) (xy 40.738459 -220.64427) (xy 40.714902 -220.57695) (xy 40.699032 -220.507415)
			(xy 40.691046 -220.436541) (xy 40.07435 -220.436541) (xy 40.066364 -220.507415) (xy 40.050494 -220.57695)
			(xy 40.026937 -220.64427) (xy 39.995992 -220.708529) (xy 39.958046 -220.76892) (xy 39.913577 -220.824682)
			(xy 39.863144 -220.875115) (xy 39.807382 -220.919584) (xy 39.746991 -220.95753) (xy 39.682732 -220.988475)
			(xy 39.615412 -221.012032) (xy 39.545877 -221.027902) (xy 39.475003 -221.035888) (xy 39.403681 -221.035888)
			(xy 39.332807 -221.027902) (xy 39.263272 -221.012032) (xy 39.195952 -220.988475) (xy 39.131693 -220.95753)
			(xy 39.071302 -220.919584) (xy 39.01554 -220.875115) (xy 38.965107 -220.824682) (xy 38.920638 -220.76892)
			(xy 38.882692 -220.708529) (xy 38.851747 -220.64427) (xy 38.82819 -220.57695) (xy 38.81232 -220.507415)
			(xy 38.804334 -220.436541) (xy 28.461716 -220.436541) (xy 28.461716 -222.073486) (xy 29.519874 -222.073486)
			(xy 29.519874 -221.986586) (xy 29.527892 -221.900057) (xy 29.54386 -221.814637) (xy 29.567641 -221.731055)
			(xy 29.599033 -221.650023) (xy 29.637767 -221.572234) (xy 29.683514 -221.49835) (xy 29.735883 -221.429003)
			(xy 29.794427 -221.364783) (xy 29.858647 -221.306239) (xy 29.927994 -221.25387) (xy 30.001878 -221.208123)
			(xy 30.079667 -221.169389) (xy 30.160699 -221.137997) (xy 30.244281 -221.114216) (xy 30.329701 -221.098248)
			(xy 30.41623 -221.09023) (xy 30.50313 -221.09023) (xy 30.589659 -221.098248) (xy 30.675079 -221.114216)
			(xy 30.758661 -221.137997) (xy 30.839693 -221.169389) (xy 30.917482 -221.208123) (xy 30.991366 -221.25387)
			(xy 31.060713 -221.306239) (xy 31.124933 -221.364783) (xy 31.183477 -221.429003) (xy 31.235846 -221.49835)
			(xy 31.281593 -221.572234) (xy 31.320327 -221.650023) (xy 31.351719 -221.731055) (xy 31.3755 -221.814637)
			(xy 31.391468 -221.900057) (xy 31.399486 -221.986586) (xy 31.399988 -222.030036) (xy 31.399486 -222.073486)
			(xy 34.599874 -222.073486) (xy 34.599874 -221.986586) (xy 34.607892 -221.900057) (xy 34.62386 -221.814637)
			(xy 34.647641 -221.731055) (xy 34.679033 -221.650023) (xy 34.717767 -221.572234) (xy 34.763514 -221.49835)
			(xy 34.815883 -221.429003) (xy 34.874427 -221.364783) (xy 34.938647 -221.306239) (xy 35.007994 -221.25387)
			(xy 35.081878 -221.208123) (xy 35.159667 -221.169389) (xy 35.240699 -221.137997) (xy 35.324281 -221.114216)
			(xy 35.409701 -221.098248) (xy 35.49623 -221.09023) (xy 35.58313 -221.09023) (xy 35.669659 -221.098248)
			(xy 35.755079 -221.114216) (xy 35.838661 -221.137997) (xy 35.919693 -221.169389) (xy 35.997482 -221.208123)
			(xy 36.071366 -221.25387) (xy 36.140713 -221.306239) (xy 36.204933 -221.364783) (xy 36.263477 -221.429003)
			(xy 36.315846 -221.49835) (xy 36.361593 -221.572234) (xy 36.400327 -221.650023) (xy 36.431719 -221.731055)
			(xy 36.4555 -221.814637) (xy 36.471468 -221.900057) (xy 36.479486 -221.986586) (xy 36.479988 -222.030036)
			(xy 36.479486 -222.073486) (xy 36.471468 -222.160015) (xy 36.4555 -222.245435) (xy 36.431719 -222.329017)
			(xy 36.400327 -222.410049) (xy 36.361593 -222.487838) (xy 36.315846 -222.561722) (xy 36.263477 -222.631069)
			(xy 36.204933 -222.695289) (xy 36.140713 -222.753833) (xy 36.071366 -222.806202) (xy 35.997482 -222.851949)
			(xy 35.919693 -222.890683) (xy 35.838661 -222.922075) (xy 35.755079 -222.945856) (xy 35.669659 -222.961824)
			(xy 35.58313 -222.969842) (xy 35.49623 -222.969842) (xy 35.409701 -222.961824) (xy 35.324281 -222.945856)
			(xy 35.240699 -222.922075) (xy 35.159667 -222.890683) (xy 35.081878 -222.851949) (xy 35.007994 -222.806202)
			(xy 34.938647 -222.753833) (xy 34.874427 -222.695289) (xy 34.815883 -222.631069) (xy 34.763514 -222.561722)
			(xy 34.717767 -222.487838) (xy 34.679033 -222.410049) (xy 34.647641 -222.329017) (xy 34.62386 -222.245435)
			(xy 34.607892 -222.160015) (xy 34.599874 -222.073486) (xy 31.399486 -222.073486) (xy 31.391468 -222.160015)
			(xy 31.3755 -222.245435) (xy 31.351719 -222.329017) (xy 31.320327 -222.410049) (xy 31.281593 -222.487838)
			(xy 31.235846 -222.561722) (xy 31.183477 -222.631069) (xy 31.124933 -222.695289) (xy 31.060713 -222.753833)
			(xy 30.991366 -222.806202) (xy 30.917482 -222.851949) (xy 30.839693 -222.890683) (xy 30.758661 -222.922075)
			(xy 30.675079 -222.945856) (xy 30.589659 -222.961824) (xy 30.50313 -222.969842) (xy 30.41623 -222.969842)
			(xy 30.329701 -222.961824) (xy 30.244281 -222.945856) (xy 30.160699 -222.922075) (xy 30.079667 -222.890683)
			(xy 30.001878 -222.851949) (xy 29.927994 -222.806202) (xy 29.858647 -222.753833) (xy 29.794427 -222.695289)
			(xy 29.735883 -222.631069) (xy 29.683514 -222.561722) (xy 29.637767 -222.487838) (xy 29.599033 -222.410049)
			(xy 29.567641 -222.329017) (xy 29.54386 -222.245435) (xy 29.527892 -222.160015) (xy 29.519874 -222.073486)
			(xy 28.461716 -222.073486) (xy 28.461716 -224.613486) (xy 29.519874 -224.613486) (xy 29.519874 -224.526586)
			(xy 29.527892 -224.440057) (xy 29.54386 -224.354637) (xy 29.567641 -224.271055) (xy 29.599033 -224.190023)
			(xy 29.637767 -224.112234) (xy 29.683514 -224.03835) (xy 29.735883 -223.969003) (xy 29.794427 -223.904783)
			(xy 29.858647 -223.846239) (xy 29.927994 -223.79387) (xy 30.001878 -223.748123) (xy 30.079667 -223.709389)
			(xy 30.160699 -223.677997) (xy 30.244281 -223.654216) (xy 30.329701 -223.638248) (xy 30.41623 -223.63023)
			(xy 30.50313 -223.63023) (xy 30.589659 -223.638248) (xy 30.675079 -223.654216) (xy 30.758661 -223.677997)
			(xy 30.839693 -223.709389) (xy 30.917482 -223.748123) (xy 30.991366 -223.79387) (xy 31.060713 -223.846239)
			(xy 31.124933 -223.904783) (xy 31.183477 -223.969003) (xy 31.235846 -224.03835) (xy 31.281593 -224.112234)
			(xy 31.320327 -224.190023) (xy 31.351719 -224.271055) (xy 31.3755 -224.354637) (xy 31.391468 -224.440057)
			(xy 31.399486 -224.526586) (xy 31.399988 -224.570036) (xy 31.399486 -224.613486) (xy 34.599874 -224.613486)
			(xy 34.599874 -224.526586) (xy 34.607892 -224.440057) (xy 34.62386 -224.354637) (xy 34.647641 -224.271055)
			(xy 34.679033 -224.190023) (xy 34.717767 -224.112234) (xy 34.763514 -224.03835) (xy 34.815883 -223.969003)
			(xy 34.874427 -223.904783) (xy 34.938647 -223.846239) (xy 35.007994 -223.79387) (xy 35.081878 -223.748123)
			(xy 35.159667 -223.709389) (xy 35.240699 -223.677997) (xy 35.324281 -223.654216) (xy 35.409701 -223.638248)
			(xy 35.49623 -223.63023) (xy 35.58313 -223.63023) (xy 35.669659 -223.638248) (xy 35.755079 -223.654216)
			(xy 35.838661 -223.677997) (xy 35.919693 -223.709389) (xy 35.997482 -223.748123) (xy 36.071366 -223.79387)
			(xy 36.140713 -223.846239) (xy 36.204933 -223.904783) (xy 36.263477 -223.969003) (xy 36.315846 -224.03835)
			(xy 36.361593 -224.112234) (xy 36.400327 -224.190023) (xy 36.431719 -224.271055) (xy 36.4555 -224.354637)
			(xy 36.471468 -224.440057) (xy 36.479486 -224.526586) (xy 36.479988 -224.570036) (xy 36.479486 -224.613486)
			(xy 36.471468 -224.700015) (xy 36.4555 -224.785435) (xy 36.431719 -224.869017) (xy 36.400327 -224.950049)
			(xy 36.361593 -225.027838) (xy 36.315846 -225.101722) (xy 36.263477 -225.171069) (xy 36.204933 -225.235289)
			(xy 36.140713 -225.293833) (xy 36.071366 -225.346202) (xy 35.997482 -225.391949) (xy 35.919693 -225.430683)
			(xy 35.838661 -225.462075) (xy 35.755079 -225.485856) (xy 35.669659 -225.501824) (xy 35.58313 -225.509842)
			(xy 35.49623 -225.509842) (xy 35.409701 -225.501824) (xy 35.324281 -225.485856) (xy 35.240699 -225.462075)
			(xy 35.159667 -225.430683) (xy 35.081878 -225.391949) (xy 35.007994 -225.346202) (xy 34.938647 -225.293833)
			(xy 34.874427 -225.235289) (xy 34.815883 -225.171069) (xy 34.763514 -225.101722) (xy 34.717767 -225.027838)
			(xy 34.679033 -224.950049) (xy 34.647641 -224.869017) (xy 34.62386 -224.785435) (xy 34.607892 -224.700015)
			(xy 34.599874 -224.613486) (xy 31.399486 -224.613486) (xy 31.391468 -224.700015) (xy 31.3755 -224.785435)
			(xy 31.351719 -224.869017) (xy 31.320327 -224.950049) (xy 31.281593 -225.027838) (xy 31.235846 -225.101722)
			(xy 31.183477 -225.171069) (xy 31.124933 -225.235289) (xy 31.060713 -225.293833) (xy 30.991366 -225.346202)
			(xy 30.917482 -225.391949) (xy 30.839693 -225.430683) (xy 30.758661 -225.462075) (xy 30.675079 -225.485856)
			(xy 30.589659 -225.501824) (xy 30.50313 -225.509842) (xy 30.41623 -225.509842) (xy 30.329701 -225.501824)
			(xy 30.244281 -225.485856) (xy 30.160699 -225.462075) (xy 30.079667 -225.430683) (xy 30.001878 -225.391949)
			(xy 29.927994 -225.346202) (xy 29.858647 -225.293833) (xy 29.794427 -225.235289) (xy 29.735883 -225.171069)
			(xy 29.683514 -225.101722) (xy 29.637767 -225.027838) (xy 29.599033 -224.950049) (xy 29.567641 -224.869017)
			(xy 29.54386 -224.785435) (xy 29.527892 -224.700015) (xy 29.519874 -224.613486) (xy 28.461716 -224.613486)
			(xy 28.461716 -227.153486) (xy 29.519874 -227.153486) (xy 29.519874 -227.066586) (xy 29.527892 -226.980057)
			(xy 29.54386 -226.894637) (xy 29.567641 -226.811055) (xy 29.599033 -226.730023) (xy 29.637767 -226.652234)
			(xy 29.683514 -226.57835) (xy 29.735883 -226.509003) (xy 29.794427 -226.444783) (xy 29.858647 -226.386239)
			(xy 29.927994 -226.33387) (xy 30.001878 -226.288123) (xy 30.079667 -226.249389) (xy 30.160699 -226.217997)
			(xy 30.244281 -226.194216) (xy 30.329701 -226.178248) (xy 30.41623 -226.17023) (xy 30.50313 -226.17023)
			(xy 30.589659 -226.178248) (xy 30.675079 -226.194216) (xy 30.758661 -226.217997) (xy 30.839693 -226.249389)
			(xy 30.917482 -226.288123) (xy 30.991366 -226.33387) (xy 31.060713 -226.386239) (xy 31.124933 -226.444783)
			(xy 31.183477 -226.509003) (xy 31.235846 -226.57835) (xy 31.281593 -226.652234) (xy 31.320327 -226.730023)
			(xy 31.351719 -226.811055) (xy 31.3755 -226.894637) (xy 31.391468 -226.980057) (xy 31.399486 -227.066586)
			(xy 31.399988 -227.110036) (xy 31.399486 -227.153486) (xy 34.599874 -227.153486) (xy 34.599874 -227.066586)
			(xy 34.607892 -226.980057) (xy 34.62386 -226.894637) (xy 34.647641 -226.811055) (xy 34.679033 -226.730023)
			(xy 34.717767 -226.652234) (xy 34.763514 -226.57835) (xy 34.815883 -226.509003) (xy 34.874427 -226.444783)
			(xy 34.938647 -226.386239) (xy 35.007994 -226.33387) (xy 35.081878 -226.288123) (xy 35.159667 -226.249389)
			(xy 35.240699 -226.217997) (xy 35.324281 -226.194216) (xy 35.409701 -226.178248) (xy 35.49623 -226.17023)
			(xy 35.58313 -226.17023) (xy 35.669659 -226.178248) (xy 35.755079 -226.194216) (xy 35.838661 -226.217997)
			(xy 35.919693 -226.249389) (xy 35.997482 -226.288123) (xy 36.071366 -226.33387) (xy 36.140713 -226.386239)
			(xy 36.204933 -226.444783) (xy 36.263477 -226.509003) (xy 36.315846 -226.57835) (xy 36.361593 -226.652234)
			(xy 36.400327 -226.730023) (xy 36.431719 -226.811055) (xy 36.4555 -226.894637) (xy 36.471468 -226.980057)
			(xy 36.479486 -227.066586) (xy 36.479988 -227.110036) (xy 36.479486 -227.153486) (xy 36.471468 -227.240015)
			(xy 36.4555 -227.325435) (xy 36.431719 -227.409017) (xy 36.400327 -227.490049) (xy 36.361593 -227.567838)
			(xy 36.315846 -227.641722) (xy 36.263477 -227.711069) (xy 36.204933 -227.775289) (xy 36.140713 -227.833833)
			(xy 36.071366 -227.886202) (xy 35.997482 -227.931949) (xy 35.919693 -227.970683) (xy 35.838661 -228.002075)
			(xy 35.755079 -228.025856) (xy 35.669659 -228.041824) (xy 35.58313 -228.049842) (xy 35.49623 -228.049842)
			(xy 35.409701 -228.041824) (xy 35.324281 -228.025856) (xy 35.240699 -228.002075) (xy 35.159667 -227.970683)
			(xy 35.081878 -227.931949) (xy 35.007994 -227.886202) (xy 34.938647 -227.833833) (xy 34.874427 -227.775289)
			(xy 34.815883 -227.711069) (xy 34.763514 -227.641722) (xy 34.717767 -227.567838) (xy 34.679033 -227.490049)
			(xy 34.647641 -227.409017) (xy 34.62386 -227.325435) (xy 34.607892 -227.240015) (xy 34.599874 -227.153486)
			(xy 31.399486 -227.153486) (xy 31.391468 -227.240015) (xy 31.3755 -227.325435) (xy 31.351719 -227.409017)
			(xy 31.320327 -227.490049) (xy 31.281593 -227.567838) (xy 31.235846 -227.641722) (xy 31.183477 -227.711069)
			(xy 31.124933 -227.775289) (xy 31.060713 -227.833833) (xy 30.991366 -227.886202) (xy 30.917482 -227.931949)
			(xy 30.839693 -227.970683) (xy 30.758661 -228.002075) (xy 30.675079 -228.025856) (xy 30.589659 -228.041824)
			(xy 30.50313 -228.049842) (xy 30.41623 -228.049842) (xy 30.329701 -228.041824) (xy 30.244281 -228.025856)
			(xy 30.160699 -228.002075) (xy 30.079667 -227.970683) (xy 30.001878 -227.931949) (xy 29.927994 -227.886202)
			(xy 29.858647 -227.833833) (xy 29.794427 -227.775289) (xy 29.735883 -227.711069) (xy 29.683514 -227.641722)
			(xy 29.637767 -227.567838) (xy 29.599033 -227.490049) (xy 29.567641 -227.409017) (xy 29.54386 -227.325435)
			(xy 29.527892 -227.240015) (xy 29.519874 -227.153486) (xy 28.461716 -227.153486) (xy 28.461716 -229.693486)
			(xy 29.519874 -229.693486) (xy 29.519874 -229.606586) (xy 29.527892 -229.520057) (xy 29.54386 -229.434637)
			(xy 29.567641 -229.351055) (xy 29.599033 -229.270023) (xy 29.637767 -229.192234) (xy 29.683514 -229.11835)
			(xy 29.735883 -229.049003) (xy 29.794427 -228.984783) (xy 29.858647 -228.926239) (xy 29.927994 -228.87387)
			(xy 30.001878 -228.828123) (xy 30.079667 -228.789389) (xy 30.160699 -228.757997) (xy 30.244281 -228.734216)
			(xy 30.329701 -228.718248) (xy 30.41623 -228.71023) (xy 30.50313 -228.71023) (xy 30.589659 -228.718248)
			(xy 30.675079 -228.734216) (xy 30.758661 -228.757997) (xy 30.839693 -228.789389) (xy 30.917482 -228.828123)
			(xy 30.991366 -228.87387) (xy 31.060713 -228.926239) (xy 31.124933 -228.984783) (xy 31.183477 -229.049003)
			(xy 31.235846 -229.11835) (xy 31.281593 -229.192234) (xy 31.320327 -229.270023) (xy 31.351719 -229.351055)
			(xy 31.3755 -229.434637) (xy 31.391468 -229.520057) (xy 31.399486 -229.606586) (xy 31.399988 -229.650036)
			(xy 31.399486 -229.693486) (xy 34.599874 -229.693486) (xy 34.599874 -229.606586) (xy 34.607892 -229.520057)
			(xy 34.62386 -229.434637) (xy 34.647641 -229.351055) (xy 34.679033 -229.270023) (xy 34.717767 -229.192234)
			(xy 34.763514 -229.11835) (xy 34.815883 -229.049003) (xy 34.874427 -228.984783) (xy 34.938647 -228.926239)
			(xy 35.007994 -228.87387) (xy 35.081878 -228.828123) (xy 35.159667 -228.789389) (xy 35.240699 -228.757997)
			(xy 35.324281 -228.734216) (xy 35.409701 -228.718248) (xy 35.49623 -228.71023) (xy 35.58313 -228.71023)
			(xy 35.669659 -228.718248) (xy 35.755079 -228.734216) (xy 35.838661 -228.757997) (xy 35.919693 -228.789389)
			(xy 35.997482 -228.828123) (xy 36.071366 -228.87387) (xy 36.140713 -228.926239) (xy 36.204933 -228.984783)
			(xy 36.263477 -229.049003) (xy 36.315846 -229.11835) (xy 36.341678 -229.16007) (xy 39.818063 -229.16007)
			(xy 39.82207 -229.044046) (xy 39.834072 -228.928574) (xy 39.854012 -228.814206) (xy 39.881795 -228.701486)
			(xy 39.917289 -228.590952) (xy 39.960324 -228.483129) (xy 40.010695 -228.378532) (xy 40.068162 -228.27766)
			(xy 40.132452 -228.180993) (xy 40.203257 -228.088992) (xy 40.280241 -228.002095) (xy 40.363037 -227.920716)
			(xy 40.45125 -227.845243) (xy 40.54446 -227.776036) (xy 40.642223 -227.713424) (xy 40.744072 -227.657707)
			(xy 40.849522 -227.609149) (xy 40.958071 -227.567981) (xy 41.069202 -227.534401) (xy 41.182385 -227.508568)
			(xy 41.29708 -227.490605) (xy 41.412742 -227.480597) (xy 41.528818 -227.478594) (xy 41.644756 -227.484603)
			(xy 41.760003 -227.498596) (xy 41.874009 -227.520507) (xy 41.986233 -227.550232) (xy 42.096139 -227.587628)
			(xy 42.203202 -227.632517) (xy 42.306914 -227.684686) (xy 42.406779 -227.743886) (xy 42.502322 -227.809835)
			(xy 42.502604 -227.81006) (xy 43.327577 -227.81006) (xy 43.331612 -227.734356) (xy 43.343671 -227.659511)
			(xy 43.363617 -227.58637) (xy 43.391224 -227.515765) (xy 43.42618 -227.448494) (xy 43.468088 -227.385319)
			(xy 43.516474 -227.326957) (xy 43.57079 -227.274069) (xy 43.630419 -227.227254) (xy 43.694687 -227.187042)
			(xy 43.762864 -227.15389) (xy 43.83418 -227.128172) (xy 43.907825 -227.11018) (xy 43.982965 -227.100118)
			(xy 44.058749 -227.098099) (xy 44.134319 -227.104148) (xy 44.208817 -227.118195) (xy 44.2814 -227.140081)
			(xy 44.351246 -227.169558) (xy 44.417563 -227.206293) (xy 44.479599 -227.249868) (xy 44.536652 -227.29979)
			(xy 44.588076 -227.355494) (xy 44.633287 -227.416349) (xy 44.671774 -227.481664) (xy 44.7031 -227.5507)
			(xy 44.72691 -227.622675) (xy 44.742935 -227.696773) (xy 44.750994 -227.772154) (xy 44.751498 -227.81006)
			(xy 45.867577 -227.81006) (xy 45.871612 -227.734356) (xy 45.883671 -227.659511) (xy 45.903617 -227.58637)
			(xy 45.931224 -227.515765) (xy 45.96618 -227.448494) (xy 46.008088 -227.385319) (xy 46.056474 -227.326957)
			(xy 46.11079 -227.274069) (xy 46.170419 -227.227254) (xy 46.234687 -227.187042) (xy 46.302864 -227.15389)
			(xy 46.37418 -227.128172) (xy 46.447825 -227.11018) (xy 46.522965 -227.100118) (xy 46.598749 -227.098099)
			(xy 46.674319 -227.104148) (xy 46.748817 -227.118195) (xy 46.8214 -227.140081) (xy 46.891246 -227.169558)
			(xy 46.957563 -227.206293) (xy 47.019599 -227.249868) (xy 47.076652 -227.29979) (xy 47.128076 -227.355494)
			(xy 47.173287 -227.416349) (xy 47.211774 -227.481664) (xy 47.2431 -227.5507) (xy 47.26691 -227.622675)
			(xy 47.282935 -227.696773) (xy 47.290994 -227.772154) (xy 47.291498 -227.81006) (xy 48.407577 -227.81006)
			(xy 48.411612 -227.734356) (xy 48.423671 -227.659511) (xy 48.443617 -227.58637) (xy 48.471224 -227.515765)
			(xy 48.50618 -227.448494) (xy 48.548088 -227.385319) (xy 48.596474 -227.326957) (xy 48.65079 -227.274069)
			(xy 48.710419 -227.227254) (xy 48.774687 -227.187042) (xy 48.842864 -227.15389) (xy 48.91418 -227.128172)
			(xy 48.987825 -227.11018) (xy 49.062965 -227.100118) (xy 49.138749 -227.098099) (xy 49.214319 -227.104148)
			(xy 49.288817 -227.118195) (xy 49.3614 -227.140081) (xy 49.431246 -227.169558) (xy 49.497563 -227.206293)
			(xy 49.559599 -227.249868) (xy 49.616652 -227.29979) (xy 49.668076 -227.355494) (xy 49.713287 -227.416349)
			(xy 49.751774 -227.481664) (xy 49.7831 -227.5507) (xy 49.80691 -227.622675) (xy 49.822935 -227.696773)
			(xy 49.830994 -227.772154) (xy 49.831498 -227.81006) (xy 50.947577 -227.81006) (xy 50.951612 -227.734356)
			(xy 50.963671 -227.659511) (xy 50.983617 -227.58637) (xy 51.011224 -227.515765) (xy 51.04618 -227.448494)
			(xy 51.088088 -227.385319) (xy 51.136474 -227.326957) (xy 51.19079 -227.274069) (xy 51.250419 -227.227254)
			(xy 51.314687 -227.187042) (xy 51.382864 -227.15389) (xy 51.45418 -227.128172) (xy 51.527825 -227.11018)
			(xy 51.602965 -227.100118) (xy 51.678749 -227.098099) (xy 51.754319 -227.104148) (xy 51.828817 -227.118195)
			(xy 51.9014 -227.140081) (xy 51.971246 -227.169558) (xy 52.037563 -227.206293) (xy 52.099599 -227.249868)
			(xy 52.156652 -227.29979) (xy 52.208076 -227.355494) (xy 52.253287 -227.416349) (xy 52.291774 -227.481664)
			(xy 52.3231 -227.5507) (xy 52.34691 -227.622675) (xy 52.362935 -227.696773) (xy 52.370994 -227.772154)
			(xy 52.371498 -227.81006) (xy 53.487577 -227.81006) (xy 53.491612 -227.734356) (xy 53.503671 -227.659511)
			(xy 53.523617 -227.58637) (xy 53.551224 -227.515765) (xy 53.58618 -227.448494) (xy 53.628088 -227.385319)
			(xy 53.676474 -227.326957) (xy 53.73079 -227.274069) (xy 53.790419 -227.227254) (xy 53.854687 -227.187042)
			(xy 53.922864 -227.15389) (xy 53.99418 -227.128172) (xy 54.067825 -227.11018) (xy 54.142965 -227.100118)
			(xy 54.218749 -227.098099) (xy 54.294319 -227.104148) (xy 54.368817 -227.118195) (xy 54.4414 -227.140081)
			(xy 54.511246 -227.169558) (xy 54.577563 -227.206293) (xy 54.639599 -227.249868) (xy 54.696652 -227.29979)
			(xy 54.748076 -227.355494) (xy 54.793287 -227.416349) (xy 54.831774 -227.481664) (xy 54.8631 -227.5507)
			(xy 54.88691 -227.622675) (xy 54.902935 -227.696773) (xy 54.910994 -227.772154) (xy 54.911498 -227.81006)
			(xy 56.027577 -227.81006) (xy 56.031612 -227.734356) (xy 56.043671 -227.659511) (xy 56.063617 -227.58637)
			(xy 56.091224 -227.515765) (xy 56.12618 -227.448494) (xy 56.168088 -227.385319) (xy 56.216474 -227.326957)
			(xy 56.27079 -227.274069) (xy 56.330419 -227.227254) (xy 56.394687 -227.187042) (xy 56.462864 -227.15389)
			(xy 56.53418 -227.128172) (xy 56.607825 -227.11018) (xy 56.682965 -227.100118) (xy 56.758749 -227.098099)
			(xy 56.834319 -227.104148) (xy 56.908817 -227.118195) (xy 56.9814 -227.140081) (xy 57.051246 -227.169558)
			(xy 57.117563 -227.206293) (xy 57.179599 -227.249868) (xy 57.236652 -227.29979) (xy 57.288076 -227.355494)
			(xy 57.333287 -227.416349) (xy 57.371774 -227.481664) (xy 57.4031 -227.5507) (xy 57.42691 -227.622675)
			(xy 57.442935 -227.696773) (xy 57.450994 -227.772154) (xy 57.451498 -227.81006) (xy 58.567577 -227.81006)
			(xy 58.571612 -227.734356) (xy 58.583671 -227.659511) (xy 58.603617 -227.58637) (xy 58.631224 -227.515765)
			(xy 58.66618 -227.448494) (xy 58.708088 -227.385319) (xy 58.756474 -227.326957) (xy 58.81079 -227.274069)
			(xy 58.870419 -227.227254) (xy 58.934687 -227.187042) (xy 59.002864 -227.15389) (xy 59.07418 -227.128172)
			(xy 59.147825 -227.11018) (xy 59.222965 -227.100118) (xy 59.298749 -227.098099) (xy 59.374319 -227.104148)
			(xy 59.448817 -227.118195) (xy 59.5214 -227.140081) (xy 59.591246 -227.169558) (xy 59.657563 -227.206293)
			(xy 59.719599 -227.249868) (xy 59.776652 -227.29979) (xy 59.828076 -227.355494) (xy 59.873287 -227.416349)
			(xy 59.911774 -227.481664) (xy 59.9431 -227.5507) (xy 59.96691 -227.622675) (xy 59.982935 -227.696773)
			(xy 59.990994 -227.772154) (xy 59.991498 -227.81006) (xy 61.107577 -227.81006) (xy 61.111612 -227.734356)
			(xy 61.123671 -227.659511) (xy 61.143617 -227.58637) (xy 61.171224 -227.515765) (xy 61.20618 -227.448494)
			(xy 61.248088 -227.385319) (xy 61.296474 -227.326957) (xy 61.35079 -227.274069) (xy 61.410419 -227.227254)
			(xy 61.474687 -227.187042) (xy 61.542864 -227.15389) (xy 61.61418 -227.128172) (xy 61.687825 -227.11018)
			(xy 61.762965 -227.100118) (xy 61.838749 -227.098099) (xy 61.914319 -227.104148) (xy 61.988817 -227.118195)
			(xy 62.0614 -227.140081) (xy 62.131246 -227.169558) (xy 62.197563 -227.206293) (xy 62.259599 -227.249868)
			(xy 62.316652 -227.29979) (xy 62.368076 -227.355494) (xy 62.413287 -227.416349) (xy 62.451774 -227.481664)
			(xy 62.4831 -227.5507) (xy 62.50691 -227.622675) (xy 62.522935 -227.696773) (xy 62.530994 -227.772154)
			(xy 62.531498 -227.81006) (xy 62.530994 -227.847966) (xy 62.522935 -227.923347) (xy 62.50691 -227.997445)
			(xy 62.4831 -228.06942) (xy 62.451774 -228.138456) (xy 62.413287 -228.203771) (xy 62.368076 -228.264626)
			(xy 62.316652 -228.32033) (xy 62.259599 -228.370252) (xy 62.197563 -228.413827) (xy 62.131246 -228.450562)
			(xy 62.0614 -228.480039) (xy 61.988817 -228.501925) (xy 61.914319 -228.515972) (xy 61.838749 -228.522021)
			(xy 61.762965 -228.520002) (xy 61.687825 -228.50994) (xy 61.61418 -228.491948) (xy 61.542864 -228.46623)
			(xy 61.474687 -228.433078) (xy 61.410419 -228.392866) (xy 61.35079 -228.346051) (xy 61.296474 -228.293163)
			(xy 61.248088 -228.234801) (xy 61.20618 -228.171626) (xy 61.171224 -228.104355) (xy 61.143617 -228.03375)
			(xy 61.123671 -227.960609) (xy 61.111612 -227.885764) (xy 61.107577 -227.81006) (xy 59.991498 -227.81006)
			(xy 59.990994 -227.847966) (xy 59.982935 -227.923347) (xy 59.96691 -227.997445) (xy 59.9431 -228.06942)
			(xy 59.911774 -228.138456) (xy 59.873287 -228.203771) (xy 59.828076 -228.264626) (xy 59.776652 -228.32033)
			(xy 59.719599 -228.370252) (xy 59.657563 -228.413827) (xy 59.591246 -228.450562) (xy 59.5214 -228.480039)
			(xy 59.448817 -228.501925) (xy 59.374319 -228.515972) (xy 59.298749 -228.522021) (xy 59.222965 -228.520002)
			(xy 59.147825 -228.50994) (xy 59.07418 -228.491948) (xy 59.002864 -228.46623) (xy 58.934687 -228.433078)
			(xy 58.870419 -228.392866) (xy 58.81079 -228.346051) (xy 58.756474 -228.293163) (xy 58.708088 -228.234801)
			(xy 58.66618 -228.171626) (xy 58.631224 -228.104355) (xy 58.603617 -228.03375) (xy 58.583671 -227.960609)
			(xy 58.571612 -227.885764) (xy 58.567577 -227.81006) (xy 57.451498 -227.81006) (xy 57.450994 -227.847966)
			(xy 57.442935 -227.923347) (xy 57.42691 -227.997445) (xy 57.4031 -228.06942) (xy 57.371774 -228.138456)
			(xy 57.333287 -228.203771) (xy 57.288076 -228.264626) (xy 57.236652 -228.32033) (xy 57.179599 -228.370252)
			(xy 57.117563 -228.413827) (xy 57.051246 -228.450562) (xy 56.9814 -228.480039) (xy 56.908817 -228.501925)
			(xy 56.834319 -228.515972) (xy 56.758749 -228.522021) (xy 56.682965 -228.520002) (xy 56.607825 -228.50994)
			(xy 56.53418 -228.491948) (xy 56.462864 -228.46623) (xy 56.394687 -228.433078) (xy 56.330419 -228.392866)
			(xy 56.27079 -228.346051) (xy 56.216474 -228.293163) (xy 56.168088 -228.234801) (xy 56.12618 -228.171626)
			(xy 56.091224 -228.104355) (xy 56.063617 -228.03375) (xy 56.043671 -227.960609) (xy 56.031612 -227.885764)
			(xy 56.027577 -227.81006) (xy 54.911498 -227.81006) (xy 54.910994 -227.847966) (xy 54.902935 -227.923347)
			(xy 54.88691 -227.997445) (xy 54.8631 -228.06942) (xy 54.831774 -228.138456) (xy 54.793287 -228.203771)
			(xy 54.748076 -228.264626) (xy 54.696652 -228.32033) (xy 54.639599 -228.370252) (xy 54.577563 -228.413827)
			(xy 54.511246 -228.450562) (xy 54.4414 -228.480039) (xy 54.368817 -228.501925) (xy 54.294319 -228.515972)
			(xy 54.218749 -228.522021) (xy 54.142965 -228.520002) (xy 54.067825 -228.50994) (xy 53.99418 -228.491948)
			(xy 53.922864 -228.46623) (xy 53.854687 -228.433078) (xy 53.790419 -228.392866) (xy 53.73079 -228.346051)
			(xy 53.676474 -228.293163) (xy 53.628088 -228.234801) (xy 53.58618 -228.171626) (xy 53.551224 -228.104355)
			(xy 53.523617 -228.03375) (xy 53.503671 -227.960609) (xy 53.491612 -227.885764) (xy 53.487577 -227.81006)
			(xy 52.371498 -227.81006) (xy 52.370994 -227.847966) (xy 52.362935 -227.923347) (xy 52.34691 -227.997445)
			(xy 52.3231 -228.06942) (xy 52.291774 -228.138456) (xy 52.253287 -228.203771) (xy 52.208076 -228.264626)
			(xy 52.156652 -228.32033) (xy 52.099599 -228.370252) (xy 52.037563 -228.413827) (xy 51.971246 -228.450562)
			(xy 51.9014 -228.480039) (xy 51.828817 -228.501925) (xy 51.754319 -228.515972) (xy 51.678749 -228.522021)
			(xy 51.602965 -228.520002) (xy 51.527825 -228.50994) (xy 51.45418 -228.491948) (xy 51.382864 -228.46623)
			(xy 51.314687 -228.433078) (xy 51.250419 -228.392866) (xy 51.19079 -228.346051) (xy 51.136474 -228.293163)
			(xy 51.088088 -228.234801) (xy 51.04618 -228.171626) (xy 51.011224 -228.104355) (xy 50.983617 -228.03375)
			(xy 50.963671 -227.960609) (xy 50.951612 -227.885764) (xy 50.947577 -227.81006) (xy 49.831498 -227.81006)
			(xy 49.830994 -227.847966) (xy 49.822935 -227.923347) (xy 49.80691 -227.997445) (xy 49.7831 -228.06942)
			(xy 49.751774 -228.138456) (xy 49.713287 -228.203771) (xy 49.668076 -228.264626) (xy 49.616652 -228.32033)
			(xy 49.559599 -228.370252) (xy 49.497563 -228.413827) (xy 49.431246 -228.450562) (xy 49.3614 -228.480039)
			(xy 49.288817 -228.501925) (xy 49.214319 -228.515972) (xy 49.138749 -228.522021) (xy 49.062965 -228.520002)
			(xy 48.987825 -228.50994) (xy 48.91418 -228.491948) (xy 48.842864 -228.46623) (xy 48.774687 -228.433078)
			(xy 48.710419 -228.392866) (xy 48.65079 -228.346051) (xy 48.596474 -228.293163) (xy 48.548088 -228.234801)
			(xy 48.50618 -228.171626) (xy 48.471224 -228.104355) (xy 48.443617 -228.03375) (xy 48.423671 -227.960609)
			(xy 48.411612 -227.885764) (xy 48.407577 -227.81006) (xy 47.291498 -227.81006) (xy 47.290994 -227.847966)
			(xy 47.282935 -227.923347) (xy 47.26691 -227.997445) (xy 47.2431 -228.06942) (xy 47.211774 -228.138456)
			(xy 47.173287 -228.203771) (xy 47.128076 -228.264626) (xy 47.076652 -228.32033) (xy 47.019599 -228.370252)
			(xy 46.957563 -228.413827) (xy 46.891246 -228.450562) (xy 46.8214 -228.480039) (xy 46.748817 -228.501925)
			(xy 46.674319 -228.515972) (xy 46.598749 -228.522021) (xy 46.522965 -228.520002) (xy 46.447825 -228.50994)
			(xy 46.37418 -228.491948) (xy 46.302864 -228.46623) (xy 46.234687 -228.433078) (xy 46.170419 -228.392866)
			(xy 46.11079 -228.346051) (xy 46.056474 -228.293163) (xy 46.008088 -228.234801) (xy 45.96618 -228.171626)
			(xy 45.931224 -228.104355) (xy 45.903617 -228.03375) (xy 45.883671 -227.960609) (xy 45.871612 -227.885764)
			(xy 45.867577 -227.81006) (xy 44.751498 -227.81006) (xy 44.750994 -227.847966) (xy 44.742935 -227.923347)
			(xy 44.72691 -227.997445) (xy 44.7031 -228.06942) (xy 44.671774 -228.138456) (xy 44.633287 -228.203771)
			(xy 44.588076 -228.264626) (xy 44.536652 -228.32033) (xy 44.479599 -228.370252) (xy 44.417563 -228.413827)
			(xy 44.351246 -228.450562) (xy 44.2814 -228.480039) (xy 44.208817 -228.501925) (xy 44.134319 -228.515972)
			(xy 44.058749 -228.522021) (xy 43.982965 -228.520002) (xy 43.907825 -228.50994) (xy 43.83418 -228.491948)
			(xy 43.762864 -228.46623) (xy 43.694687 -228.433078) (xy 43.630419 -228.392866) (xy 43.57079 -228.346051)
			(xy 43.516474 -228.293163) (xy 43.468088 -228.234801) (xy 43.42618 -228.171626) (xy 43.391224 -228.104355)
			(xy 43.363617 -228.03375) (xy 43.343671 -227.960609) (xy 43.331612 -227.885764) (xy 43.327577 -227.81006)
			(xy 42.502604 -227.81006) (xy 42.593088 -227.882218) (xy 42.678643 -227.960691) (xy 42.758581 -228.044879)
			(xy 42.83252 -228.134381) (xy 42.900108 -228.228772) (xy 42.961022 -228.3276) (xy 43.014974 -228.430396)
			(xy 43.061704 -228.536669) (xy 43.100992 -228.645913) (xy 43.132649 -228.757606) (xy 43.156525 -228.871218)
			(xy 43.172506 -228.986206) (xy 43.180515 -229.102023) (xy 43.181016 -229.16007) (xy 43.180515 -229.218117)
			(xy 43.172506 -229.333934) (xy 43.156525 -229.448922) (xy 43.132649 -229.562534) (xy 43.100992 -229.674227)
			(xy 43.061704 -229.783471) (xy 43.014974 -229.889744) (xy 42.961022 -229.99254) (xy 42.900108 -230.091368)
			(xy 42.83252 -230.185759) (xy 42.758581 -230.275261) (xy 42.678643 -230.359449) (xy 42.593088 -230.437922)
			(xy 42.502604 -230.51008) (xy 43.327577 -230.51008) (xy 43.331612 -230.434376) (xy 43.343671 -230.359531)
			(xy 43.363617 -230.28639) (xy 43.391224 -230.215785) (xy 43.42618 -230.148514) (xy 43.468088 -230.085339)
			(xy 43.516474 -230.026977) (xy 43.57079 -229.974089) (xy 43.630419 -229.927274) (xy 43.694687 -229.887062)
			(xy 43.762864 -229.85391) (xy 43.83418 -229.828192) (xy 43.907825 -229.8102) (xy 43.982965 -229.800138)
			(xy 44.058749 -229.798119) (xy 44.134319 -229.804168) (xy 44.208817 -229.818215) (xy 44.2814 -229.840101)
			(xy 44.351246 -229.869578) (xy 44.417563 -229.906313) (xy 44.479599 -229.949888) (xy 44.536652 -229.99981)
			(xy 44.588076 -230.055514) (xy 44.633287 -230.116369) (xy 44.671774 -230.181684) (xy 44.7031 -230.25072)
			(xy 44.72691 -230.322695) (xy 44.742935 -230.396793) (xy 44.750994 -230.472174) (xy 44.751498 -230.51008)
			(xy 45.867577 -230.51008) (xy 45.871612 -230.434376) (xy 45.883671 -230.359531) (xy 45.903617 -230.28639)
			(xy 45.931224 -230.215785) (xy 45.96618 -230.148514) (xy 46.008088 -230.085339) (xy 46.056474 -230.026977)
			(xy 46.11079 -229.974089) (xy 46.170419 -229.927274) (xy 46.234687 -229.887062) (xy 46.302864 -229.85391)
			(xy 46.37418 -229.828192) (xy 46.447825 -229.8102) (xy 46.522965 -229.800138) (xy 46.598749 -229.798119)
			(xy 46.674319 -229.804168) (xy 46.748817 -229.818215) (xy 46.8214 -229.840101) (xy 46.891246 -229.869578)
			(xy 46.957563 -229.906313) (xy 47.019599 -229.949888) (xy 47.076652 -229.99981) (xy 47.128076 -230.055514)
			(xy 47.173287 -230.116369) (xy 47.211774 -230.181684) (xy 47.2431 -230.25072) (xy 47.26691 -230.322695)
			(xy 47.282935 -230.396793) (xy 47.290994 -230.472174) (xy 47.291498 -230.51008) (xy 48.407577 -230.51008)
			(xy 48.411612 -230.434376) (xy 48.423671 -230.359531) (xy 48.443617 -230.28639) (xy 48.471224 -230.215785)
			(xy 48.50618 -230.148514) (xy 48.548088 -230.085339) (xy 48.596474 -230.026977) (xy 48.65079 -229.974089)
			(xy 48.710419 -229.927274) (xy 48.774687 -229.887062) (xy 48.842864 -229.85391) (xy 48.91418 -229.828192)
			(xy 48.987825 -229.8102) (xy 49.062965 -229.800138) (xy 49.138749 -229.798119) (xy 49.214319 -229.804168)
			(xy 49.288817 -229.818215) (xy 49.3614 -229.840101) (xy 49.431246 -229.869578) (xy 49.497563 -229.906313)
			(xy 49.559599 -229.949888) (xy 49.616652 -229.99981) (xy 49.668076 -230.055514) (xy 49.713287 -230.116369)
			(xy 49.751774 -230.181684) (xy 49.7831 -230.25072) (xy 49.80691 -230.322695) (xy 49.822935 -230.396793)
			(xy 49.830994 -230.472174) (xy 49.831498 -230.51008) (xy 50.947577 -230.51008) (xy 50.951612 -230.434376)
			(xy 50.963671 -230.359531) (xy 50.983617 -230.28639) (xy 51.011224 -230.215785) (xy 51.04618 -230.148514)
			(xy 51.088088 -230.085339) (xy 51.136474 -230.026977) (xy 51.19079 -229.974089) (xy 51.250419 -229.927274)
			(xy 51.314687 -229.887062) (xy 51.382864 -229.85391) (xy 51.45418 -229.828192) (xy 51.527825 -229.8102)
			(xy 51.602965 -229.800138) (xy 51.678749 -229.798119) (xy 51.754319 -229.804168) (xy 51.828817 -229.818215)
			(xy 51.9014 -229.840101) (xy 51.971246 -229.869578) (xy 52.037563 -229.906313) (xy 52.099599 -229.949888)
			(xy 52.156652 -229.99981) (xy 52.208076 -230.055514) (xy 52.253287 -230.116369) (xy 52.291774 -230.181684)
			(xy 52.3231 -230.25072) (xy 52.34691 -230.322695) (xy 52.362935 -230.396793) (xy 52.370994 -230.472174)
			(xy 52.371498 -230.51008) (xy 53.487577 -230.51008) (xy 53.491612 -230.434376) (xy 53.503671 -230.359531)
			(xy 53.523617 -230.28639) (xy 53.551224 -230.215785) (xy 53.58618 -230.148514) (xy 53.628088 -230.085339)
			(xy 53.676474 -230.026977) (xy 53.73079 -229.974089) (xy 53.790419 -229.927274) (xy 53.854687 -229.887062)
			(xy 53.922864 -229.85391) (xy 53.99418 -229.828192) (xy 54.067825 -229.8102) (xy 54.142965 -229.800138)
			(xy 54.218749 -229.798119) (xy 54.294319 -229.804168) (xy 54.368817 -229.818215) (xy 54.4414 -229.840101)
			(xy 54.511246 -229.869578) (xy 54.577563 -229.906313) (xy 54.639599 -229.949888) (xy 54.696652 -229.99981)
			(xy 54.748076 -230.055514) (xy 54.793287 -230.116369) (xy 54.831774 -230.181684) (xy 54.8631 -230.25072)
			(xy 54.88691 -230.322695) (xy 54.902935 -230.396793) (xy 54.910994 -230.472174) (xy 54.911498 -230.51008)
			(xy 56.027577 -230.51008) (xy 56.031612 -230.434376) (xy 56.043671 -230.359531) (xy 56.063617 -230.28639)
			(xy 56.091224 -230.215785) (xy 56.12618 -230.148514) (xy 56.168088 -230.085339) (xy 56.216474 -230.026977)
			(xy 56.27079 -229.974089) (xy 56.330419 -229.927274) (xy 56.394687 -229.887062) (xy 56.462864 -229.85391)
			(xy 56.53418 -229.828192) (xy 56.607825 -229.8102) (xy 56.682965 -229.800138) (xy 56.758749 -229.798119)
			(xy 56.834319 -229.804168) (xy 56.908817 -229.818215) (xy 56.9814 -229.840101) (xy 57.051246 -229.869578)
			(xy 57.117563 -229.906313) (xy 57.179599 -229.949888) (xy 57.236652 -229.99981) (xy 57.288076 -230.055514)
			(xy 57.333287 -230.116369) (xy 57.371774 -230.181684) (xy 57.4031 -230.25072) (xy 57.42691 -230.322695)
			(xy 57.442935 -230.396793) (xy 57.450994 -230.472174) (xy 57.451498 -230.51008) (xy 58.567577 -230.51008)
			(xy 58.571612 -230.434376) (xy 58.583671 -230.359531) (xy 58.603617 -230.28639) (xy 58.631224 -230.215785)
			(xy 58.66618 -230.148514) (xy 58.708088 -230.085339) (xy 58.756474 -230.026977) (xy 58.81079 -229.974089)
			(xy 58.870419 -229.927274) (xy 58.934687 -229.887062) (xy 59.002864 -229.85391) (xy 59.07418 -229.828192)
			(xy 59.147825 -229.8102) (xy 59.222965 -229.800138) (xy 59.298749 -229.798119) (xy 59.374319 -229.804168)
			(xy 59.448817 -229.818215) (xy 59.5214 -229.840101) (xy 59.591246 -229.869578) (xy 59.657563 -229.906313)
			(xy 59.719599 -229.949888) (xy 59.776652 -229.99981) (xy 59.828076 -230.055514) (xy 59.873287 -230.116369)
			(xy 59.911774 -230.181684) (xy 59.9431 -230.25072) (xy 59.96691 -230.322695) (xy 59.982935 -230.396793)
			(xy 59.990994 -230.472174) (xy 59.991498 -230.51008) (xy 61.107577 -230.51008) (xy 61.111612 -230.434376)
			(xy 61.123671 -230.359531) (xy 61.143617 -230.28639) (xy 61.171224 -230.215785) (xy 61.20618 -230.148514)
			(xy 61.248088 -230.085339) (xy 61.296474 -230.026977) (xy 61.35079 -229.974089) (xy 61.410419 -229.927274)
			(xy 61.474687 -229.887062) (xy 61.542864 -229.85391) (xy 61.61418 -229.828192) (xy 61.687825 -229.8102)
			(xy 61.762965 -229.800138) (xy 61.838749 -229.798119) (xy 61.914319 -229.804168) (xy 61.988817 -229.818215)
			(xy 62.0614 -229.840101) (xy 62.131246 -229.869578) (xy 62.197563 -229.906313) (xy 62.259599 -229.949888)
			(xy 62.316652 -229.99981) (xy 62.368076 -230.055514) (xy 62.413287 -230.116369) (xy 62.451774 -230.181684)
			(xy 62.4831 -230.25072) (xy 62.50691 -230.322695) (xy 62.522935 -230.396793) (xy 62.530994 -230.472174)
			(xy 62.531498 -230.51008) (xy 62.530994 -230.547986) (xy 62.522935 -230.623367) (xy 62.50691 -230.697465)
			(xy 62.4831 -230.76944) (xy 62.451774 -230.838476) (xy 62.413287 -230.903791) (xy 62.368076 -230.964646)
			(xy 62.316652 -231.02035) (xy 62.259599 -231.070272) (xy 62.197563 -231.113847) (xy 62.131246 -231.150582)
			(xy 62.0614 -231.180059) (xy 61.988817 -231.201945) (xy 61.914319 -231.215992) (xy 61.838749 -231.222041)
			(xy 61.762965 -231.220022) (xy 61.687825 -231.20996) (xy 61.61418 -231.191968) (xy 61.542864 -231.16625)
			(xy 61.474687 -231.133098) (xy 61.410419 -231.092886) (xy 61.35079 -231.046071) (xy 61.296474 -230.993183)
			(xy 61.248088 -230.934821) (xy 61.20618 -230.871646) (xy 61.171224 -230.804375) (xy 61.143617 -230.73377)
			(xy 61.123671 -230.660629) (xy 61.111612 -230.585784) (xy 61.107577 -230.51008) (xy 59.991498 -230.51008)
			(xy 59.990994 -230.547986) (xy 59.982935 -230.623367) (xy 59.96691 -230.697465) (xy 59.9431 -230.76944)
			(xy 59.911774 -230.838476) (xy 59.873287 -230.903791) (xy 59.828076 -230.964646) (xy 59.776652 -231.02035)
			(xy 59.719599 -231.070272) (xy 59.657563 -231.113847) (xy 59.591246 -231.150582) (xy 59.5214 -231.180059)
			(xy 59.448817 -231.201945) (xy 59.374319 -231.215992) (xy 59.298749 -231.222041) (xy 59.222965 -231.220022)
			(xy 59.147825 -231.20996) (xy 59.07418 -231.191968) (xy 59.002864 -231.16625) (xy 58.934687 -231.133098)
			(xy 58.870419 -231.092886) (xy 58.81079 -231.046071) (xy 58.756474 -230.993183) (xy 58.708088 -230.934821)
			(xy 58.66618 -230.871646) (xy 58.631224 -230.804375) (xy 58.603617 -230.73377) (xy 58.583671 -230.660629)
			(xy 58.571612 -230.585784) (xy 58.567577 -230.51008) (xy 57.451498 -230.51008) (xy 57.450994 -230.547986)
			(xy 57.442935 -230.623367) (xy 57.42691 -230.697465) (xy 57.4031 -230.76944) (xy 57.371774 -230.838476)
			(xy 57.333287 -230.903791) (xy 57.288076 -230.964646) (xy 57.236652 -231.02035) (xy 57.179599 -231.070272)
			(xy 57.117563 -231.113847) (xy 57.051246 -231.150582) (xy 56.9814 -231.180059) (xy 56.908817 -231.201945)
			(xy 56.834319 -231.215992) (xy 56.758749 -231.222041) (xy 56.682965 -231.220022) (xy 56.607825 -231.20996)
			(xy 56.53418 -231.191968) (xy 56.462864 -231.16625) (xy 56.394687 -231.133098) (xy 56.330419 -231.092886)
			(xy 56.27079 -231.046071) (xy 56.216474 -230.993183) (xy 56.168088 -230.934821) (xy 56.12618 -230.871646)
			(xy 56.091224 -230.804375) (xy 56.063617 -230.73377) (xy 56.043671 -230.660629) (xy 56.031612 -230.585784)
			(xy 56.027577 -230.51008) (xy 54.911498 -230.51008) (xy 54.910994 -230.547986) (xy 54.902935 -230.623367)
			(xy 54.88691 -230.697465) (xy 54.8631 -230.76944) (xy 54.831774 -230.838476) (xy 54.793287 -230.903791)
			(xy 54.748076 -230.964646) (xy 54.696652 -231.02035) (xy 54.639599 -231.070272) (xy 54.577563 -231.113847)
			(xy 54.511246 -231.150582) (xy 54.4414 -231.180059) (xy 54.368817 -231.201945) (xy 54.294319 -231.215992)
			(xy 54.218749 -231.222041) (xy 54.142965 -231.220022) (xy 54.067825 -231.20996) (xy 53.99418 -231.191968)
			(xy 53.922864 -231.16625) (xy 53.854687 -231.133098) (xy 53.790419 -231.092886) (xy 53.73079 -231.046071)
			(xy 53.676474 -230.993183) (xy 53.628088 -230.934821) (xy 53.58618 -230.871646) (xy 53.551224 -230.804375)
			(xy 53.523617 -230.73377) (xy 53.503671 -230.660629) (xy 53.491612 -230.585784) (xy 53.487577 -230.51008)
			(xy 52.371498 -230.51008) (xy 52.370994 -230.547986) (xy 52.362935 -230.623367) (xy 52.34691 -230.697465)
			(xy 52.3231 -230.76944) (xy 52.291774 -230.838476) (xy 52.253287 -230.903791) (xy 52.208076 -230.964646)
			(xy 52.156652 -231.02035) (xy 52.099599 -231.070272) (xy 52.037563 -231.113847) (xy 51.971246 -231.150582)
			(xy 51.9014 -231.180059) (xy 51.828817 -231.201945) (xy 51.754319 -231.215992) (xy 51.678749 -231.222041)
			(xy 51.602965 -231.220022) (xy 51.527825 -231.20996) (xy 51.45418 -231.191968) (xy 51.382864 -231.16625)
			(xy 51.314687 -231.133098) (xy 51.250419 -231.092886) (xy 51.19079 -231.046071) (xy 51.136474 -230.993183)
			(xy 51.088088 -230.934821) (xy 51.04618 -230.871646) (xy 51.011224 -230.804375) (xy 50.983617 -230.73377)
			(xy 50.963671 -230.660629) (xy 50.951612 -230.585784) (xy 50.947577 -230.51008) (xy 49.831498 -230.51008)
			(xy 49.830994 -230.547986) (xy 49.822935 -230.623367) (xy 49.80691 -230.697465) (xy 49.7831 -230.76944)
			(xy 49.751774 -230.838476) (xy 49.713287 -230.903791) (xy 49.668076 -230.964646) (xy 49.616652 -231.02035)
			(xy 49.559599 -231.070272) (xy 49.497563 -231.113847) (xy 49.431246 -231.150582) (xy 49.3614 -231.180059)
			(xy 49.288817 -231.201945) (xy 49.214319 -231.215992) (xy 49.138749 -231.222041) (xy 49.062965 -231.220022)
			(xy 48.987825 -231.20996) (xy 48.91418 -231.191968) (xy 48.842864 -231.16625) (xy 48.774687 -231.133098)
			(xy 48.710419 -231.092886) (xy 48.65079 -231.046071) (xy 48.596474 -230.993183) (xy 48.548088 -230.934821)
			(xy 48.50618 -230.871646) (xy 48.471224 -230.804375) (xy 48.443617 -230.73377) (xy 48.423671 -230.660629)
			(xy 48.411612 -230.585784) (xy 48.407577 -230.51008) (xy 47.291498 -230.51008) (xy 47.290994 -230.547986)
			(xy 47.282935 -230.623367) (xy 47.26691 -230.697465) (xy 47.2431 -230.76944) (xy 47.211774 -230.838476)
			(xy 47.173287 -230.903791) (xy 47.128076 -230.964646) (xy 47.076652 -231.02035) (xy 47.019599 -231.070272)
			(xy 46.957563 -231.113847) (xy 46.891246 -231.150582) (xy 46.8214 -231.180059) (xy 46.748817 -231.201945)
			(xy 46.674319 -231.215992) (xy 46.598749 -231.222041) (xy 46.522965 -231.220022) (xy 46.447825 -231.20996)
			(xy 46.37418 -231.191968) (xy 46.302864 -231.16625) (xy 46.234687 -231.133098) (xy 46.170419 -231.092886)
			(xy 46.11079 -231.046071) (xy 46.056474 -230.993183) (xy 46.008088 -230.934821) (xy 45.96618 -230.871646)
			(xy 45.931224 -230.804375) (xy 45.903617 -230.73377) (xy 45.883671 -230.660629) (xy 45.871612 -230.585784)
			(xy 45.867577 -230.51008) (xy 44.751498 -230.51008) (xy 44.750994 -230.547986) (xy 44.742935 -230.623367)
			(xy 44.72691 -230.697465) (xy 44.7031 -230.76944) (xy 44.671774 -230.838476) (xy 44.633287 -230.903791)
			(xy 44.588076 -230.964646) (xy 44.536652 -231.02035) (xy 44.479599 -231.070272) (xy 44.417563 -231.113847)
			(xy 44.351246 -231.150582) (xy 44.2814 -231.180059) (xy 44.208817 -231.201945) (xy 44.134319 -231.215992)
			(xy 44.058749 -231.222041) (xy 43.982965 -231.220022) (xy 43.907825 -231.20996) (xy 43.83418 -231.191968)
			(xy 43.762864 -231.16625) (xy 43.694687 -231.133098) (xy 43.630419 -231.092886) (xy 43.57079 -231.046071)
			(xy 43.516474 -230.993183) (xy 43.468088 -230.934821) (xy 43.42618 -230.871646) (xy 43.391224 -230.804375)
			(xy 43.363617 -230.73377) (xy 43.343671 -230.660629) (xy 43.331612 -230.585784) (xy 43.327577 -230.51008)
			(xy 42.502604 -230.51008) (xy 42.502322 -230.510305) (xy 42.406779 -230.576254) (xy 42.306914 -230.635454)
			(xy 42.203202 -230.687623) (xy 42.096139 -230.732512) (xy 41.986233 -230.769908) (xy 41.874009 -230.799633)
			(xy 41.760003 -230.821544) (xy 41.644756 -230.835537) (xy 41.528818 -230.841546) (xy 41.412742 -230.839543)
			(xy 41.29708 -230.829535) (xy 41.182385 -230.811572) (xy 41.069202 -230.785739) (xy 40.958071 -230.752159)
			(xy 40.849522 -230.710991) (xy 40.744072 -230.662433) (xy 40.642223 -230.606716) (xy 40.54446 -230.544104)
			(xy 40.45125 -230.474897) (xy 40.363037 -230.399424) (xy 40.280241 -230.318045) (xy 40.203257 -230.231148)
			(xy 40.132452 -230.139147) (xy 40.068162 -230.04248) (xy 40.010695 -229.941608) (xy 39.960324 -229.837011)
			(xy 39.917289 -229.729188) (xy 39.881795 -229.618654) (xy 39.854012 -229.505934) (xy 39.834072 -229.391566)
			(xy 39.82207 -229.276094) (xy 39.818063 -229.16007) (xy 36.341678 -229.16007) (xy 36.361593 -229.192234)
			(xy 36.400327 -229.270023) (xy 36.431719 -229.351055) (xy 36.4555 -229.434637) (xy 36.471468 -229.520057)
			(xy 36.479486 -229.606586) (xy 36.479988 -229.650036) (xy 36.479486 -229.693486) (xy 36.471468 -229.780015)
			(xy 36.4555 -229.865435) (xy 36.431719 -229.949017) (xy 36.400327 -230.030049) (xy 36.361593 -230.107838)
			(xy 36.315846 -230.181722) (xy 36.263477 -230.251069) (xy 36.204933 -230.315289) (xy 36.140713 -230.373833)
			(xy 36.071366 -230.426202) (xy 35.997482 -230.471949) (xy 35.919693 -230.510683) (xy 35.838661 -230.542075)
			(xy 35.755079 -230.565856) (xy 35.669659 -230.581824) (xy 35.58313 -230.589842) (xy 35.49623 -230.589842)
			(xy 35.409701 -230.581824) (xy 35.324281 -230.565856) (xy 35.240699 -230.542075) (xy 35.159667 -230.510683)
			(xy 35.081878 -230.471949) (xy 35.007994 -230.426202) (xy 34.938647 -230.373833) (xy 34.874427 -230.315289)
			(xy 34.815883 -230.251069) (xy 34.763514 -230.181722) (xy 34.717767 -230.107838) (xy 34.679033 -230.030049)
			(xy 34.647641 -229.949017) (xy 34.62386 -229.865435) (xy 34.607892 -229.780015) (xy 34.599874 -229.693486)
			(xy 31.399486 -229.693486) (xy 31.391468 -229.780015) (xy 31.3755 -229.865435) (xy 31.351719 -229.949017)
			(xy 31.320327 -230.030049) (xy 31.281593 -230.107838) (xy 31.235846 -230.181722) (xy 31.183477 -230.251069)
			(xy 31.124933 -230.315289) (xy 31.060713 -230.373833) (xy 30.991366 -230.426202) (xy 30.917482 -230.471949)
			(xy 30.839693 -230.510683) (xy 30.758661 -230.542075) (xy 30.675079 -230.565856) (xy 30.589659 -230.581824)
			(xy 30.50313 -230.589842) (xy 30.41623 -230.589842) (xy 30.329701 -230.581824) (xy 30.244281 -230.565856)
			(xy 30.160699 -230.542075) (xy 30.079667 -230.510683) (xy 30.001878 -230.471949) (xy 29.927994 -230.426202)
			(xy 29.858647 -230.373833) (xy 29.794427 -230.315289) (xy 29.735883 -230.251069) (xy 29.683514 -230.181722)
			(xy 29.637767 -230.107838) (xy 29.599033 -230.030049) (xy 29.567641 -229.949017) (xy 29.54386 -229.865435)
			(xy 29.527892 -229.780015) (xy 29.519874 -229.693486) (xy 28.461716 -229.693486) (xy 28.461716 -231.95407)
			(xy 22.461126 -237.954566) (xy 44.324776 -237.954566) (xy 44.328847 -237.898944) (xy 44.340973 -237.844507)
			(xy 44.360896 -237.792416) (xy 44.388192 -237.743781) (xy 44.422278 -237.699638) (xy 44.462427 -237.660929)
			(xy 44.507785 -237.628478) (xy 44.557385 -237.602977) (xy 44.610169 -237.58497) (xy 44.665012 -237.57484)
			(xy 44.720746 -237.572803) (xy 44.776183 -237.578903) (xy 44.83014 -237.593009) (xy 44.881469 -237.614821)
			(xy 44.929075 -237.643875) (xy 44.971943 -237.67955) (xy 45.00916 -237.721087) (xy 45.039933 -237.7676)
			(xy 45.063605 -237.818097) (xy 45.079673 -237.871504) (xy 45.087793 -237.92668) (xy 45.088302 -237.954566)
			(xy 45.087793 -237.982452) (xy 45.079673 -238.037628) (xy 45.063605 -238.091035) (xy 45.039933 -238.141532)
			(xy 45.00916 -238.188045) (xy 44.971943 -238.229582) (xy 44.929075 -238.265257) (xy 44.881469 -238.294311)
			(xy 44.83014 -238.316123) (xy 44.776183 -238.330229) (xy 44.720746 -238.336329) (xy 44.665012 -238.334292)
			(xy 44.610169 -238.324162) (xy 44.557385 -238.306155) (xy 44.507785 -238.280654) (xy 44.462427 -238.248203)
			(xy 44.422278 -238.209494) (xy 44.388192 -238.165351) (xy 44.360896 -238.116716) (xy 44.340973 -238.064625)
			(xy 44.328847 -238.010188) (xy 44.324776 -237.954566) (xy 22.461126 -237.954566) (xy 21.289405 -239.126268)
			(xy 71.041258 -239.126268) (xy 71.045329 -239.070646) (xy 71.057455 -239.016209) (xy 71.077378 -238.964118)
			(xy 71.104674 -238.915483) (xy 71.13876 -238.87134) (xy 71.178909 -238.832631) (xy 71.224267 -238.80018)
			(xy 71.273867 -238.774679) (xy 71.326651 -238.756672) (xy 71.381494 -238.746542) (xy 71.437228 -238.744505)
			(xy 71.492665 -238.750605) (xy 71.546622 -238.764711) (xy 71.597951 -238.786523) (xy 71.645557 -238.815577)
			(xy 71.688425 -238.851252) (xy 71.725642 -238.892789) (xy 71.756415 -238.939302) (xy 71.780087 -238.989799)
			(xy 71.796155 -239.043206) (xy 71.804275 -239.098382) (xy 71.804784 -239.126268) (xy 72.229978 -239.126268)
			(xy 72.234049 -239.070646) (xy 72.246175 -239.016209) (xy 72.266098 -238.964118) (xy 72.293394 -238.915483)
			(xy 72.32748 -238.87134) (xy 72.367629 -238.832631) (xy 72.412987 -238.80018) (xy 72.462587 -238.774679)
			(xy 72.515371 -238.756672) (xy 72.570214 -238.746542) (xy 72.625948 -238.744505) (xy 72.681385 -238.750605)
			(xy 72.735342 -238.764711) (xy 72.786671 -238.786523) (xy 72.834277 -238.815577) (xy 72.877145 -238.851252)
			(xy 72.914362 -238.892789) (xy 72.945135 -238.939302) (xy 72.968807 -238.989799) (xy 72.984875 -239.043206)
			(xy 72.992995 -239.098382) (xy 72.993504 -239.126268) (xy 72.992995 -239.154154) (xy 72.984875 -239.20933)
			(xy 72.968807 -239.262737) (xy 72.945135 -239.313234) (xy 72.914362 -239.359747) (xy 72.877145 -239.401284)
			(xy 72.834277 -239.436959) (xy 72.786671 -239.466013) (xy 72.735342 -239.487825) (xy 72.681385 -239.501931)
			(xy 72.625948 -239.508031) (xy 72.570214 -239.505994) (xy 72.515371 -239.495864) (xy 72.462587 -239.477857)
			(xy 72.412987 -239.452356) (xy 72.367629 -239.419905) (xy 72.32748 -239.381196) (xy 72.293394 -239.337053)
			(xy 72.266098 -239.288418) (xy 72.246175 -239.236327) (xy 72.234049 -239.18189) (xy 72.229978 -239.126268)
			(xy 71.804784 -239.126268) (xy 71.804275 -239.154154) (xy 71.796155 -239.20933) (xy 71.780087 -239.262737)
			(xy 71.756415 -239.313234) (xy 71.725642 -239.359747) (xy 71.688425 -239.401284) (xy 71.645557 -239.436959)
			(xy 71.597951 -239.466013) (xy 71.546622 -239.487825) (xy 71.492665 -239.501931) (xy 71.437228 -239.508031)
			(xy 71.381494 -239.505994) (xy 71.326651 -239.495864) (xy 71.273867 -239.477857) (xy 71.224267 -239.452356)
			(xy 71.178909 -239.419905) (xy 71.13876 -239.381196) (xy 71.104674 -239.337053) (xy 71.077378 -239.288418)
			(xy 71.057455 -239.236327) (xy 71.045329 -239.18189) (xy 71.041258 -239.126268) (xy 21.289405 -239.126268)
			(xy 20.503263 -239.912398) (xy 44.319188 -239.912398) (xy 44.323259 -239.856776) (xy 44.335385 -239.802339)
			(xy 44.355308 -239.750248) (xy 44.382604 -239.701613) (xy 44.41669 -239.65747) (xy 44.456839 -239.618761)
			(xy 44.502197 -239.58631) (xy 44.551797 -239.560809) (xy 44.604581 -239.542802) (xy 44.659424 -239.532672)
			(xy 44.715158 -239.530635) (xy 44.770595 -239.536735) (xy 44.824552 -239.550841) (xy 44.875881 -239.572653)
			(xy 44.923487 -239.601707) (xy 44.966355 -239.637382) (xy 45.003572 -239.678919) (xy 45.034345 -239.725432)
			(xy 45.058017 -239.775929) (xy 45.074085 -239.829336) (xy 45.082205 -239.884512) (xy 45.082714 -239.912398)
			(xy 45.082205 -239.940284) (xy 45.074085 -239.99546) (xy 45.058017 -240.048867) (xy 45.034345 -240.099364)
			(xy 45.003572 -240.145877) (xy 44.966355 -240.187414) (xy 44.923487 -240.223089) (xy 44.875881 -240.252143)
			(xy 44.824552 -240.273955) (xy 44.770595 -240.288061) (xy 44.715158 -240.294161) (xy 44.659424 -240.292124)
			(xy 44.604581 -240.281994) (xy 44.551797 -240.263987) (xy 44.502197 -240.238486) (xy 44.456839 -240.206035)
			(xy 44.41669 -240.167326) (xy 44.382604 -240.123183) (xy 44.355308 -240.074548) (xy 44.335385 -240.022457)
			(xy 44.323259 -239.96802) (xy 44.319188 -239.912398) (xy 20.503263 -239.912398) (xy 19.539572 -240.876074)
			(xy 46.426118 -240.876074) (xy 46.430189 -240.820452) (xy 46.442315 -240.766015) (xy 46.462238 -240.713924)
			(xy 46.489534 -240.665289) (xy 46.52362 -240.621146) (xy 46.563769 -240.582437) (xy 46.609127 -240.549986)
			(xy 46.658727 -240.524485) (xy 46.711511 -240.506478) (xy 46.766354 -240.496348) (xy 46.822088 -240.494311)
			(xy 46.877525 -240.500411) (xy 46.931482 -240.514517) (xy 46.982811 -240.536329) (xy 47.030417 -240.565383)
			(xy 47.073285 -240.601058) (xy 47.099094 -240.629863) (xy 49.037484 -240.629863) (xy 49.037484 -240.548753)
			(xy 49.045434 -240.468034) (xy 49.061257 -240.388483) (xy 49.084802 -240.310867) (xy 49.115841 -240.235931)
			(xy 49.154076 -240.164399) (xy 49.199138 -240.096959) (xy 49.250593 -240.03426) (xy 49.307946 -239.976907)
			(xy 49.370645 -239.925452) (xy 49.438085 -239.88039) (xy 49.509617 -239.842155) (xy 49.584553 -239.811116)
			(xy 49.662169 -239.787571) (xy 49.74172 -239.771748) (xy 49.822439 -239.763798) (xy 49.903549 -239.763798)
			(xy 49.984268 -239.771748) (xy 50.063819 -239.787571) (xy 50.141435 -239.811116) (xy 50.216371 -239.842155)
			(xy 50.287903 -239.88039) (xy 50.355343 -239.925452) (xy 50.410622 -239.970818) (xy 69.713346 -239.970818)
			(xy 69.717417 -239.915196) (xy 69.729543 -239.860759) (xy 69.749466 -239.808668) (xy 69.776762 -239.760033)
			(xy 69.810848 -239.71589) (xy 69.850997 -239.677181) (xy 69.896355 -239.64473) (xy 69.945955 -239.619229)
			(xy 69.998739 -239.601222) (xy 70.053582 -239.591092) (xy 70.109316 -239.589055) (xy 70.164753 -239.595155)
			(xy 70.21871 -239.609261) (xy 70.270039 -239.631073) (xy 70.317645 -239.660127) (xy 70.360513 -239.695802)
			(xy 70.39773 -239.737339) (xy 70.428503 -239.783852) (xy 70.452175 -239.834349) (xy 70.468243 -239.887756)
			(xy 70.476363 -239.942932) (xy 70.476872 -239.970818) (xy 70.476363 -239.998704) (xy 70.468243 -240.05388)
			(xy 70.452175 -240.107287) (xy 70.428503 -240.157784) (xy 70.39773 -240.204297) (xy 70.360513 -240.245834)
			(xy 70.317645 -240.281509) (xy 70.270039 -240.310563) (xy 70.21871 -240.332375) (xy 70.164753 -240.346481)
			(xy 70.109316 -240.352581) (xy 70.053582 -240.350544) (xy 69.998739 -240.340414) (xy 69.945955 -240.322407)
			(xy 69.896355 -240.296906) (xy 69.850997 -240.264455) (xy 69.810848 -240.225746) (xy 69.776762 -240.181603)
			(xy 69.749466 -240.132968) (xy 69.729543 -240.080877) (xy 69.717417 -240.02644) (xy 69.713346 -239.970818)
			(xy 50.410622 -239.970818) (xy 50.418042 -239.976907) (xy 50.475395 -240.03426) (xy 50.52685 -240.096959)
			(xy 50.571912 -240.164399) (xy 50.610147 -240.235931) (xy 50.641186 -240.310867) (xy 50.664731 -240.388483)
			(xy 50.680554 -240.468034) (xy 50.688504 -240.548753) (xy 50.689002 -240.589308) (xy 50.688504 -240.629863)
			(xy 50.680554 -240.710582) (xy 50.664731 -240.790133) (xy 50.641186 -240.867749) (xy 50.610147 -240.942685)
			(xy 50.571912 -241.014217) (xy 50.52685 -241.081657) (xy 50.475395 -241.144356) (xy 50.418042 -241.201709)
			(xy 50.355343 -241.253164) (xy 50.287903 -241.298226) (xy 50.216371 -241.336461) (xy 50.141435 -241.3675)
			(xy 50.063819 -241.391045) (xy 49.984268 -241.406868) (xy 49.903549 -241.414818) (xy 49.822439 -241.414818)
			(xy 49.74172 -241.406868) (xy 49.662169 -241.391045) (xy 49.584553 -241.3675) (xy 49.509617 -241.336461)
			(xy 49.438085 -241.298226) (xy 49.370645 -241.253164) (xy 49.307946 -241.201709) (xy 49.250593 -241.144356)
			(xy 49.199138 -241.081657) (xy 49.154076 -241.014217) (xy 49.115841 -240.942685) (xy 49.084802 -240.867749)
			(xy 49.061257 -240.790133) (xy 49.045434 -240.710582) (xy 49.037484 -240.629863) (xy 47.099094 -240.629863)
			(xy 47.110502 -240.642595) (xy 47.141275 -240.689108) (xy 47.164947 -240.739605) (xy 47.181015 -240.793012)
			(xy 47.189135 -240.848188) (xy 47.189644 -240.876074) (xy 47.189135 -240.90396) (xy 47.181015 -240.959136)
			(xy 47.164947 -241.012543) (xy 47.141275 -241.06304) (xy 47.110502 -241.109553) (xy 47.073285 -241.15109)
			(xy 47.030417 -241.186765) (xy 46.982811 -241.215819) (xy 46.931482 -241.237631) (xy 46.877525 -241.251737)
			(xy 46.822088 -241.257837) (xy 46.766354 -241.2558) (xy 46.711511 -241.24567) (xy 46.658727 -241.227663)
			(xy 46.609127 -241.202162) (xy 46.563769 -241.169711) (xy 46.52362 -241.131002) (xy 46.489534 -241.086859)
			(xy 46.462238 -241.038224) (xy 46.442315 -240.986133) (xy 46.430189 -240.931696) (xy 46.426118 -240.876074)
			(xy 19.539572 -240.876074) (xy 18.456652 -241.958977) (xy 58.125098 -241.958977) (xy 58.125098 -241.887655)
			(xy 58.133084 -241.816781) (xy 58.148954 -241.747246) (xy 58.172511 -241.679926) (xy 58.203456 -241.615667)
			(xy 58.241402 -241.555276) (xy 58.285871 -241.499514) (xy 58.336304 -241.449081) (xy 58.392066 -241.404612)
			(xy 58.452457 -241.366666) (xy 58.516716 -241.335721) (xy 58.584036 -241.312164) (xy 58.653571 -241.296294)
			(xy 58.724445 -241.288308) (xy 58.795767 -241.288308) (xy 58.866641 -241.296294) (xy 58.936176 -241.312164)
			(xy 59.003496 -241.335721) (xy 59.067755 -241.366666) (xy 59.128146 -241.404612) (xy 59.183908 -241.449081)
			(xy 59.234341 -241.499514) (xy 59.27881 -241.555276) (xy 59.316756 -241.615667) (xy 59.347701 -241.679926)
			(xy 59.371258 -241.747246) (xy 59.387128 -241.816781) (xy 59.395114 -241.887655) (xy 59.395614 -241.923316)
			(xy 59.395114 -241.958977) (xy 60.01181 -241.958977) (xy 60.01181 -241.887655) (xy 60.019796 -241.816781)
			(xy 60.035666 -241.747246) (xy 60.059223 -241.679926) (xy 60.090168 -241.615667) (xy 60.128114 -241.555276)
			(xy 60.172583 -241.499514) (xy 60.223016 -241.449081) (xy 60.278778 -241.404612) (xy 60.339169 -241.366666)
			(xy 60.403428 -241.335721) (xy 60.470748 -241.312164) (xy 60.540283 -241.296294) (xy 60.611157 -241.288308)
			(xy 60.682479 -241.288308) (xy 60.753353 -241.296294) (xy 60.822888 -241.312164) (xy 60.890208 -241.335721)
			(xy 60.954467 -241.366666) (xy 61.014858 -241.404612) (xy 61.07062 -241.449081) (xy 61.121053 -241.499514)
			(xy 61.165522 -241.555276) (xy 61.203468 -241.615667) (xy 61.234413 -241.679926) (xy 61.25797 -241.747246)
			(xy 61.27384 -241.816781) (xy 61.281826 -241.887655) (xy 61.282326 -241.923316) (xy 61.281826 -241.958977)
			(xy 61.27384 -242.029851) (xy 61.25797 -242.099386) (xy 61.234413 -242.166706) (xy 61.203468 -242.230965)
			(xy 61.165522 -242.291356) (xy 61.121053 -242.347118) (xy 61.07062 -242.397551) (xy 61.014858 -242.44202)
			(xy 60.954467 -242.479966) (xy 60.890208 -242.510911) (xy 60.822888 -242.534468) (xy 60.753353 -242.550338)
			(xy 60.682479 -242.558324) (xy 60.611157 -242.558324) (xy 60.540283 -242.550338) (xy 60.470748 -242.534468)
			(xy 60.403428 -242.510911) (xy 60.339169 -242.479966) (xy 60.278778 -242.44202) (xy 60.223016 -242.397551)
			(xy 60.172583 -242.347118) (xy 60.128114 -242.291356) (xy 60.090168 -242.230965) (xy 60.059223 -242.166706)
			(xy 60.035666 -242.099386) (xy 60.019796 -242.029851) (xy 60.01181 -241.958977) (xy 59.395114 -241.958977)
			(xy 59.387128 -242.029851) (xy 59.371258 -242.099386) (xy 59.347701 -242.166706) (xy 59.316756 -242.230965)
			(xy 59.27881 -242.291356) (xy 59.234341 -242.347118) (xy 59.183908 -242.397551) (xy 59.128146 -242.44202)
			(xy 59.067755 -242.479966) (xy 59.003496 -242.510911) (xy 58.936176 -242.534468) (xy 58.866641 -242.550338)
			(xy 58.795767 -242.558324) (xy 58.724445 -242.558324) (xy 58.653571 -242.550338) (xy 58.584036 -242.534468)
			(xy 58.516716 -242.510911) (xy 58.452457 -242.479966) (xy 58.392066 -242.44202) (xy 58.336304 -242.397551)
			(xy 58.285871 -242.347118) (xy 58.241402 -242.291356) (xy 58.203456 -242.230965) (xy 58.172511 -242.166706)
			(xy 58.148954 -242.099386) (xy 58.133084 -242.029851) (xy 58.125098 -241.958977) (xy 18.456652 -241.958977)
			(xy 17.60076 -242.814856) (xy 44.210476 -242.814856) (xy 44.214547 -242.759234) (xy 44.226673 -242.704797)
			(xy 44.246596 -242.652706) (xy 44.273892 -242.604071) (xy 44.307978 -242.559928) (xy 44.348127 -242.521219)
			(xy 44.393485 -242.488768) (xy 44.443085 -242.463267) (xy 44.495869 -242.44526) (xy 44.550712 -242.43513)
			(xy 44.606446 -242.433093) (xy 44.661883 -242.439193) (xy 44.71584 -242.453299) (xy 44.767169 -242.475111)
			(xy 44.814775 -242.504165) (xy 44.857643 -242.53984) (xy 44.89486 -242.581377) (xy 44.925633 -242.62789)
			(xy 44.949305 -242.678387) (xy 44.965373 -242.731794) (xy 44.973493 -242.78697) (xy 44.974002 -242.814856)
			(xy 44.973493 -242.842742) (xy 44.965373 -242.897918) (xy 44.949305 -242.951325) (xy 44.925633 -243.001822)
			(xy 44.89486 -243.048335) (xy 44.857643 -243.089872) (xy 44.814775 -243.125547) (xy 44.767169 -243.154601)
			(xy 44.71584 -243.176413) (xy 44.661883 -243.190519) (xy 44.606446 -243.196619) (xy 44.550712 -243.194582)
			(xy 44.495869 -243.184452) (xy 44.443085 -243.166445) (xy 44.393485 -243.140944) (xy 44.348127 -243.108493)
			(xy 44.307978 -243.069784) (xy 44.273892 -243.025641) (xy 44.246596 -242.977006) (xy 44.226673 -242.924915)
			(xy 44.214547 -242.870478) (xy 44.210476 -242.814856) (xy 17.60076 -242.814856) (xy 16.622998 -243.792603)
			(xy 58.125098 -243.792603) (xy 58.125098 -243.721281) (xy 58.133084 -243.650407) (xy 58.148954 -243.580872)
			(xy 58.172511 -243.513552) (xy 58.203456 -243.449293) (xy 58.241402 -243.388902) (xy 58.285871 -243.33314)
			(xy 58.336304 -243.282707) (xy 58.392066 -243.238238) (xy 58.452457 -243.200292) (xy 58.516716 -243.169347)
			(xy 58.584036 -243.14579) (xy 58.653571 -243.12992) (xy 58.724445 -243.121934) (xy 58.795767 -243.121934)
			(xy 58.866641 -243.12992) (xy 58.936176 -243.14579) (xy 59.003496 -243.169347) (xy 59.067755 -243.200292)
			(xy 59.128146 -243.238238) (xy 59.183908 -243.282707) (xy 59.234341 -243.33314) (xy 59.27881 -243.388902)
			(xy 59.316756 -243.449293) (xy 59.347701 -243.513552) (xy 59.371258 -243.580872) (xy 59.387128 -243.650407)
			(xy 59.395114 -243.721281) (xy 59.395614 -243.756942) (xy 59.395114 -243.792603) (xy 60.01181 -243.792603)
			(xy 60.01181 -243.721281) (xy 60.019796 -243.650407) (xy 60.035666 -243.580872) (xy 60.059223 -243.513552)
			(xy 60.090168 -243.449293) (xy 60.128114 -243.388902) (xy 60.172583 -243.33314) (xy 60.223016 -243.282707)
			(xy 60.278778 -243.238238) (xy 60.339169 -243.200292) (xy 60.403428 -243.169347) (xy 60.470748 -243.14579)
			(xy 60.540283 -243.12992) (xy 60.611157 -243.121934) (xy 60.682479 -243.121934) (xy 60.753353 -243.12992)
			(xy 60.822888 -243.14579) (xy 60.890208 -243.169347) (xy 60.954467 -243.200292) (xy 61.014858 -243.238238)
			(xy 61.07062 -243.282707) (xy 61.121053 -243.33314) (xy 61.165522 -243.388902) (xy 61.203468 -243.449293)
			(xy 61.234413 -243.513552) (xy 61.25797 -243.580872) (xy 61.27384 -243.650407) (xy 61.281826 -243.721281)
			(xy 61.282326 -243.756942) (xy 61.281826 -243.792603) (xy 62.252852 -243.792603) (xy 62.252852 -243.721281)
			(xy 62.260838 -243.650407) (xy 62.276708 -243.580872) (xy 62.300265 -243.513552) (xy 62.33121 -243.449293)
			(xy 62.369156 -243.388902) (xy 62.413625 -243.33314) (xy 62.464058 -243.282707) (xy 62.51982 -243.238238)
			(xy 62.580211 -243.200292) (xy 62.64447 -243.169347) (xy 62.71179 -243.14579) (xy 62.781325 -243.12992)
			(xy 62.852199 -243.121934) (xy 62.923521 -243.121934) (xy 62.994395 -243.12992) (xy 63.06393 -243.14579)
			(xy 63.13125 -243.169347) (xy 63.195509 -243.200292) (xy 63.2559 -243.238238) (xy 63.311662 -243.282707)
			(xy 63.362095 -243.33314) (xy 63.406564 -243.388902) (xy 63.44451 -243.449293) (xy 63.475455 -243.513552)
			(xy 63.499012 -243.580872) (xy 63.514882 -243.650407) (xy 63.522868 -243.721281) (xy 63.523368 -243.756942)
			(xy 63.522868 -243.792603) (xy 64.156836 -243.792603) (xy 64.156836 -243.721281) (xy 64.164822 -243.650407)
			(xy 64.180692 -243.580872) (xy 64.204249 -243.513552) (xy 64.235194 -243.449293) (xy 64.27314 -243.388902)
			(xy 64.317609 -243.33314) (xy 64.368042 -243.282707) (xy 64.423804 -243.238238) (xy 64.484195 -243.200292)
			(xy 64.548454 -243.169347) (xy 64.615774 -243.14579) (xy 64.685309 -243.12992) (xy 64.756183 -243.121934)
			(xy 64.827505 -243.121934) (xy 64.898379 -243.12992) (xy 64.967914 -243.14579) (xy 65.035234 -243.169347)
			(xy 65.099493 -243.200292) (xy 65.159884 -243.238238) (xy 65.215646 -243.282707) (xy 65.266079 -243.33314)
			(xy 65.310548 -243.388902) (xy 65.348494 -243.449293) (xy 65.379439 -243.513552) (xy 65.402996 -243.580872)
			(xy 65.418866 -243.650407) (xy 65.426852 -243.721281) (xy 65.427352 -243.756942) (xy 65.426852 -243.792603)
			(xy 65.418866 -243.863477) (xy 65.402996 -243.933012) (xy 65.379439 -244.000332) (xy 65.348494 -244.064591)
			(xy 65.310548 -244.124982) (xy 65.266079 -244.180744) (xy 65.215646 -244.231177) (xy 65.159884 -244.275646)
			(xy 65.099493 -244.313592) (xy 65.035234 -244.344537) (xy 64.967914 -244.368094) (xy 64.898379 -244.383964)
			(xy 64.827505 -244.39195) (xy 64.756183 -244.39195) (xy 64.685309 -244.383964) (xy 64.615774 -244.368094)
			(xy 64.548454 -244.344537) (xy 64.484195 -244.313592) (xy 64.423804 -244.275646) (xy 64.368042 -244.231177)
			(xy 64.317609 -244.180744) (xy 64.27314 -244.124982) (xy 64.235194 -244.064591) (xy 64.204249 -244.000332)
			(xy 64.180692 -243.933012) (xy 64.164822 -243.863477) (xy 64.156836 -243.792603) (xy 63.522868 -243.792603)
			(xy 63.514882 -243.863477) (xy 63.499012 -243.933012) (xy 63.475455 -244.000332) (xy 63.44451 -244.064591)
			(xy 63.406564 -244.124982) (xy 63.362095 -244.180744) (xy 63.311662 -244.231177) (xy 63.2559 -244.275646)
			(xy 63.195509 -244.313592) (xy 63.13125 -244.344537) (xy 63.06393 -244.368094) (xy 62.994395 -244.383964)
			(xy 62.923521 -244.39195) (xy 62.852199 -244.39195) (xy 62.781325 -244.383964) (xy 62.71179 -244.368094)
			(xy 62.64447 -244.344537) (xy 62.580211 -244.313592) (xy 62.51982 -244.275646) (xy 62.464058 -244.231177)
			(xy 62.413625 -244.180744) (xy 62.369156 -244.124982) (xy 62.33121 -244.064591) (xy 62.300265 -244.000332)
			(xy 62.276708 -243.933012) (xy 62.260838 -243.863477) (xy 62.252852 -243.792603) (xy 61.281826 -243.792603)
			(xy 61.27384 -243.863477) (xy 61.25797 -243.933012) (xy 61.234413 -244.000332) (xy 61.203468 -244.064591)
			(xy 61.165522 -244.124982) (xy 61.121053 -244.180744) (xy 61.07062 -244.231177) (xy 61.014858 -244.275646)
			(xy 60.954467 -244.313592) (xy 60.890208 -244.344537) (xy 60.822888 -244.368094) (xy 60.753353 -244.383964)
			(xy 60.682479 -244.39195) (xy 60.611157 -244.39195) (xy 60.540283 -244.383964) (xy 60.470748 -244.368094)
			(xy 60.403428 -244.344537) (xy 60.339169 -244.313592) (xy 60.278778 -244.275646) (xy 60.223016 -244.231177)
			(xy 60.172583 -244.180744) (xy 60.128114 -244.124982) (xy 60.090168 -244.064591) (xy 60.059223 -244.000332)
			(xy 60.035666 -243.933012) (xy 60.019796 -243.863477) (xy 60.01181 -243.792603) (xy 59.395114 -243.792603)
			(xy 59.387128 -243.863477) (xy 59.371258 -243.933012) (xy 59.347701 -244.000332) (xy 59.316756 -244.064591)
			(xy 59.27881 -244.124982) (xy 59.234341 -244.180744) (xy 59.183908 -244.231177) (xy 59.128146 -244.275646)
			(xy 59.067755 -244.313592) (xy 59.003496 -244.344537) (xy 58.936176 -244.368094) (xy 58.866641 -244.383964)
			(xy 58.795767 -244.39195) (xy 58.724445 -244.39195) (xy 58.653571 -244.383964) (xy 58.584036 -244.368094)
			(xy 58.516716 -244.344537) (xy 58.452457 -244.313592) (xy 58.392066 -244.275646) (xy 58.336304 -244.231177)
			(xy 58.285871 -244.180744) (xy 58.241402 -244.124982) (xy 58.203456 -244.064591) (xy 58.172511 -244.000332)
			(xy 58.148954 -243.933012) (xy 58.133084 -243.863477) (xy 58.125098 -243.792603) (xy 16.622998 -243.792603)
			(xy 15.690142 -244.725444) (xy 44.159168 -244.725444) (xy 44.163239 -244.669822) (xy 44.175365 -244.615385)
			(xy 44.195288 -244.563294) (xy 44.222584 -244.514659) (xy 44.25667 -244.470516) (xy 44.296819 -244.431807)
			(xy 44.342177 -244.399356) (xy 44.391777 -244.373855) (xy 44.444561 -244.355848) (xy 44.499404 -244.345718)
			(xy 44.555138 -244.343681) (xy 44.610575 -244.349781) (xy 44.664532 -244.363887) (xy 44.715861 -244.385699)
			(xy 44.763467 -244.414753) (xy 44.806335 -244.450428) (xy 44.843552 -244.491965) (xy 44.874325 -244.538478)
			(xy 44.897997 -244.588975) (xy 44.914065 -244.642382) (xy 44.922185 -244.697558) (xy 44.922694 -244.725444)
			(xy 44.922185 -244.75333) (xy 44.914065 -244.808506) (xy 44.897997 -244.861913) (xy 44.874325 -244.91241)
			(xy 44.843552 -244.958923) (xy 44.806335 -245.00046) (xy 44.763467 -245.036135) (xy 44.715861 -245.065189)
			(xy 44.664532 -245.087001) (xy 44.610575 -245.101107) (xy 44.555138 -245.107207) (xy 44.499404 -245.10517)
			(xy 44.444561 -245.09504) (xy 44.391777 -245.077033) (xy 44.342177 -245.051532) (xy 44.296819 -245.019081)
			(xy 44.25667 -244.980372) (xy 44.222584 -244.936229) (xy 44.195288 -244.887594) (xy 44.175365 -244.835503)
			(xy 44.163239 -244.781066) (xy 44.159168 -244.725444) (xy 15.690142 -244.725444) (xy 14.703336 -245.712234)
			(xy 46.403766 -245.712234) (xy 46.407837 -245.656612) (xy 46.419963 -245.602175) (xy 46.439886 -245.550084)
			(xy 46.467182 -245.501449) (xy 46.501268 -245.457306) (xy 46.541417 -245.418597) (xy 46.586775 -245.386146)
			(xy 46.636375 -245.360645) (xy 46.689159 -245.342638) (xy 46.744002 -245.332508) (xy 46.799736 -245.330471)
			(xy 46.855173 -245.336571) (xy 46.90913 -245.350677) (xy 46.960459 -245.372489) (xy 47.008065 -245.401543)
			(xy 47.050933 -245.437218) (xy 47.08815 -245.478755) (xy 47.118923 -245.525268) (xy 47.142595 -245.575765)
			(xy 47.158663 -245.629172) (xy 47.166783 -245.684348) (xy 47.166951 -245.693539) (xy 58.125098 -245.693539)
			(xy 58.125098 -245.622217) (xy 58.133084 -245.551343) (xy 58.148954 -245.481808) (xy 58.172511 -245.414488)
			(xy 58.203456 -245.350229) (xy 58.241402 -245.289838) (xy 58.285871 -245.234076) (xy 58.336304 -245.183643)
			(xy 58.392066 -245.139174) (xy 58.452457 -245.101228) (xy 58.516716 -245.070283) (xy 58.584036 -245.046726)
			(xy 58.653571 -245.030856) (xy 58.724445 -245.02287) (xy 58.795767 -245.02287) (xy 58.866641 -245.030856)
			(xy 58.936176 -245.046726) (xy 59.003496 -245.070283) (xy 59.067755 -245.101228) (xy 59.128146 -245.139174)
			(xy 59.183908 -245.183643) (xy 59.234341 -245.234076) (xy 59.27881 -245.289838) (xy 59.316756 -245.350229)
			(xy 59.347701 -245.414488) (xy 59.371258 -245.481808) (xy 59.387128 -245.551343) (xy 59.395114 -245.622217)
			(xy 59.395614 -245.657878) (xy 59.395114 -245.693539) (xy 60.01181 -245.693539) (xy 60.01181 -245.622217)
			(xy 60.019796 -245.551343) (xy 60.035666 -245.481808) (xy 60.059223 -245.414488) (xy 60.090168 -245.350229)
			(xy 60.128114 -245.289838) (xy 60.172583 -245.234076) (xy 60.223016 -245.183643) (xy 60.278778 -245.139174)
			(xy 60.339169 -245.101228) (xy 60.403428 -245.070283) (xy 60.470748 -245.046726) (xy 60.540283 -245.030856)
			(xy 60.611157 -245.02287) (xy 60.682479 -245.02287) (xy 60.753353 -245.030856) (xy 60.822888 -245.046726)
			(xy 60.890208 -245.070283) (xy 60.954467 -245.101228) (xy 61.014858 -245.139174) (xy 61.07062 -245.183643)
			(xy 61.121053 -245.234076) (xy 61.165522 -245.289838) (xy 61.203468 -245.350229) (xy 61.234413 -245.414488)
			(xy 61.25797 -245.481808) (xy 61.27384 -245.551343) (xy 61.281826 -245.622217) (xy 61.282326 -245.657878)
			(xy 61.281826 -245.693539) (xy 62.252852 -245.693539) (xy 62.252852 -245.622217) (xy 62.260838 -245.551343)
			(xy 62.276708 -245.481808) (xy 62.300265 -245.414488) (xy 62.33121 -245.350229) (xy 62.369156 -245.289838)
			(xy 62.413625 -245.234076) (xy 62.464058 -245.183643) (xy 62.51982 -245.139174) (xy 62.580211 -245.101228)
			(xy 62.64447 -245.070283) (xy 62.71179 -245.046726) (xy 62.781325 -245.030856) (xy 62.852199 -245.02287)
			(xy 62.923521 -245.02287) (xy 62.994395 -245.030856) (xy 63.06393 -245.046726) (xy 63.13125 -245.070283)
			(xy 63.195509 -245.101228) (xy 63.2559 -245.139174) (xy 63.311662 -245.183643) (xy 63.362095 -245.234076)
			(xy 63.406564 -245.289838) (xy 63.44451 -245.350229) (xy 63.475455 -245.414488) (xy 63.499012 -245.481808)
			(xy 63.514882 -245.551343) (xy 63.522868 -245.622217) (xy 63.523368 -245.657878) (xy 63.522868 -245.693539)
			(xy 64.156836 -245.693539) (xy 64.156836 -245.622217) (xy 64.164822 -245.551343) (xy 64.180692 -245.481808)
			(xy 64.204249 -245.414488) (xy 64.235194 -245.350229) (xy 64.27314 -245.289838) (xy 64.317609 -245.234076)
			(xy 64.368042 -245.183643) (xy 64.423804 -245.139174) (xy 64.484195 -245.101228) (xy 64.548454 -245.070283)
			(xy 64.615774 -245.046726) (xy 64.685309 -245.030856) (xy 64.756183 -245.02287) (xy 64.827505 -245.02287)
			(xy 64.898379 -245.030856) (xy 64.967914 -245.046726) (xy 65.035234 -245.070283) (xy 65.099493 -245.101228)
			(xy 65.159884 -245.139174) (xy 65.215646 -245.183643) (xy 65.266079 -245.234076) (xy 65.310548 -245.289838)
			(xy 65.348494 -245.350229) (xy 65.379439 -245.414488) (xy 65.402996 -245.481808) (xy 65.418866 -245.551343)
			(xy 65.426852 -245.622217) (xy 65.427352 -245.657878) (xy 65.426852 -245.693539) (xy 65.418866 -245.764413)
			(xy 65.402996 -245.833948) (xy 65.379439 -245.901268) (xy 65.348494 -245.965527) (xy 65.310548 -246.025918)
			(xy 65.266079 -246.08168) (xy 65.215646 -246.132113) (xy 65.159884 -246.176582) (xy 65.099493 -246.214528)
			(xy 65.035234 -246.245473) (xy 64.967914 -246.26903) (xy 64.898379 -246.2849) (xy 64.827505 -246.292886)
			(xy 64.756183 -246.292886) (xy 64.685309 -246.2849) (xy 64.615774 -246.26903) (xy 64.548454 -246.245473)
			(xy 64.484195 -246.214528) (xy 64.423804 -246.176582) (xy 64.368042 -246.132113) (xy 64.317609 -246.08168)
			(xy 64.27314 -246.025918) (xy 64.235194 -245.965527) (xy 64.204249 -245.901268) (xy 64.180692 -245.833948)
			(xy 64.164822 -245.764413) (xy 64.156836 -245.693539) (xy 63.522868 -245.693539) (xy 63.514882 -245.764413)
			(xy 63.499012 -245.833948) (xy 63.475455 -245.901268) (xy 63.44451 -245.965527) (xy 63.406564 -246.025918)
			(xy 63.362095 -246.08168) (xy 63.311662 -246.132113) (xy 63.2559 -246.176582) (xy 63.195509 -246.214528)
			(xy 63.13125 -246.245473) (xy 63.06393 -246.26903) (xy 62.994395 -246.2849) (xy 62.923521 -246.292886)
			(xy 62.852199 -246.292886) (xy 62.781325 -246.2849) (xy 62.71179 -246.26903) (xy 62.64447 -246.245473)
			(xy 62.580211 -246.214528) (xy 62.51982 -246.176582) (xy 62.464058 -246.132113) (xy 62.413625 -246.08168)
			(xy 62.369156 -246.025918) (xy 62.33121 -245.965527) (xy 62.300265 -245.901268) (xy 62.276708 -245.833948)
			(xy 62.260838 -245.764413) (xy 62.252852 -245.693539) (xy 61.281826 -245.693539) (xy 61.27384 -245.764413)
			(xy 61.25797 -245.833948) (xy 61.234413 -245.901268) (xy 61.203468 -245.965527) (xy 61.165522 -246.025918)
			(xy 61.121053 -246.08168) (xy 61.07062 -246.132113) (xy 61.014858 -246.176582) (xy 60.954467 -246.214528)
			(xy 60.890208 -246.245473) (xy 60.822888 -246.26903) (xy 60.753353 -246.2849) (xy 60.682479 -246.292886)
			(xy 60.611157 -246.292886) (xy 60.540283 -246.2849) (xy 60.470748 -246.26903) (xy 60.403428 -246.245473)
			(xy 60.339169 -246.214528) (xy 60.278778 -246.176582) (xy 60.223016 -246.132113) (xy 60.172583 -246.08168)
			(xy 60.128114 -246.025918) (xy 60.090168 -245.965527) (xy 60.059223 -245.901268) (xy 60.035666 -245.833948)
			(xy 60.019796 -245.764413) (xy 60.01181 -245.693539) (xy 59.395114 -245.693539) (xy 59.387128 -245.764413)
			(xy 59.371258 -245.833948) (xy 59.347701 -245.901268) (xy 59.316756 -245.965527) (xy 59.27881 -246.025918)
			(xy 59.234341 -246.08168) (xy 59.183908 -246.132113) (xy 59.128146 -246.176582) (xy 59.067755 -246.214528)
			(xy 59.003496 -246.245473) (xy 58.936176 -246.26903) (xy 58.866641 -246.2849) (xy 58.795767 -246.292886)
			(xy 58.724445 -246.292886) (xy 58.653571 -246.2849) (xy 58.584036 -246.26903) (xy 58.516716 -246.245473)
			(xy 58.452457 -246.214528) (xy 58.392066 -246.176582) (xy 58.336304 -246.132113) (xy 58.285871 -246.08168)
			(xy 58.241402 -246.025918) (xy 58.203456 -245.965527) (xy 58.172511 -245.901268) (xy 58.148954 -245.833948)
			(xy 58.133084 -245.764413) (xy 58.125098 -245.693539) (xy 47.166951 -245.693539) (xy 47.167292 -245.712234)
			(xy 47.166783 -245.74012) (xy 47.158663 -245.795296) (xy 47.142595 -245.848703) (xy 47.118923 -245.8992)
			(xy 47.08815 -245.945713) (xy 47.050933 -245.98725) (xy 47.008065 -246.022925) (xy 46.960459 -246.051979)
			(xy 46.90913 -246.073791) (xy 46.855173 -246.087897) (xy 46.799736 -246.093997) (xy 46.744002 -246.09196)
			(xy 46.689159 -246.08183) (xy 46.636375 -246.063823) (xy 46.586775 -246.038322) (xy 46.541417 -246.005871)
			(xy 46.501268 -245.967162) (xy 46.467182 -245.923019) (xy 46.439886 -245.874384) (xy 46.419963 -245.822293)
			(xy 46.407837 -245.767856) (xy 46.403766 -245.712234) (xy 14.703336 -245.712234) (xy 13.474939 -246.940612)
			(xy 25.681069 -246.940612) (xy 25.685634 -246.884923) (xy 25.69827 -246.830494) (xy 25.718709 -246.77849)
			(xy 25.746512 -246.730023) (xy 25.781086 -246.686128) (xy 25.821692 -246.647744) (xy 25.867461 -246.615691)
			(xy 25.917415 -246.590656) (xy 25.970485 -246.573173) (xy 26.025538 -246.563616) (xy 26.081396 -246.562189)
			(xy 26.136865 -246.568922) (xy 26.190759 -246.583673) (xy 26.241926 -246.606125) (xy 26.289271 -246.635799)
			(xy 26.310844 -246.653558) (xy 26.323561 -246.663834) (xy 26.352996 -246.678048) (xy 26.38508 -246.684301)
			(xy 26.417699 -246.682181) (xy 26.448704 -246.671829) (xy 26.476053 -246.653926) (xy 26.487374 -246.642128)
			(xy 26.506519 -246.621781) (xy 26.549647 -246.58627) (xy 26.597492 -246.557428) (xy 26.649031 -246.535872)
			(xy 26.703163 -246.522061) (xy 26.758731 -246.516292) (xy 26.814545 -246.518687) (xy 26.869414 -246.529196)
			(xy 26.922164 -246.547593) (xy 26.971667 -246.573486) (xy 27.016865 -246.606321) (xy 27.056792 -246.645395)
			(xy 27.090594 -246.689875) (xy 27.117549 -246.738808) (xy 27.13708 -246.791148) (xy 27.14877 -246.845778)
			(xy 27.152369 -246.901527) (xy 27.1478 -246.957206) (xy 27.13516 -247.011623) (xy 27.134831 -247.01246)
			(xy 44.102272 -247.01246) (xy 44.106343 -246.956838) (xy 44.118469 -246.902401) (xy 44.138392 -246.85031)
			(xy 44.165688 -246.801675) (xy 44.199774 -246.757532) (xy 44.239923 -246.718823) (xy 44.285281 -246.686372)
			(xy 44.334881 -246.660871) (xy 44.387665 -246.642864) (xy 44.442508 -246.632734) (xy 44.498242 -246.630697)
			(xy 44.553679 -246.636797) (xy 44.607636 -246.650903) (xy 44.658965 -246.672715) (xy 44.706571 -246.701769)
			(xy 44.749439 -246.737444) (xy 44.786656 -246.778981) (xy 44.817429 -246.825494) (xy 44.841101 -246.875991)
			(xy 44.857169 -246.929398) (xy 44.865289 -246.984574) (xy 44.865798 -247.01246) (xy 44.865289 -247.040346)
			(xy 44.857169 -247.095522) (xy 44.841101 -247.148929) (xy 44.817429 -247.199426) (xy 44.786656 -247.245939)
			(xy 44.749439 -247.287476) (xy 44.706571 -247.323151) (xy 44.658965 -247.352205) (xy 44.620221 -247.368669)
			(xy 58.125098 -247.368669) (xy 58.125098 -247.297347) (xy 58.133084 -247.226473) (xy 58.148954 -247.156938)
			(xy 58.172511 -247.089618) (xy 58.203456 -247.025359) (xy 58.241402 -246.964968) (xy 58.285871 -246.909206)
			(xy 58.336304 -246.858773) (xy 58.392066 -246.814304) (xy 58.452457 -246.776358) (xy 58.516716 -246.745413)
			(xy 58.584036 -246.721856) (xy 58.653571 -246.705986) (xy 58.724445 -246.698) (xy 58.795767 -246.698)
			(xy 58.866641 -246.705986) (xy 58.936176 -246.721856) (xy 59.003496 -246.745413) (xy 59.067755 -246.776358)
			(xy 59.128146 -246.814304) (xy 59.183908 -246.858773) (xy 59.234341 -246.909206) (xy 59.27881 -246.964968)
			(xy 59.316756 -247.025359) (xy 59.347701 -247.089618) (xy 59.371258 -247.156938) (xy 59.387128 -247.226473)
			(xy 59.395114 -247.297347) (xy 59.395614 -247.333008) (xy 59.395114 -247.368669) (xy 60.01181 -247.368669)
			(xy 60.01181 -247.297347) (xy 60.019796 -247.226473) (xy 60.035666 -247.156938) (xy 60.059223 -247.089618)
			(xy 60.090168 -247.025359) (xy 60.128114 -246.964968) (xy 60.172583 -246.909206) (xy 60.223016 -246.858773)
			(xy 60.278778 -246.814304) (xy 60.339169 -246.776358) (xy 60.403428 -246.745413) (xy 60.470748 -246.721856)
			(xy 60.540283 -246.705986) (xy 60.611157 -246.698) (xy 60.682479 -246.698) (xy 60.753353 -246.705986)
			(xy 60.822888 -246.721856) (xy 60.890208 -246.745413) (xy 60.954467 -246.776358) (xy 61.014858 -246.814304)
			(xy 61.07062 -246.858773) (xy 61.121053 -246.909206) (xy 61.165522 -246.964968) (xy 61.203468 -247.025359)
			(xy 61.234413 -247.089618) (xy 61.25797 -247.156938) (xy 61.27384 -247.226473) (xy 61.281826 -247.297347)
			(xy 61.282326 -247.333008) (xy 61.281826 -247.368669) (xy 62.252852 -247.368669) (xy 62.252852 -247.297347)
			(xy 62.260838 -247.226473) (xy 62.276708 -247.156938) (xy 62.300265 -247.089618) (xy 62.33121 -247.025359)
			(xy 62.369156 -246.964968) (xy 62.413625 -246.909206) (xy 62.464058 -246.858773) (xy 62.51982 -246.814304)
			(xy 62.580211 -246.776358) (xy 62.64447 -246.745413) (xy 62.71179 -246.721856) (xy 62.781325 -246.705986)
			(xy 62.852199 -246.698) (xy 62.923521 -246.698) (xy 62.994395 -246.705986) (xy 63.06393 -246.721856)
			(xy 63.13125 -246.745413) (xy 63.195509 -246.776358) (xy 63.2559 -246.814304) (xy 63.311662 -246.858773)
			(xy 63.362095 -246.909206) (xy 63.406564 -246.964968) (xy 63.44451 -247.025359) (xy 63.475455 -247.089618)
			(xy 63.499012 -247.156938) (xy 63.514882 -247.226473) (xy 63.522868 -247.297347) (xy 63.523368 -247.333008)
			(xy 63.522868 -247.368669) (xy 64.156836 -247.368669) (xy 64.156836 -247.297347) (xy 64.164822 -247.226473)
			(xy 64.180692 -247.156938) (xy 64.204249 -247.089618) (xy 64.235194 -247.025359) (xy 64.27314 -246.964968)
			(xy 64.317609 -246.909206) (xy 64.368042 -246.858773) (xy 64.423804 -246.814304) (xy 64.484195 -246.776358)
			(xy 64.548454 -246.745413) (xy 64.615774 -246.721856) (xy 64.685309 -246.705986) (xy 64.756183 -246.698)
			(xy 64.827505 -246.698) (xy 64.898379 -246.705986) (xy 64.967914 -246.721856) (xy 65.035234 -246.745413)
			(xy 65.099493 -246.776358) (xy 65.159884 -246.814304) (xy 65.215646 -246.858773) (xy 65.266079 -246.909206)
			(xy 65.310548 -246.964968) (xy 65.348494 -247.025359) (xy 65.379439 -247.089618) (xy 65.402996 -247.156938)
			(xy 65.418866 -247.226473) (xy 65.426852 -247.297347) (xy 65.427352 -247.333008) (xy 65.426852 -247.368669)
			(xy 65.418866 -247.439543) (xy 65.402996 -247.509078) (xy 65.379439 -247.576398) (xy 65.348494 -247.640657)
			(xy 65.310548 -247.701048) (xy 65.266079 -247.75681) (xy 65.215646 -247.807243) (xy 65.159884 -247.851712)
			(xy 65.099493 -247.889658) (xy 65.035234 -247.920603) (xy 64.967914 -247.94416) (xy 64.898379 -247.96003)
			(xy 64.827505 -247.968016) (xy 64.756183 -247.968016) (xy 64.685309 -247.96003) (xy 64.615774 -247.94416)
			(xy 64.548454 -247.920603) (xy 64.484195 -247.889658) (xy 64.423804 -247.851712) (xy 64.368042 -247.807243)
			(xy 64.317609 -247.75681) (xy 64.27314 -247.701048) (xy 64.235194 -247.640657) (xy 64.204249 -247.576398)
			(xy 64.180692 -247.509078) (xy 64.164822 -247.439543) (xy 64.156836 -247.368669) (xy 63.522868 -247.368669)
			(xy 63.514882 -247.439543) (xy 63.499012 -247.509078) (xy 63.475455 -247.576398) (xy 63.44451 -247.640657)
			(xy 63.406564 -247.701048) (xy 63.362095 -247.75681) (xy 63.311662 -247.807243) (xy 63.2559 -247.851712)
			(xy 63.195509 -247.889658) (xy 63.13125 -247.920603) (xy 63.06393 -247.94416) (xy 62.994395 -247.96003)
			(xy 62.923521 -247.968016) (xy 62.852199 -247.968016) (xy 62.781325 -247.96003) (xy 62.71179 -247.94416)
			(xy 62.64447 -247.920603) (xy 62.580211 -247.889658) (xy 62.51982 -247.851712) (xy 62.464058 -247.807243)
			(xy 62.413625 -247.75681) (xy 62.369156 -247.701048) (xy 62.33121 -247.640657) (xy 62.300265 -247.576398)
			(xy 62.276708 -247.509078) (xy 62.260838 -247.439543) (xy 62.252852 -247.368669) (xy 61.281826 -247.368669)
			(xy 61.27384 -247.439543) (xy 61.25797 -247.509078) (xy 61.234413 -247.576398) (xy 61.203468 -247.640657)
			(xy 61.165522 -247.701048) (xy 61.121053 -247.75681) (xy 61.07062 -247.807243) (xy 61.014858 -247.851712)
			(xy 60.954467 -247.889658) (xy 60.890208 -247.920603) (xy 60.822888 -247.94416) (xy 60.753353 -247.96003)
			(xy 60.682479 -247.968016) (xy 60.611157 -247.968016) (xy 60.540283 -247.96003) (xy 60.470748 -247.94416)
			(xy 60.403428 -247.920603) (xy 60.339169 -247.889658) (xy 60.278778 -247.851712) (xy 60.223016 -247.807243)
			(xy 60.172583 -247.75681) (xy 60.128114 -247.701048) (xy 60.090168 -247.640657) (xy 60.059223 -247.576398)
			(xy 60.035666 -247.509078) (xy 60.019796 -247.439543) (xy 60.01181 -247.368669) (xy 59.395114 -247.368669)
			(xy 59.387128 -247.439543) (xy 59.371258 -247.509078) (xy 59.347701 -247.576398) (xy 59.316756 -247.640657)
			(xy 59.27881 -247.701048) (xy 59.234341 -247.75681) (xy 59.183908 -247.807243) (xy 59.128146 -247.851712)
			(xy 59.067755 -247.889658) (xy 59.003496 -247.920603) (xy 58.936176 -247.94416) (xy 58.866641 -247.96003)
			(xy 58.795767 -247.968016) (xy 58.724445 -247.968016) (xy 58.653571 -247.96003) (xy 58.584036 -247.94416)
			(xy 58.516716 -247.920603) (xy 58.452457 -247.889658) (xy 58.392066 -247.851712) (xy 58.336304 -247.807243)
			(xy 58.285871 -247.75681) (xy 58.241402 -247.701048) (xy 58.203456 -247.640657) (xy 58.172511 -247.576398)
			(xy 58.148954 -247.509078) (xy 58.133084 -247.439543) (xy 58.125098 -247.368669) (xy 44.620221 -247.368669)
			(xy 44.607636 -247.374017) (xy 44.553679 -247.388123) (xy 44.498242 -247.394223) (xy 44.442508 -247.392186)
			(xy 44.387665 -247.382056) (xy 44.334881 -247.364049) (xy 44.285281 -247.338548) (xy 44.239923 -247.306097)
			(xy 44.199774 -247.267388) (xy 44.165688 -247.223245) (xy 44.138392 -247.17461) (xy 44.118469 -247.122519)
			(xy 44.106343 -247.068082) (xy 44.102272 -247.01246) (xy 27.134831 -247.01246) (xy 27.11472 -247.063616)
			(xy 27.086917 -247.112072) (xy 27.052346 -247.155956) (xy 27.011744 -247.194329) (xy 26.965981 -247.226372)
			(xy 26.916034 -247.251399) (xy 26.862972 -247.268875) (xy 26.807929 -247.278426) (xy 26.752081 -247.279849)
			(xy 26.696623 -247.273113) (xy 26.642739 -247.258361) (xy 26.591583 -247.23591) (xy 26.544248 -247.206239)
			(xy 26.52268 -247.188482) (xy 26.509948 -247.178225) (xy 26.480518 -247.164004) (xy 26.448437 -247.157745)
			(xy 26.41582 -247.15986) (xy 26.384816 -247.170211) (xy 26.35747 -247.188113) (xy 26.34615 -247.199912)
			(xy 26.327067 -247.220322) (xy 26.283936 -247.255846) (xy 26.236087 -247.2847) (xy 26.184541 -247.306268)
			(xy 26.130402 -247.32009) (xy 26.074825 -247.325868) (xy 26.019 -247.32348) (xy 25.96412 -247.312977)
			(xy 25.911358 -247.294583) (xy 25.861842 -247.268692) (xy 25.816632 -247.235857) (xy 25.776693 -247.19678)
			(xy 25.742879 -247.152296) (xy 25.715914 -247.103358) (xy 25.696373 -247.05101) (xy 25.684675 -246.996372)
			(xy 25.681069 -246.940612) (xy 13.474939 -246.940612) (xy 12.260072 -248.15546) (xy 9.291066 -248.15546)
			(xy 9.26773 -248.156729) (xy 9.222082 -248.166717) (xy 9.179028 -248.184879) (xy 9.140019 -248.210604)
			(xy 9.106367 -248.243024) (xy 9.079208 -248.281049) (xy 9.059454 -248.323396) (xy 9.047773 -248.36864)
			(xy 9.044556 -248.415258) (xy 9.049914 -248.461678) (xy 9.05637 -248.484136) (xy 9.066126 -248.517537)
			(xy 9.079145 -248.585894) (xy 9.084621 -248.655264) (xy 9.082488 -248.724817) (xy 9.072772 -248.793722)
			(xy 9.055589 -248.861153) (xy 9.031144 -248.926304) (xy 8.99973 -248.988395) (xy 8.997788 -248.991374)
			(xy 44.07357 -248.991374) (xy 44.077641 -248.935752) (xy 44.089767 -248.881315) (xy 44.10969 -248.829224)
			(xy 44.136986 -248.780589) (xy 44.171072 -248.736446) (xy 44.211221 -248.697737) (xy 44.256579 -248.665286)
			(xy 44.306179 -248.639785) (xy 44.358963 -248.621778) (xy 44.413806 -248.611648) (xy 44.46954 -248.609611)
			(xy 44.524977 -248.615711) (xy 44.578934 -248.629817) (xy 44.630263 -248.651629) (xy 44.677869 -248.680683)
			(xy 44.720737 -248.716358) (xy 44.757954 -248.757895) (xy 44.788727 -248.804408) (xy 44.812399 -248.854905)
			(xy 44.828467 -248.908312) (xy 44.836587 -248.963488) (xy 44.837096 -248.991374) (xy 44.836587 -249.01926)
			(xy 44.828467 -249.074436) (xy 44.812399 -249.127843) (xy 44.788727 -249.17834) (xy 44.757954 -249.224853)
			(xy 44.720737 -249.26639) (xy 44.677869 -249.302065) (xy 44.630263 -249.331119) (xy 44.578934 -249.352931)
			(xy 44.524977 -249.367037) (xy 44.46954 -249.373137) (xy 44.413806 -249.3711) (xy 44.358963 -249.36097)
			(xy 44.306179 -249.342963) (xy 44.256579 -249.317462) (xy 44.211221 -249.285011) (xy 44.171072 -249.246302)
			(xy 44.136986 -249.202159) (xy 44.10969 -249.153524) (xy 44.089767 -249.101433) (xy 44.077641 -249.046996)
			(xy 44.07357 -248.991374) (xy 8.997788 -248.991374) (xy 8.961722 -249.046685) (xy 8.917577 -249.100475)
			(xy 8.86782 -249.149121) (xy 8.840724 -249.170952) (xy 8.81888 -249.188224) (xy 8.766556 -249.289824)
			(xy 8.766556 -249.379841) (xy 58.081664 -249.379841) (xy 58.081664 -249.308519) (xy 58.08965 -249.237645)
			(xy 58.10552 -249.16811) (xy 58.129077 -249.10079) (xy 58.160022 -249.036531) (xy 58.197968 -248.97614)
			(xy 58.242437 -248.920378) (xy 58.29287 -248.869945) (xy 58.348632 -248.825476) (xy 58.409023 -248.78753)
			(xy 58.473282 -248.756585) (xy 58.540602 -248.733028) (xy 58.610137 -248.717158) (xy 58.681011 -248.709172)
			(xy 58.752333 -248.709172) (xy 58.823207 -248.717158) (xy 58.892742 -248.733028) (xy 58.960062 -248.756585)
			(xy 59.024321 -248.78753) (xy 59.084712 -248.825476) (xy 59.140474 -248.869945) (xy 59.190907 -248.920378)
			(xy 59.235376 -248.97614) (xy 59.273322 -249.036531) (xy 59.304267 -249.10079) (xy 59.327824 -249.16811)
			(xy 59.343694 -249.237645) (xy 59.35168 -249.308519) (xy 59.35218 -249.34418) (xy 59.35168 -249.379841)
			(xy 59.968376 -249.379841) (xy 59.968376 -249.308519) (xy 59.976362 -249.237645) (xy 59.992232 -249.16811)
			(xy 60.015789 -249.10079) (xy 60.046734 -249.036531) (xy 60.08468 -248.97614) (xy 60.129149 -248.920378)
			(xy 60.179582 -248.869945) (xy 60.235344 -248.825476) (xy 60.295735 -248.78753) (xy 60.359994 -248.756585)
			(xy 60.427314 -248.733028) (xy 60.496849 -248.717158) (xy 60.567723 -248.709172) (xy 60.639045 -248.709172)
			(xy 60.709919 -248.717158) (xy 60.779454 -248.733028) (xy 60.846774 -248.756585) (xy 60.911033 -248.78753)
			(xy 60.971424 -248.825476) (xy 61.027186 -248.869945) (xy 61.077619 -248.920378) (xy 61.122088 -248.97614)
			(xy 61.160034 -249.036531) (xy 61.190979 -249.10079) (xy 61.214536 -249.16811) (xy 61.230406 -249.237645)
			(xy 61.238392 -249.308519) (xy 61.238892 -249.34418) (xy 61.238392 -249.379841) (xy 62.209418 -249.379841)
			(xy 62.209418 -249.308519) (xy 62.217404 -249.237645) (xy 62.233274 -249.16811) (xy 62.256831 -249.10079)
			(xy 62.287776 -249.036531) (xy 62.325722 -248.97614) (xy 62.370191 -248.920378) (xy 62.420624 -248.869945)
			(xy 62.476386 -248.825476) (xy 62.536777 -248.78753) (xy 62.601036 -248.756585) (xy 62.668356 -248.733028)
			(xy 62.737891 -248.717158) (xy 62.808765 -248.709172) (xy 62.880087 -248.709172) (xy 62.950961 -248.717158)
			(xy 63.020496 -248.733028) (xy 63.087816 -248.756585) (xy 63.152075 -248.78753) (xy 63.212466 -248.825476)
			(xy 63.268228 -248.869945) (xy 63.318661 -248.920378) (xy 63.36313 -248.97614) (xy 63.401076 -249.036531)
			(xy 63.432021 -249.10079) (xy 63.455578 -249.16811) (xy 63.471448 -249.237645) (xy 63.479434 -249.308519)
			(xy 63.479934 -249.34418) (xy 63.479434 -249.379841) (xy 64.113402 -249.379841) (xy 64.113402 -249.308519)
			(xy 64.121388 -249.237645) (xy 64.137258 -249.16811) (xy 64.160815 -249.10079) (xy 64.19176 -249.036531)
			(xy 64.229706 -248.97614) (xy 64.274175 -248.920378) (xy 64.324608 -248.869945) (xy 64.38037 -248.825476)
			(xy 64.440761 -248.78753) (xy 64.50502 -248.756585) (xy 64.57234 -248.733028) (xy 64.641875 -248.717158)
			(xy 64.712749 -248.709172) (xy 64.784071 -248.709172) (xy 64.854945 -248.717158) (xy 64.92448 -248.733028)
			(xy 64.9918 -248.756585) (xy 65.056059 -248.78753) (xy 65.11645 -248.825476) (xy 65.172212 -248.869945)
			(xy 65.222645 -248.920378) (xy 65.267114 -248.97614) (xy 65.30506 -249.036531) (xy 65.336005 -249.10079)
			(xy 65.359562 -249.16811) (xy 65.375432 -249.237645) (xy 65.383418 -249.308519) (xy 65.383918 -249.34418)
			(xy 65.383418 -249.379841) (xy 65.375432 -249.450715) (xy 65.359562 -249.52025) (xy 65.336005 -249.58757)
			(xy 65.30506 -249.651829) (xy 65.267114 -249.71222) (xy 65.222645 -249.767982) (xy 65.172212 -249.818415)
			(xy 65.11645 -249.862884) (xy 65.056059 -249.90083) (xy 64.9918 -249.931775) (xy 64.92448 -249.955332)
			(xy 64.854945 -249.971202) (xy 64.784071 -249.979188) (xy 64.712749 -249.979188) (xy 64.641875 -249.971202)
			(xy 64.57234 -249.955332) (xy 64.50502 -249.931775) (xy 64.440761 -249.90083) (xy 64.38037 -249.862884)
			(xy 64.324608 -249.818415) (xy 64.274175 -249.767982) (xy 64.229706 -249.71222) (xy 64.19176 -249.651829)
			(xy 64.160815 -249.58757) (xy 64.137258 -249.52025) (xy 64.121388 -249.450715) (xy 64.113402 -249.379841)
			(xy 63.479434 -249.379841) (xy 63.471448 -249.450715) (xy 63.455578 -249.52025) (xy 63.432021 -249.58757)
			(xy 63.401076 -249.651829) (xy 63.36313 -249.71222) (xy 63.318661 -249.767982) (xy 63.268228 -249.818415)
			(xy 63.212466 -249.862884) (xy 63.152075 -249.90083) (xy 63.087816 -249.931775) (xy 63.020496 -249.955332)
			(xy 62.950961 -249.971202) (xy 62.880087 -249.979188) (xy 62.808765 -249.979188) (xy 62.737891 -249.971202)
			(xy 62.668356 -249.955332) (xy 62.601036 -249.931775) (xy 62.536777 -249.90083) (xy 62.476386 -249.862884)
			(xy 62.420624 -249.818415) (xy 62.370191 -249.767982) (xy 62.325722 -249.71222) (xy 62.287776 -249.651829)
			(xy 62.256831 -249.58757) (xy 62.233274 -249.52025) (xy 62.217404 -249.450715) (xy 62.209418 -249.379841)
			(xy 61.238392 -249.379841) (xy 61.230406 -249.450715) (xy 61.214536 -249.52025) (xy 61.190979 -249.58757)
			(xy 61.160034 -249.651829) (xy 61.122088 -249.71222) (xy 61.077619 -249.767982) (xy 61.027186 -249.818415)
			(xy 60.971424 -249.862884) (xy 60.911033 -249.90083) (xy 60.846774 -249.931775) (xy 60.779454 -249.955332)
			(xy 60.709919 -249.971202) (xy 60.639045 -249.979188) (xy 60.567723 -249.979188) (xy 60.496849 -249.971202)
			(xy 60.427314 -249.955332) (xy 60.359994 -249.931775) (xy 60.295735 -249.90083) (xy 60.235344 -249.862884)
			(xy 60.179582 -249.818415) (xy 60.129149 -249.767982) (xy 60.08468 -249.71222) (xy 60.046734 -249.651829)
			(xy 60.015789 -249.58757) (xy 59.992232 -249.52025) (xy 59.976362 -249.450715) (xy 59.968376 -249.379841)
			(xy 59.35168 -249.379841) (xy 59.343694 -249.450715) (xy 59.327824 -249.52025) (xy 59.304267 -249.58757)
			(xy 59.273322 -249.651829) (xy 59.235376 -249.71222) (xy 59.190907 -249.767982) (xy 59.140474 -249.818415)
			(xy 59.084712 -249.862884) (xy 59.024321 -249.90083) (xy 58.960062 -249.931775) (xy 58.892742 -249.955332)
			(xy 58.823207 -249.971202) (xy 58.752333 -249.979188) (xy 58.681011 -249.979188) (xy 58.610137 -249.971202)
			(xy 58.540602 -249.955332) (xy 58.473282 -249.931775) (xy 58.409023 -249.90083) (xy 58.348632 -249.862884)
			(xy 58.29287 -249.818415) (xy 58.242437 -249.767982) (xy 58.197968 -249.71222) (xy 58.160022 -249.651829)
			(xy 58.129077 -249.58757) (xy 58.10552 -249.52025) (xy 58.08965 -249.450715) (xy 58.081664 -249.379841)
			(xy 8.766556 -249.379841) (xy 8.766556 -249.789442) (xy 46.51451 -249.789442) (xy 46.518581 -249.73382)
			(xy 46.530707 -249.679383) (xy 46.55063 -249.627292) (xy 46.577926 -249.578657) (xy 46.612012 -249.534514)
			(xy 46.652161 -249.495805) (xy 46.697519 -249.463354) (xy 46.747119 -249.437853) (xy 46.799903 -249.419846)
			(xy 46.854746 -249.409716) (xy 46.91048 -249.407679) (xy 46.965917 -249.413779) (xy 47.019874 -249.427885)
			(xy 47.071203 -249.449697) (xy 47.118809 -249.478751) (xy 47.161677 -249.514426) (xy 47.198894 -249.555963)
			(xy 47.229667 -249.602476) (xy 47.253339 -249.652973) (xy 47.269407 -249.70638) (xy 47.277527 -249.761556)
			(xy 47.278036 -249.789442) (xy 47.277527 -249.817328) (xy 47.269407 -249.872504) (xy 47.253339 -249.925911)
			(xy 47.229667 -249.976408) (xy 47.198894 -250.022921) (xy 47.161677 -250.064458) (xy 47.118809 -250.100133)
			(xy 47.071203 -250.129187) (xy 47.019874 -250.150999) (xy 46.965917 -250.165105) (xy 46.91048 -250.171205)
			(xy 46.854746 -250.169168) (xy 46.799903 -250.159038) (xy 46.747119 -250.141031) (xy 46.697519 -250.11553)
			(xy 46.652161 -250.083079) (xy 46.612012 -250.04437) (xy 46.577926 -250.000227) (xy 46.55063 -249.951592)
			(xy 46.530707 -249.899501) (xy 46.518581 -249.845064) (xy 46.51451 -249.789442) (xy 8.766556 -249.789442)
			(xy 8.766556 -250.697238) (xy 8.767089 -250.713858) (xy 8.775672 -250.745969) (xy 8.79227 -250.774768)
			(xy 8.80364 -250.7869) (xy 9.720382 -251.703586) (xy 24.545288 -251.703586) (xy 24.549359 -251.647964)
			(xy 24.561485 -251.593527) (xy 24.581408 -251.541436) (xy 24.608704 -251.492801) (xy 24.64279 -251.448658)
			(xy 24.682939 -251.409949) (xy 24.728297 -251.377498) (xy 24.777897 -251.351997) (xy 24.830681 -251.33399)
			(xy 24.885524 -251.32386) (xy 24.941258 -251.321823) (xy 24.996695 -251.327923) (xy 25.050652 -251.342029)
			(xy 25.101981 -251.363841) (xy 25.149587 -251.392895) (xy 25.192455 -251.42857) (xy 25.211058 -251.449332)
			(xy 44.25645 -251.449332) (xy 44.260521 -251.39371) (xy 44.272647 -251.339273) (xy 44.29257 -251.287182)
			(xy 44.319866 -251.238547) (xy 44.353952 -251.194404) (xy 44.394101 -251.155695) (xy 44.439459 -251.123244)
			(xy 44.489059 -251.097743) (xy 44.541843 -251.079736) (xy 44.596686 -251.069606) (xy 44.65242 -251.067569)
			(xy 44.707857 -251.073669) (xy 44.761814 -251.087775) (xy 44.813143 -251.109587) (xy 44.860749 -251.138641)
			(xy 44.903617 -251.174316) (xy 44.940834 -251.215853) (xy 44.971607 -251.262366) (xy 44.975356 -251.270363)
			(xy 58.081664 -251.270363) (xy 58.081664 -251.199041) (xy 58.08965 -251.128167) (xy 58.10552 -251.058632)
			(xy 58.129077 -250.991312) (xy 58.160022 -250.927053) (xy 58.197968 -250.866662) (xy 58.242437 -250.8109)
			(xy 58.29287 -250.760467) (xy 58.348632 -250.715998) (xy 58.409023 -250.678052) (xy 58.473282 -250.647107)
			(xy 58.540602 -250.62355) (xy 58.610137 -250.60768) (xy 58.681011 -250.599694) (xy 58.752333 -250.599694)
			(xy 58.823207 -250.60768) (xy 58.892742 -250.62355) (xy 58.960062 -250.647107) (xy 59.024321 -250.678052)
			(xy 59.084712 -250.715998) (xy 59.140474 -250.760467) (xy 59.190907 -250.8109) (xy 59.235376 -250.866662)
			(xy 59.273322 -250.927053) (xy 59.304267 -250.991312) (xy 59.327824 -251.058632) (xy 59.343694 -251.128167)
			(xy 59.35168 -251.199041) (xy 59.35218 -251.234702) (xy 59.35168 -251.270363) (xy 59.968376 -251.270363)
			(xy 59.968376 -251.199041) (xy 59.976362 -251.128167) (xy 59.992232 -251.058632) (xy 60.015789 -250.991312)
			(xy 60.046734 -250.927053) (xy 60.08468 -250.866662) (xy 60.129149 -250.8109) (xy 60.179582 -250.760467)
			(xy 60.235344 -250.715998) (xy 60.295735 -250.678052) (xy 60.359994 -250.647107) (xy 60.427314 -250.62355)
			(xy 60.496849 -250.60768) (xy 60.567723 -250.599694) (xy 60.639045 -250.599694) (xy 60.709919 -250.60768)
			(xy 60.779454 -250.62355) (xy 60.846774 -250.647107) (xy 60.911033 -250.678052) (xy 60.971424 -250.715998)
			(xy 61.027186 -250.760467) (xy 61.077619 -250.8109) (xy 61.122088 -250.866662) (xy 61.160034 -250.927053)
			(xy 61.190979 -250.991312) (xy 61.214536 -251.058632) (xy 61.230406 -251.128167) (xy 61.238392 -251.199041)
			(xy 61.238892 -251.234702) (xy 61.238392 -251.270363) (xy 62.209418 -251.270363) (xy 62.209418 -251.199041)
			(xy 62.217404 -251.128167) (xy 62.233274 -251.058632) (xy 62.256831 -250.991312) (xy 62.287776 -250.927053)
			(xy 62.325722 -250.866662) (xy 62.370191 -250.8109) (xy 62.420624 -250.760467) (xy 62.476386 -250.715998)
			(xy 62.536777 -250.678052) (xy 62.601036 -250.647107) (xy 62.668356 -250.62355) (xy 62.737891 -250.60768)
			(xy 62.808765 -250.599694) (xy 62.880087 -250.599694) (xy 62.950961 -250.60768) (xy 63.020496 -250.62355)
			(xy 63.087816 -250.647107) (xy 63.152075 -250.678052) (xy 63.212466 -250.715998) (xy 63.268228 -250.760467)
			(xy 63.318661 -250.8109) (xy 63.36313 -250.866662) (xy 63.401076 -250.927053) (xy 63.432021 -250.991312)
			(xy 63.455578 -251.058632) (xy 63.471448 -251.128167) (xy 63.479434 -251.199041) (xy 63.479934 -251.234702)
			(xy 63.479434 -251.270363) (xy 64.113402 -251.270363) (xy 64.113402 -251.199041) (xy 64.121388 -251.128167)
			(xy 64.137258 -251.058632) (xy 64.160815 -250.991312) (xy 64.19176 -250.927053) (xy 64.229706 -250.866662)
			(xy 64.274175 -250.8109) (xy 64.324608 -250.760467) (xy 64.38037 -250.715998) (xy 64.440761 -250.678052)
			(xy 64.50502 -250.647107) (xy 64.57234 -250.62355) (xy 64.641875 -250.60768) (xy 64.712749 -250.599694)
			(xy 64.784071 -250.599694) (xy 64.854945 -250.60768) (xy 64.92448 -250.62355) (xy 64.9918 -250.647107)
			(xy 65.056059 -250.678052) (xy 65.11645 -250.715998) (xy 65.172212 -250.760467) (xy 65.222645 -250.8109)
			(xy 65.267114 -250.866662) (xy 65.30506 -250.927053) (xy 65.336005 -250.991312) (xy 65.359562 -251.058632)
			(xy 65.375432 -251.128167) (xy 65.383418 -251.199041) (xy 65.383918 -251.234702) (xy 65.383418 -251.270363)
			(xy 65.375432 -251.341237) (xy 65.359562 -251.410772) (xy 65.336005 -251.478092) (xy 65.30506 -251.542351)
			(xy 65.267114 -251.602742) (xy 65.222645 -251.658504) (xy 65.172212 -251.708937) (xy 65.11645 -251.753406)
			(xy 65.056059 -251.791352) (xy 64.9918 -251.822297) (xy 64.92448 -251.845854) (xy 64.854945 -251.861724)
			(xy 64.784071 -251.86971) (xy 64.712749 -251.86971) (xy 64.641875 -251.861724) (xy 64.57234 -251.845854)
			(xy 64.50502 -251.822297) (xy 64.440761 -251.791352) (xy 64.38037 -251.753406) (xy 64.324608 -251.708937)
			(xy 64.274175 -251.658504) (xy 64.229706 -251.602742) (xy 64.19176 -251.542351) (xy 64.160815 -251.478092)
			(xy 64.137258 -251.410772) (xy 64.121388 -251.341237) (xy 64.113402 -251.270363) (xy 63.479434 -251.270363)
			(xy 63.471448 -251.341237) (xy 63.455578 -251.410772) (xy 63.432021 -251.478092) (xy 63.401076 -251.542351)
			(xy 63.36313 -251.602742) (xy 63.318661 -251.658504) (xy 63.268228 -251.708937) (xy 63.212466 -251.753406)
			(xy 63.152075 -251.791352) (xy 63.087816 -251.822297) (xy 63.020496 -251.845854) (xy 62.950961 -251.861724)
			(xy 62.880087 -251.86971) (xy 62.808765 -251.86971) (xy 62.737891 -251.861724) (xy 62.668356 -251.845854)
			(xy 62.601036 -251.822297) (xy 62.536777 -251.791352) (xy 62.476386 -251.753406) (xy 62.420624 -251.708937)
			(xy 62.370191 -251.658504) (xy 62.325722 -251.602742) (xy 62.287776 -251.542351) (xy 62.256831 -251.478092)
			(xy 62.233274 -251.410772) (xy 62.217404 -251.341237) (xy 62.209418 -251.270363) (xy 61.238392 -251.270363)
			(xy 61.230406 -251.341237) (xy 61.214536 -251.410772) (xy 61.190979 -251.478092) (xy 61.160034 -251.542351)
			(xy 61.122088 -251.602742) (xy 61.077619 -251.658504) (xy 61.027186 -251.708937) (xy 60.971424 -251.753406)
			(xy 60.911033 -251.791352) (xy 60.846774 -251.822297) (xy 60.779454 -251.845854) (xy 60.709919 -251.861724)
			(xy 60.639045 -251.86971) (xy 60.567723 -251.86971) (xy 60.496849 -251.861724) (xy 60.427314 -251.845854)
			(xy 60.359994 -251.822297) (xy 60.295735 -251.791352) (xy 60.235344 -251.753406) (xy 60.179582 -251.708937)
			(xy 60.129149 -251.658504) (xy 60.08468 -251.602742) (xy 60.046734 -251.542351) (xy 60.015789 -251.478092)
			(xy 59.992232 -251.410772) (xy 59.976362 -251.341237) (xy 59.968376 -251.270363) (xy 59.35168 -251.270363)
			(xy 59.343694 -251.341237) (xy 59.327824 -251.410772) (xy 59.304267 -251.478092) (xy 59.273322 -251.542351)
			(xy 59.235376 -251.602742) (xy 59.190907 -251.658504) (xy 59.140474 -251.708937) (xy 59.084712 -251.753406)
			(xy 59.024321 -251.791352) (xy 58.960062 -251.822297) (xy 58.892742 -251.845854) (xy 58.823207 -251.861724)
			(xy 58.752333 -251.86971) (xy 58.681011 -251.86971) (xy 58.610137 -251.861724) (xy 58.540602 -251.845854)
			(xy 58.473282 -251.822297) (xy 58.409023 -251.791352) (xy 58.348632 -251.753406) (xy 58.29287 -251.708937)
			(xy 58.242437 -251.658504) (xy 58.197968 -251.602742) (xy 58.160022 -251.542351) (xy 58.129077 -251.478092)
			(xy 58.10552 -251.410772) (xy 58.08965 -251.341237) (xy 58.081664 -251.270363) (xy 44.975356 -251.270363)
			(xy 44.995279 -251.312863) (xy 45.011347 -251.36627) (xy 45.019467 -251.421446) (xy 45.019976 -251.449332)
			(xy 45.019467 -251.477218) (xy 45.011347 -251.532394) (xy 44.995279 -251.585801) (xy 44.971607 -251.636298)
			(xy 44.940834 -251.682811) (xy 44.903617 -251.724348) (xy 44.860749 -251.760023) (xy 44.813143 -251.789077)
			(xy 44.761814 -251.810889) (xy 44.707857 -251.824995) (xy 44.65242 -251.831095) (xy 44.596686 -251.829058)
			(xy 44.541843 -251.818928) (xy 44.489059 -251.800921) (xy 44.439459 -251.77542) (xy 44.394101 -251.742969)
			(xy 44.353952 -251.70426) (xy 44.319866 -251.660117) (xy 44.29257 -251.611482) (xy 44.272647 -251.559391)
			(xy 44.260521 -251.504954) (xy 44.25645 -251.449332) (xy 25.211058 -251.449332) (xy 25.229672 -251.470107)
			(xy 25.260445 -251.51662) (xy 25.284117 -251.567117) (xy 25.300185 -251.620524) (xy 25.308305 -251.6757)
			(xy 25.308814 -251.703586) (xy 25.308305 -251.731472) (xy 25.300185 -251.786648) (xy 25.284117 -251.840055)
			(xy 25.260445 -251.890552) (xy 25.229672 -251.937065) (xy 25.192455 -251.978602) (xy 25.149587 -252.014277)
			(xy 25.101981 -252.043331) (xy 25.050652 -252.065143) (xy 24.996695 -252.079249) (xy 24.941258 -252.085349)
			(xy 24.885524 -252.083312) (xy 24.830681 -252.073182) (xy 24.777897 -252.055175) (xy 24.728297 -252.029674)
			(xy 24.682939 -251.997223) (xy 24.64279 -251.958514) (xy 24.608704 -251.914371) (xy 24.581408 -251.865736)
			(xy 24.561485 -251.813645) (xy 24.549359 -251.759208) (xy 24.545288 -251.703586) (xy 9.720382 -251.703586)
			(xy 11.422539 -253.40564) (xy 44.182028 -253.40564) (xy 44.186099 -253.350018) (xy 44.198225 -253.295581)
			(xy 44.218148 -253.24349) (xy 44.245444 -253.194855) (xy 44.27953 -253.150712) (xy 44.319679 -253.112003)
			(xy 44.365037 -253.079552) (xy 44.414637 -253.054051) (xy 44.467421 -253.036044) (xy 44.522264 -253.025914)
			(xy 44.577998 -253.023877) (xy 44.633435 -253.029977) (xy 44.687392 -253.044083) (xy 44.738721 -253.065895)
			(xy 44.786327 -253.094949) (xy 44.829195 -253.130624) (xy 44.866412 -253.172161) (xy 44.897185 -253.218674)
			(xy 44.920857 -253.269171) (xy 44.933594 -253.311507) (xy 58.081664 -253.311507) (xy 58.081664 -253.240185)
			(xy 58.08965 -253.169311) (xy 58.10552 -253.099776) (xy 58.129077 -253.032456) (xy 58.160022 -252.968197)
			(xy 58.197968 -252.907806) (xy 58.242437 -252.852044) (xy 58.29287 -252.801611) (xy 58.348632 -252.757142)
			(xy 58.409023 -252.719196) (xy 58.473282 -252.688251) (xy 58.540602 -252.664694) (xy 58.610137 -252.648824)
			(xy 58.681011 -252.640838) (xy 58.752333 -252.640838) (xy 58.823207 -252.648824) (xy 58.892742 -252.664694)
			(xy 58.960062 -252.688251) (xy 59.024321 -252.719196) (xy 59.084712 -252.757142) (xy 59.140474 -252.801611)
			(xy 59.190907 -252.852044) (xy 59.235376 -252.907806) (xy 59.273322 -252.968197) (xy 59.304267 -253.032456)
			(xy 59.327824 -253.099776) (xy 59.343694 -253.169311) (xy 59.35168 -253.240185) (xy 59.35218 -253.275846)
			(xy 59.35168 -253.311507) (xy 59.968376 -253.311507) (xy 59.968376 -253.240185) (xy 59.976362 -253.169311)
			(xy 59.992232 -253.099776) (xy 60.015789 -253.032456) (xy 60.046734 -252.968197) (xy 60.08468 -252.907806)
			(xy 60.129149 -252.852044) (xy 60.179582 -252.801611) (xy 60.235344 -252.757142) (xy 60.295735 -252.719196)
			(xy 60.359994 -252.688251) (xy 60.427314 -252.664694) (xy 60.496849 -252.648824) (xy 60.567723 -252.640838)
			(xy 60.639045 -252.640838) (xy 60.709919 -252.648824) (xy 60.779454 -252.664694) (xy 60.846774 -252.688251)
			(xy 60.911033 -252.719196) (xy 60.971424 -252.757142) (xy 61.027186 -252.801611) (xy 61.077619 -252.852044)
			(xy 61.122088 -252.907806) (xy 61.160034 -252.968197) (xy 61.190979 -253.032456) (xy 61.214536 -253.099776)
			(xy 61.230406 -253.169311) (xy 61.238392 -253.240185) (xy 61.238892 -253.275846) (xy 61.238392 -253.311507)
			(xy 62.209418 -253.311507) (xy 62.209418 -253.240185) (xy 62.217404 -253.169311) (xy 62.233274 -253.099776)
			(xy 62.256831 -253.032456) (xy 62.287776 -252.968197) (xy 62.325722 -252.907806) (xy 62.370191 -252.852044)
			(xy 62.420624 -252.801611) (xy 62.476386 -252.757142) (xy 62.536777 -252.719196) (xy 62.601036 -252.688251)
			(xy 62.668356 -252.664694) (xy 62.737891 -252.648824) (xy 62.808765 -252.640838) (xy 62.880087 -252.640838)
			(xy 62.950961 -252.648824) (xy 63.020496 -252.664694) (xy 63.087816 -252.688251) (xy 63.152075 -252.719196)
			(xy 63.212466 -252.757142) (xy 63.268228 -252.801611) (xy 63.318661 -252.852044) (xy 63.36313 -252.907806)
			(xy 63.401076 -252.968197) (xy 63.432021 -253.032456) (xy 63.455578 -253.099776) (xy 63.471448 -253.169311)
			(xy 63.479434 -253.240185) (xy 63.479934 -253.275846) (xy 63.479434 -253.311507) (xy 64.113402 -253.311507)
			(xy 64.113402 -253.240185) (xy 64.121388 -253.169311) (xy 64.137258 -253.099776) (xy 64.160815 -253.032456)
			(xy 64.19176 -252.968197) (xy 64.229706 -252.907806) (xy 64.274175 -252.852044) (xy 64.324608 -252.801611)
			(xy 64.38037 -252.757142) (xy 64.440761 -252.719196) (xy 64.50502 -252.688251) (xy 64.57234 -252.664694)
			(xy 64.641875 -252.648824) (xy 64.712749 -252.640838) (xy 64.784071 -252.640838) (xy 64.854945 -252.648824)
			(xy 64.92448 -252.664694) (xy 64.9918 -252.688251) (xy 65.056059 -252.719196) (xy 65.11645 -252.757142)
			(xy 65.172212 -252.801611) (xy 65.222645 -252.852044) (xy 65.267114 -252.907806) (xy 65.30506 -252.968197)
			(xy 65.336005 -253.032456) (xy 65.359562 -253.099776) (xy 65.375432 -253.169311) (xy 65.383418 -253.240185)
			(xy 65.383918 -253.275846) (xy 65.383418 -253.311507) (xy 65.375432 -253.382381) (xy 65.359562 -253.451916)
			(xy 65.336005 -253.519236) (xy 65.30506 -253.583495) (xy 65.267114 -253.643886) (xy 65.222645 -253.699648)
			(xy 65.172212 -253.750081) (xy 65.11645 -253.79455) (xy 65.056059 -253.832496) (xy 64.9918 -253.863441)
			(xy 64.92448 -253.886998) (xy 64.854945 -253.902868) (xy 64.784071 -253.910854) (xy 64.712749 -253.910854)
			(xy 64.641875 -253.902868) (xy 64.57234 -253.886998) (xy 64.50502 -253.863441) (xy 64.440761 -253.832496)
			(xy 64.38037 -253.79455) (xy 64.324608 -253.750081) (xy 64.274175 -253.699648) (xy 64.229706 -253.643886)
			(xy 64.19176 -253.583495) (xy 64.160815 -253.519236) (xy 64.137258 -253.451916) (xy 64.121388 -253.382381)
			(xy 64.113402 -253.311507) (xy 63.479434 -253.311507) (xy 63.471448 -253.382381) (xy 63.455578 -253.451916)
			(xy 63.432021 -253.519236) (xy 63.401076 -253.583495) (xy 63.36313 -253.643886) (xy 63.318661 -253.699648)
			(xy 63.268228 -253.750081) (xy 63.212466 -253.79455) (xy 63.152075 -253.832496) (xy 63.087816 -253.863441)
			(xy 63.020496 -253.886998) (xy 62.950961 -253.902868) (xy 62.880087 -253.910854) (xy 62.808765 -253.910854)
			(xy 62.737891 -253.902868) (xy 62.668356 -253.886998) (xy 62.601036 -253.863441) (xy 62.536777 -253.832496)
			(xy 62.476386 -253.79455) (xy 62.420624 -253.750081) (xy 62.370191 -253.699648) (xy 62.325722 -253.643886)
			(xy 62.287776 -253.583495) (xy 62.256831 -253.519236) (xy 62.233274 -253.451916) (xy 62.217404 -253.382381)
			(xy 62.209418 -253.311507) (xy 61.238392 -253.311507) (xy 61.230406 -253.382381) (xy 61.214536 -253.451916)
			(xy 61.190979 -253.519236) (xy 61.160034 -253.583495) (xy 61.122088 -253.643886) (xy 61.077619 -253.699648)
			(xy 61.027186 -253.750081) (xy 60.971424 -253.79455) (xy 60.911033 -253.832496) (xy 60.846774 -253.863441)
			(xy 60.779454 -253.886998) (xy 60.709919 -253.902868) (xy 60.639045 -253.910854) (xy 60.567723 -253.910854)
			(xy 60.496849 -253.902868) (xy 60.427314 -253.886998) (xy 60.359994 -253.863441) (xy 60.295735 -253.832496)
			(xy 60.235344 -253.79455) (xy 60.179582 -253.750081) (xy 60.129149 -253.699648) (xy 60.08468 -253.643886)
			(xy 60.046734 -253.583495) (xy 60.015789 -253.519236) (xy 59.992232 -253.451916) (xy 59.976362 -253.382381)
			(xy 59.968376 -253.311507) (xy 59.35168 -253.311507) (xy 59.343694 -253.382381) (xy 59.327824 -253.451916)
			(xy 59.304267 -253.519236) (xy 59.273322 -253.583495) (xy 59.235376 -253.643886) (xy 59.190907 -253.699648)
			(xy 59.140474 -253.750081) (xy 59.084712 -253.79455) (xy 59.024321 -253.832496) (xy 58.960062 -253.863441)
			(xy 58.892742 -253.886998) (xy 58.823207 -253.902868) (xy 58.752333 -253.910854) (xy 58.681011 -253.910854)
			(xy 58.610137 -253.902868) (xy 58.540602 -253.886998) (xy 58.473282 -253.863441) (xy 58.409023 -253.832496)
			(xy 58.348632 -253.79455) (xy 58.29287 -253.750081) (xy 58.242437 -253.699648) (xy 58.197968 -253.643886)
			(xy 58.160022 -253.583495) (xy 58.129077 -253.519236) (xy 58.10552 -253.451916) (xy 58.08965 -253.382381)
			(xy 58.081664 -253.311507) (xy 44.933594 -253.311507) (xy 44.936925 -253.322578) (xy 44.945045 -253.377754)
			(xy 44.945554 -253.40564) (xy 44.945045 -253.433526) (xy 44.936925 -253.488702) (xy 44.920857 -253.542109)
			(xy 44.897185 -253.592606) (xy 44.866412 -253.639119) (xy 44.829195 -253.680656) (xy 44.786327 -253.716331)
			(xy 44.738721 -253.745385) (xy 44.687392 -253.767197) (xy 44.633435 -253.781303) (xy 44.577998 -253.787403)
			(xy 44.522264 -253.785366) (xy 44.467421 -253.775236) (xy 44.414637 -253.757229) (xy 44.365037 -253.731728)
			(xy 44.319679 -253.699277) (xy 44.27953 -253.660568) (xy 44.245444 -253.616425) (xy 44.218148 -253.56779)
			(xy 44.198225 -253.515699) (xy 44.186099 -253.461262) (xy 44.182028 -253.40564) (xy 11.422539 -253.40564)
			(xy 11.86224 -253.845314) (xy 25.19248 -253.845314) (xy 25.196551 -253.789692) (xy 25.208677 -253.735255)
			(xy 25.2286 -253.683164) (xy 25.255896 -253.634529) (xy 25.289982 -253.590386) (xy 25.330131 -253.551677)
			(xy 25.375489 -253.519226) (xy 25.425089 -253.493725) (xy 25.477873 -253.475718) (xy 25.532716 -253.465588)
			(xy 25.58845 -253.463551) (xy 25.643887 -253.469651) (xy 25.697844 -253.483757) (xy 25.749173 -253.505569)
			(xy 25.796779 -253.534623) (xy 25.839647 -253.570298) (xy 25.876864 -253.611835) (xy 25.907637 -253.658348)
			(xy 25.931309 -253.708845) (xy 25.947377 -253.762252) (xy 25.955497 -253.817428) (xy 25.956006 -253.845314)
			(xy 25.955497 -253.8732) (xy 25.947377 -253.928376) (xy 25.931309 -253.981783) (xy 25.907637 -254.03228)
			(xy 25.876864 -254.078793) (xy 25.839647 -254.12033) (xy 25.796779 -254.156005) (xy 25.749173 -254.185059)
			(xy 25.697844 -254.206871) (xy 25.643887 -254.220977) (xy 25.58845 -254.227077) (xy 25.532716 -254.22504)
			(xy 25.477873 -254.21491) (xy 25.425089 -254.196903) (xy 25.375489 -254.171402) (xy 25.330131 -254.138951)
			(xy 25.289982 -254.100242) (xy 25.255896 -254.056099) (xy 25.2286 -254.007464) (xy 25.208677 -253.955373)
			(xy 25.196551 -253.900936) (xy 25.19248 -253.845314) (xy 11.86224 -253.845314) (xy 12.412183 -254.395224)
			(xy 46.443644 -254.395224) (xy 46.447715 -254.339602) (xy 46.459841 -254.285165) (xy 46.479764 -254.233074)
			(xy 46.50706 -254.184439) (xy 46.541146 -254.140296) (xy 46.581295 -254.101587) (xy 46.626653 -254.069136)
			(xy 46.676253 -254.043635) (xy 46.729037 -254.025628) (xy 46.78388 -254.015498) (xy 46.839614 -254.013461)
			(xy 46.895051 -254.019561) (xy 46.949008 -254.033667) (xy 47.000337 -254.055479) (xy 47.047943 -254.084533)
			(xy 47.090811 -254.120208) (xy 47.128028 -254.161745) (xy 47.158801 -254.208258) (xy 47.182473 -254.258755)
			(xy 47.198541 -254.312162) (xy 47.206661 -254.367338) (xy 47.20717 -254.395224) (xy 47.206661 -254.42311)
			(xy 47.198541 -254.478286) (xy 47.182473 -254.531693) (xy 47.158801 -254.58219) (xy 47.128028 -254.628703)
			(xy 47.090811 -254.67024) (xy 47.047943 -254.705915) (xy 47.000337 -254.734969) (xy 46.949008 -254.756781)
			(xy 46.895051 -254.770887) (xy 46.839614 -254.776987) (xy 46.78388 -254.77495) (xy 46.729037 -254.76482)
			(xy 46.676253 -254.746813) (xy 46.626653 -254.721312) (xy 46.581295 -254.688861) (xy 46.541146 -254.650152)
			(xy 46.50706 -254.606009) (xy 46.479764 -254.557374) (xy 46.459841 -254.505283) (xy 46.447715 -254.450846)
			(xy 46.443644 -254.395224) (xy 12.412183 -254.395224) (xy 12.983972 -254.966978) (xy 12.983972 -255.221333)
			(xy 58.081664 -255.221333) (xy 58.081664 -255.150011) (xy 58.08965 -255.079137) (xy 58.10552 -255.009602)
			(xy 58.129077 -254.942282) (xy 58.160022 -254.878023) (xy 58.197968 -254.817632) (xy 58.242437 -254.76187)
			(xy 58.29287 -254.711437) (xy 58.348632 -254.666968) (xy 58.409023 -254.629022) (xy 58.473282 -254.598077)
			(xy 58.540602 -254.57452) (xy 58.610137 -254.55865) (xy 58.681011 -254.550664) (xy 58.752333 -254.550664)
			(xy 58.823207 -254.55865) (xy 58.892742 -254.57452) (xy 58.960062 -254.598077) (xy 59.024321 -254.629022)
			(xy 59.084712 -254.666968) (xy 59.140474 -254.711437) (xy 59.190907 -254.76187) (xy 59.235376 -254.817632)
			(xy 59.273322 -254.878023) (xy 59.304267 -254.942282) (xy 59.327824 -255.009602) (xy 59.343694 -255.079137)
			(xy 59.35168 -255.150011) (xy 59.35218 -255.185672) (xy 59.35168 -255.221333) (xy 59.968376 -255.221333)
			(xy 59.968376 -255.150011) (xy 59.976362 -255.079137) (xy 59.992232 -255.009602) (xy 60.015789 -254.942282)
			(xy 60.046734 -254.878023) (xy 60.08468 -254.817632) (xy 60.129149 -254.76187) (xy 60.179582 -254.711437)
			(xy 60.235344 -254.666968) (xy 60.295735 -254.629022) (xy 60.359994 -254.598077) (xy 60.427314 -254.57452)
			(xy 60.496849 -254.55865) (xy 60.567723 -254.550664) (xy 60.639045 -254.550664) (xy 60.709919 -254.55865)
			(xy 60.779454 -254.57452) (xy 60.846774 -254.598077) (xy 60.911033 -254.629022) (xy 60.971424 -254.666968)
			(xy 61.027186 -254.711437) (xy 61.077619 -254.76187) (xy 61.122088 -254.817632) (xy 61.160034 -254.878023)
			(xy 61.190979 -254.942282) (xy 61.214536 -255.009602) (xy 61.230406 -255.079137) (xy 61.238392 -255.150011)
			(xy 61.238892 -255.185672) (xy 61.238392 -255.221333) (xy 62.209418 -255.221333) (xy 62.209418 -255.150011)
			(xy 62.217404 -255.079137) (xy 62.233274 -255.009602) (xy 62.256831 -254.942282) (xy 62.287776 -254.878023)
			(xy 62.325722 -254.817632) (xy 62.370191 -254.76187) (xy 62.420624 -254.711437) (xy 62.476386 -254.666968)
			(xy 62.536777 -254.629022) (xy 62.601036 -254.598077) (xy 62.668356 -254.57452) (xy 62.737891 -254.55865)
			(xy 62.808765 -254.550664) (xy 62.880087 -254.550664) (xy 62.950961 -254.55865) (xy 63.020496 -254.57452)
			(xy 63.087816 -254.598077) (xy 63.152075 -254.629022) (xy 63.212466 -254.666968) (xy 63.268228 -254.711437)
			(xy 63.318661 -254.76187) (xy 63.36313 -254.817632) (xy 63.401076 -254.878023) (xy 63.432021 -254.942282)
			(xy 63.455578 -255.009602) (xy 63.471448 -255.079137) (xy 63.479434 -255.150011) (xy 63.479934 -255.185672)
			(xy 63.479434 -255.221333) (xy 64.113402 -255.221333) (xy 64.113402 -255.150011) (xy 64.121388 -255.079137)
			(xy 64.137258 -255.009602) (xy 64.160815 -254.942282) (xy 64.19176 -254.878023) (xy 64.229706 -254.817632)
			(xy 64.274175 -254.76187) (xy 64.324608 -254.711437) (xy 64.38037 -254.666968) (xy 64.440761 -254.629022)
			(xy 64.50502 -254.598077) (xy 64.57234 -254.57452) (xy 64.641875 -254.55865) (xy 64.712749 -254.550664)
			(xy 64.784071 -254.550664) (xy 64.854945 -254.55865) (xy 64.92448 -254.57452) (xy 64.9918 -254.598077)
			(xy 65.056059 -254.629022) (xy 65.11645 -254.666968) (xy 65.172212 -254.711437) (xy 65.222645 -254.76187)
			(xy 65.267114 -254.817632) (xy 65.30506 -254.878023) (xy 65.336005 -254.942282) (xy 65.359562 -255.009602)
			(xy 65.375432 -255.079137) (xy 65.383418 -255.150011) (xy 65.383918 -255.185672) (xy 65.383418 -255.221333)
			(xy 65.375432 -255.292207) (xy 65.359562 -255.361742) (xy 65.336005 -255.429062) (xy 65.30506 -255.493321)
			(xy 65.267114 -255.553712) (xy 65.222645 -255.609474) (xy 65.172212 -255.659907) (xy 65.11645 -255.704376)
			(xy 65.056059 -255.742322) (xy 64.9918 -255.773267) (xy 64.92448 -255.796824) (xy 64.854945 -255.812694)
			(xy 64.784071 -255.82068) (xy 64.712749 -255.82068) (xy 64.641875 -255.812694) (xy 64.57234 -255.796824)
			(xy 64.50502 -255.773267) (xy 64.440761 -255.742322) (xy 64.38037 -255.704376) (xy 64.324608 -255.659907)
			(xy 64.274175 -255.609474) (xy 64.229706 -255.553712) (xy 64.19176 -255.493321) (xy 64.160815 -255.429062)
			(xy 64.137258 -255.361742) (xy 64.121388 -255.292207) (xy 64.113402 -255.221333) (xy 63.479434 -255.221333)
			(xy 63.471448 -255.292207) (xy 63.455578 -255.361742) (xy 63.432021 -255.429062) (xy 63.401076 -255.493321)
			(xy 63.36313 -255.553712) (xy 63.318661 -255.609474) (xy 63.268228 -255.659907) (xy 63.212466 -255.704376)
			(xy 63.152075 -255.742322) (xy 63.087816 -255.773267) (xy 63.020496 -255.796824) (xy 62.950961 -255.812694)
			(xy 62.880087 -255.82068) (xy 62.808765 -255.82068) (xy 62.737891 -255.812694) (xy 62.668356 -255.796824)
			(xy 62.601036 -255.773267) (xy 62.536777 -255.742322) (xy 62.476386 -255.704376) (xy 62.420624 -255.659907)
			(xy 62.370191 -255.609474) (xy 62.325722 -255.553712) (xy 62.287776 -255.493321) (xy 62.256831 -255.429062)
			(xy 62.233274 -255.361742) (xy 62.217404 -255.292207) (xy 62.209418 -255.221333) (xy 61.238392 -255.221333)
			(xy 61.230406 -255.292207) (xy 61.214536 -255.361742) (xy 61.190979 -255.429062) (xy 61.160034 -255.493321)
			(xy 61.122088 -255.553712) (xy 61.077619 -255.609474) (xy 61.027186 -255.659907) (xy 60.971424 -255.704376)
			(xy 60.911033 -255.742322) (xy 60.846774 -255.773267) (xy 60.779454 -255.796824) (xy 60.709919 -255.812694)
			(xy 60.639045 -255.82068) (xy 60.567723 -255.82068) (xy 60.496849 -255.812694) (xy 60.427314 -255.796824)
			(xy 60.359994 -255.773267) (xy 60.295735 -255.742322) (xy 60.235344 -255.704376) (xy 60.179582 -255.659907)
			(xy 60.129149 -255.609474) (xy 60.08468 -255.553712) (xy 60.046734 -255.493321) (xy 60.015789 -255.429062)
			(xy 59.992232 -255.361742) (xy 59.976362 -255.292207) (xy 59.968376 -255.221333) (xy 59.35168 -255.221333)
			(xy 59.343694 -255.292207) (xy 59.327824 -255.361742) (xy 59.304267 -255.429062) (xy 59.273322 -255.493321)
			(xy 59.235376 -255.553712) (xy 59.190907 -255.609474) (xy 59.140474 -255.659907) (xy 59.084712 -255.704376)
			(xy 59.024321 -255.742322) (xy 58.960062 -255.773267) (xy 58.892742 -255.796824) (xy 58.823207 -255.812694)
			(xy 58.752333 -255.82068) (xy 58.681011 -255.82068) (xy 58.610137 -255.812694) (xy 58.540602 -255.796824)
			(xy 58.473282 -255.773267) (xy 58.409023 -255.742322) (xy 58.348632 -255.704376) (xy 58.29287 -255.659907)
			(xy 58.242437 -255.609474) (xy 58.197968 -255.553712) (xy 58.160022 -255.493321) (xy 58.129077 -255.429062)
			(xy 58.10552 -255.361742) (xy 58.08965 -255.292207) (xy 58.081664 -255.221333) (xy 12.983972 -255.221333)
			(xy 12.983972 -256.21742) (xy 44.245274 -256.21742) (xy 44.249345 -256.161798) (xy 44.261471 -256.107361)
			(xy 44.281394 -256.05527) (xy 44.30869 -256.006635) (xy 44.342776 -255.962492) (xy 44.382925 -255.923783)
			(xy 44.428283 -255.891332) (xy 44.477883 -255.865831) (xy 44.530667 -255.847824) (xy 44.58551 -255.837694)
			(xy 44.641244 -255.835657) (xy 44.696681 -255.841757) (xy 44.750638 -255.855863) (xy 44.801967 -255.877675)
			(xy 44.849573 -255.906729) (xy 44.892441 -255.942404) (xy 44.929658 -255.983941) (xy 44.960431 -256.030454)
			(xy 44.984103 -256.080951) (xy 45.000171 -256.134358) (xy 45.008291 -256.189534) (xy 45.0088 -256.21742)
			(xy 45.008291 -256.245306) (xy 45.000171 -256.300482) (xy 44.984103 -256.353889) (xy 44.960431 -256.404386)
			(xy 44.929658 -256.450899) (xy 44.892441 -256.492436) (xy 44.849573 -256.528111) (xy 44.801967 -256.557165)
			(xy 44.750638 -256.578977) (xy 44.696681 -256.593083) (xy 44.641244 -256.599183) (xy 44.58551 -256.597146)
			(xy 44.530667 -256.587016) (xy 44.477883 -256.569009) (xy 44.428283 -256.543508) (xy 44.382925 -256.511057)
			(xy 44.342776 -256.472348) (xy 44.30869 -256.428205) (xy 44.281394 -256.37957) (xy 44.261471 -256.327479)
			(xy 44.249345 -256.273042) (xy 44.245274 -256.21742) (xy 12.983972 -256.21742) (xy 12.983972 -256.646934)
			(xy 14.114217 -257.777179) (xy 19.03539 -257.777179) (xy 19.039328 -257.722502) (xy 19.051053 -257.668951)
			(xy 19.070324 -257.61763) (xy 19.096744 -257.569598) (xy 19.129768 -257.525843) (xy 19.168717 -257.487266)
			(xy 19.212788 -257.454664) (xy 19.261072 -257.428706) (xy 19.312576 -257.409929) (xy 19.366236 -257.39872)
			(xy 19.420949 -257.395308) (xy 19.475587 -257.399765) (xy 19.529024 -257.411998) (xy 19.580159 -257.431756)
			(xy 19.627939 -257.458631) (xy 19.649948 -257.474974) (xy 19.669174 -257.489086) (xy 19.711723 -257.510616)
			(xy 19.757538 -257.523843) (xy 19.805015 -257.528304) (xy 19.852492 -257.523843) (xy 19.898307 -257.510616)
			(xy 19.940856 -257.489086) (xy 19.960082 -257.474974) (xy 19.982091 -257.458624) (xy 20.029876 -257.431746)
			(xy 20.081018 -257.411986) (xy 20.134462 -257.399752) (xy 20.189107 -257.395295) (xy 20.243827 -257.398709)
			(xy 20.297495 -257.409921) (xy 20.349004 -257.428702) (xy 20.397294 -257.454664) (xy 20.441369 -257.487272)
			(xy 20.480322 -257.525855) (xy 20.513349 -257.569617) (xy 20.539771 -257.617657) (xy 20.559042 -257.668984)
			(xy 20.570767 -257.722543) (xy 20.574702 -257.777228) (xy 20.570767 -257.831913) (xy 20.559044 -257.885471)
			(xy 20.539773 -257.936799) (xy 20.513352 -257.984839) (xy 20.480325 -258.028602) (xy 20.441373 -258.067185)
			(xy 20.397298 -258.099794) (xy 20.349009 -258.125756) (xy 20.312181 -258.139184) (xy 44.188124 -258.139184)
			(xy 44.192195 -258.083562) (xy 44.204321 -258.029125) (xy 44.224244 -257.977034) (xy 44.25154 -257.928399)
			(xy 44.285626 -257.884256) (xy 44.325775 -257.845547) (xy 44.371133 -257.813096) (xy 44.420733 -257.787595)
			(xy 44.473517 -257.769588) (xy 44.52836 -257.759458) (xy 44.584094 -257.757421) (xy 44.639531 -257.763521)
			(xy 44.693488 -257.777627) (xy 44.744817 -257.799439) (xy 44.792423 -257.828493) (xy 44.835291 -257.864168)
			(xy 44.872508 -257.905705) (xy 44.903281 -257.952218) (xy 44.926953 -258.002715) (xy 44.943021 -258.056122)
			(xy 44.951141 -258.111298) (xy 44.95165 -258.139184) (xy 44.951141 -258.16707) (xy 44.943021 -258.222246)
			(xy 44.926953 -258.275653) (xy 44.903281 -258.32615) (xy 44.872508 -258.372663) (xy 44.835291 -258.4142)
			(xy 44.792423 -258.449875) (xy 44.744817 -258.478929) (xy 44.693488 -258.500741) (xy 44.639531 -258.514847)
			(xy 44.584094 -258.520947) (xy 44.52836 -258.51891) (xy 44.473517 -258.50878) (xy 44.420733 -258.490773)
			(xy 44.371133 -258.465272) (xy 44.325775 -258.432821) (xy 44.285626 -258.394112) (xy 44.25154 -258.349969)
			(xy 44.224244 -258.301334) (xy 44.204321 -258.249243) (xy 44.192195 -258.194806) (xy 44.188124 -258.139184)
			(xy 20.312181 -258.139184) (xy 20.2975 -258.144537) (xy 20.243832 -258.155751) (xy 20.189112 -258.159165)
			(xy 20.134467 -258.154709) (xy 20.081023 -258.142476) (xy 20.029881 -258.122716) (xy 19.982095 -258.095839)
			(xy 19.960082 -258.079494) (xy 19.940871 -258.065346) (xy 19.898333 -258.043753) (xy 19.85251 -258.030486)
			(xy 19.805015 -258.026011) (xy 19.75752 -258.030486) (xy 19.711697 -258.043753) (xy 19.669159 -258.065346)
			(xy 19.649948 -258.079494) (xy 19.627904 -258.095792) (xy 19.580122 -258.122662) (xy 19.528984 -258.142414)
			(xy 19.475546 -258.154642) (xy 19.420908 -258.159093) (xy 19.366195 -258.155675) (xy 19.312536 -258.144459)
			(xy 19.261034 -258.125677) (xy 19.212753 -258.099714) (xy 19.168686 -258.067107) (xy 19.129741 -258.028526)
			(xy 19.096721 -257.984767) (xy 19.070306 -257.936732) (xy 19.051041 -257.885409) (xy 19.039322 -257.831857)
			(xy 19.03539 -257.777179) (xy 14.114217 -257.777179) (xy 14.860778 -258.52374) (xy 14.87633 -258.538671)
			(xy 14.911501 -258.563597) (xy 14.950375 -258.582228) (xy 14.991837 -258.594028) (xy 15.034696 -258.598659)
			(xy 15.077721 -258.595988) (xy 15.119678 -258.586091) (xy 15.159362 -258.569253) (xy 15.17777 -258.55803)
			(xy 15.197952 -258.538931) (xy 15.242815 -258.506149) (xy 15.291928 -258.48016) (xy 15.344267 -258.461507)
			(xy 15.398746 -258.450576) (xy 15.45423 -258.447595) (xy 15.509567 -258.452627) (xy 15.563603 -258.465567)
			(xy 15.615217 -258.486144) (xy 15.663334 -258.513933) (xy 15.706953 -258.548353) (xy 15.72641 -258.56819)
			(xy 15.809722 -258.602988) (xy 15.893034 -258.571238) (xy 15.908528 -258.558538) (xy 15.930563 -258.541335)
			(xy 15.978684 -258.512884) (xy 16.03044 -258.491758) (xy 16.084724 -258.478409) (xy 16.140376 -258.473122)
			(xy 16.196203 -258.476009) (xy 16.251011 -258.487011) (xy 16.303629 -258.50589) (xy 16.352929 -258.532243)
			(xy 16.397858 -258.565507) (xy 16.437453 -258.604969) (xy 16.470867 -258.649785) (xy 16.497386 -258.698996)
			(xy 16.516443 -258.75155) (xy 16.527628 -258.806321) (xy 16.530704 -258.862138) (xy 16.528542 -258.890008)
			(xy 16.52546 -258.918089) (xy 16.512075 -258.972971) (xy 16.490743 -259.025279) (xy 16.461932 -259.07387)
			(xy 16.42627 -259.117681) (xy 16.384538 -259.155755) (xy 16.337648 -259.187259) (xy 16.286625 -259.211504)
			(xy 16.232585 -259.227961) (xy 16.176709 -259.236269) (xy 16.120218 -259.236247) (xy 16.064348 -259.227896)
			(xy 16.010321 -259.211398) (xy 15.959317 -259.187113) (xy 15.912451 -259.155573) (xy 15.891256 -259.136896)
			(xy 15.875 -259.12191) (xy 15.785846 -259.084826) (xy 15.708884 -259.114036) (xy 15.697102 -259.12477)
			(xy 15.672049 -259.144478) (xy 15.658846 -259.153406) (xy 15.627096 -259.185156) (xy 15.627096 -259.290312)
			(xy 15.664688 -259.32765) (xy 17.197578 -260.86054) (xy 42.340784 -260.86054) (xy 42.38371 -260.817614)
			(xy 42.726102 -260.475476) (xy 44.062904 -260.475476) (xy 44.084832 -260.474331) (xy 44.12783 -260.465445)
			(xy 44.168661 -260.449304) (xy 44.206112 -260.426387) (xy 44.239068 -260.397376) (xy 44.266549 -260.363134)
			(xy 44.287739 -260.324679) (xy 44.302006 -260.283156) (xy 44.308926 -260.239798) (xy 44.308294 -260.195897)
			(xy 44.304712 -260.174232) (xy 44.299368 -260.146504) (xy 44.295956 -260.090139) (xy 44.30089 -260.033887)
			(xy 44.314063 -259.978977) (xy 44.335188 -259.92661) (xy 44.363802 -259.877928) (xy 44.39928 -259.833998)
			(xy 44.440847 -259.795777) (xy 44.487595 -259.764102) (xy 44.538501 -259.739665) (xy 44.592454 -259.723)
			(xy 44.648274 -259.714472) (xy 44.704742 -259.714265) (xy 44.760622 -259.722386) (xy 44.78782 -259.729986)
			(xy 44.815073 -259.738733) (xy 44.866793 -259.763246) (xy 44.914273 -259.795207) (xy 44.956448 -259.8339)
			(xy 44.992372 -259.878458) (xy 45.02124 -259.92788) (xy 45.042404 -259.981058) (xy 45.055389 -260.036801)
			(xy 45.059905 -260.093858) (xy 45.055849 -260.15095) (xy 45.043314 -260.206795) (xy 45.02258 -260.260143)
			(xy 45.0088 -260.28523) (xy 44.992036 -260.31444) (xy 44.992036 -260.348476) (xy 44.992528 -260.365131)
			(xy 45.001146 -260.397307) (xy 45.0178 -260.426155) (xy 45.041355 -260.449708) (xy 45.070204 -260.466359)
			(xy 45.102381 -260.474974) (xy 45.119036 -260.475476) (xy 45.309282 -260.475476) (xy 46.342554 -259.442204)
			(xy 46.476158 -259.442204) (xy 46.492817 -259.441714) (xy 46.525001 -259.4331) (xy 46.553858 -259.416449)
			(xy 46.577421 -259.392894) (xy 46.594083 -259.364043) (xy 46.602708 -259.331862) (xy 46.603158 -259.315204)
			(xy 46.603158 -259.283708) (xy 46.574456 -259.22859) (xy 46.548548 -259.21081) (xy 46.526093 -259.194648)
			(xy 46.48565 -259.156897) (xy 46.45108 -259.113702) (xy 46.42311 -259.065969) (xy 46.402324 -259.014698)
			(xy 46.389158 -258.960962) (xy 46.383889 -258.905889) (xy 46.386626 -258.850632) (xy 46.397312 -258.79635)
			(xy 46.415724 -258.744179) (xy 46.441476 -258.695213) (xy 46.474027 -258.650477) (xy 46.512696 -258.610911)
			(xy 46.556672 -258.577342) (xy 46.605035 -258.550474) (xy 46.656769 -258.53087) (xy 46.710793 -258.51894)
			(xy 46.765972 -258.514936) (xy 46.821151 -258.51894) (xy 46.875175 -258.53087) (xy 46.926909 -258.550474)
			(xy 46.975272 -258.577342) (xy 47.019248 -258.610911) (xy 47.057917 -258.650477) (xy 47.090468 -258.695213)
			(xy 47.11622 -258.744179) (xy 47.134632 -258.79635) (xy 47.145318 -258.850632) (xy 47.148055 -258.905889)
			(xy 47.142786 -258.960962) (xy 47.12962 -259.014698) (xy 47.108834 -259.065969) (xy 47.080864 -259.113702)
			(xy 47.046294 -259.156897) (xy 47.005851 -259.194648) (xy 46.983396 -259.21081) (xy 46.957488 -259.22859)
			(xy 46.928786 -259.283708) (xy 46.928786 -259.315204) (xy 46.92933 -259.331853) (xy 46.937948 -259.364015)
			(xy 46.954596 -259.392852) (xy 46.97814 -259.416398) (xy 47.006975 -259.433048) (xy 47.039137 -259.441669)
			(xy 47.055786 -259.442204) (xy 47.229776 -259.442204) (xy 47.251563 -259.441054) (xy 47.294287 -259.432235)
			(xy 47.33488 -259.416258) (xy 47.372154 -259.39359) (xy 47.405015 -259.364898) (xy 47.432501 -259.331021)
			(xy 47.453805 -259.292952) (xy 47.468304 -259.251807) (xy 47.472346 -259.230368) (xy 47.476771 -259.203531)
			(xy 47.492228 -259.151384) (xy 47.514936 -259.101961) (xy 47.544433 -259.056264) (xy 47.580121 -259.015221)
			(xy 47.621278 -258.979662) (xy 47.667067 -258.950309) (xy 47.716561 -258.927757) (xy 47.768757 -258.912463)
			(xy 47.822595 -258.904738) (xy 47.876985 -258.904738) (xy 47.930823 -258.912463) (xy 47.983019 -258.927757)
			(xy 48.032513 -258.950309) (xy 48.078302 -258.979662) (xy 48.119459 -259.015221) (xy 48.155147 -259.056264)
			(xy 48.184644 -259.101961) (xy 48.207352 -259.151384) (xy 48.222809 -259.203531) (xy 48.227234 -259.230368)
			(xy 48.231293 -259.251806) (xy 48.245762 -259.292964) (xy 48.26705 -259.331045) (xy 48.29453 -259.364931)
			(xy 48.327395 -259.393624) (xy 48.364677 -259.416281) (xy 48.405283 -259.432237) (xy 48.448016 -259.441022)
			(xy 48.469804 -259.442204) (xy 64.619886 -259.442204) (xy 64.634487 -259.441118) (xy 64.662648 -259.433133)
			(xy 64.688248 -259.418941) (xy 64.699388 -259.409438) (xy 77.99324 -246.115586) (xy 77.99324 -235.589572)
			(xy 82.617564 -230.964994) (xy 82.617564 -216.241376) (xy 83.931506 -214.927434) (xy 83.941029 -214.91631)
			(xy 83.955217 -214.890703) (xy 83.963194 -214.862535) (xy 83.964272 -214.847932) (xy 83.964272 -202.780646)
			(xy 83.963737 -202.764027) (xy 83.955152 -202.731916) (xy 83.938555 -202.703119) (xy 83.927188 -202.690984)
			(xy 82.990944 -201.754994) (xy 82.873088 -201.637138) (xy 82.873088 -192.75044) (xy 82.85734 -192.721738)
			(xy 82.844429 -192.697397) (xy 82.824972 -192.645849) (xy 82.813134 -192.592037) (xy 82.809163 -192.537082)
			(xy 82.813139 -192.482128) (xy 82.824982 -192.428318) (xy 82.844443 -192.376771) (xy 82.85734 -192.352422)
			(xy 82.873088 -192.32372) (xy 82.873088 -183.590692) (xy 85.31606 -181.14772) (xy 90.782394 -181.14772)
			(xy 91.712034 -182.07736) (xy 91.723736 -182.088428) (xy 91.751462 -182.104802) (xy 91.78241 -182.113693)
			(xy 91.814599 -182.114534) (xy 91.830398 -182.111396) (xy 91.867795 -182.103282) (xy 91.943778 -182.094167)
			(xy 92.020301 -182.093257) (xy 92.096479 -182.100561) (xy 92.171434 -182.115997) (xy 92.244301 -182.139385)
			(xy 92.314237 -182.170456) (xy 92.380437 -182.208851) (xy 92.442135 -182.254127) (xy 92.498619 -182.305761)
			(xy 92.549237 -182.363157) (xy 92.593406 -182.425652) (xy 92.630615 -182.492526) (xy 92.660434 -182.563005)
			(xy 92.682519 -182.636277) (xy 92.696616 -182.711495) (xy 92.702562 -182.787792) (xy 92.700287 -182.864286)
			(xy 92.689819 -182.940095) (xy 92.671278 -183.014343) (xy 92.644878 -183.086173) (xy 92.610924 -183.154756)
			(xy 92.569807 -183.2193) (xy 92.522004 -183.279061) (xy 92.468064 -183.333348) (xy 92.408612 -183.381534)
			(xy 92.376752 -183.402732) (xy 92.376752 -184.741058) (xy 92.395548 -184.759854) (xy 92.425751 -184.78131)
			(xy 92.481991 -184.829544) (xy 92.532912 -184.883364) (xy 92.577963 -184.942184) (xy 92.616655 -185.005369)
			(xy 92.64857 -185.072234) (xy 92.673362 -185.142054) (xy 92.690762 -185.214073) (xy 92.700581 -185.28751)
			(xy 92.702714 -185.361571) (xy 92.697136 -185.435451) (xy 92.683909 -185.508352) (xy 92.663176 -185.579483)
			(xy 92.635161 -185.648073) (xy 92.600169 -185.71338) (xy 92.558577 -185.774696) (xy 92.510837 -185.831356)
			(xy 92.457466 -185.882746) (xy 92.399042 -185.928311) (xy 92.367862 -185.94832) (xy 92.354467 -185.957252)
			(xy 92.332318 -185.980606) (xy 92.316721 -186.00876) (xy 92.308668 -186.039923) (xy 92.308172 -186.056016)
			(xy 92.308172 -186.06008) (xy 93.15476 -186.06008) (xy 93.158776 -185.94381) (xy 93.170803 -185.828095)
			(xy 93.190785 -185.713485) (xy 93.218627 -185.600526) (xy 93.254196 -185.489758) (xy 93.297322 -185.381707)
			(xy 93.347799 -185.276889) (xy 93.405388 -185.175804) (xy 93.469814 -185.078932) (xy 93.540769 -184.986736)
			(xy 93.617916 -184.899655) (xy 93.700887 -184.818104) (xy 93.789287 -184.742472) (xy 93.882694 -184.673118)
			(xy 93.980663 -184.610375) (xy 94.082727 -184.554539) (xy 94.188401 -184.505878) (xy 94.29718 -184.464624)
			(xy 94.408545 -184.430973) (xy 94.521968 -184.405085) (xy 94.636905 -184.387084) (xy 94.752811 -184.377055)
			(xy 94.869133 -184.375047) (xy 94.985316 -184.381069) (xy 95.100807 -184.395092) (xy 95.215055 -184.41705)
			(xy 95.327516 -184.446837) (xy 95.437654 -184.484312) (xy 95.544944 -184.529297) (xy 95.648875 -184.581576)
			(xy 95.748951 -184.640901) (xy 95.844697 -184.706989) (xy 95.935654 -184.779525) (xy 96.02139 -184.858164)
			(xy 96.101497 -184.94253) (xy 96.175593 -185.032222) (xy 96.243323 -185.126812) (xy 96.304367 -185.22585)
			(xy 96.358432 -185.328863) (xy 96.405262 -185.43536) (xy 96.444633 -185.544835) (xy 96.476357 -185.656765)
			(xy 96.500283 -185.770617) (xy 96.516297 -185.885849) (xy 96.524324 -186.001911) (xy 96.524826 -186.06008)
			(xy 96.524324 -186.118249) (xy 96.516297 -186.234311) (xy 96.500283 -186.349543) (xy 96.476357 -186.463395)
			(xy 96.444633 -186.575325) (xy 96.405262 -186.6848) (xy 96.358432 -186.791297) (xy 96.304367 -186.89431)
			(xy 96.243323 -186.993348) (xy 96.175593 -187.087938) (xy 96.101497 -187.17763) (xy 96.02139 -187.261996)
			(xy 95.935654 -187.340635) (xy 95.844697 -187.413171) (xy 95.748951 -187.479259) (xy 95.648875 -187.538584)
			(xy 95.544944 -187.590863) (xy 95.437654 -187.635848) (xy 95.327516 -187.673323) (xy 95.215055 -187.70311)
			(xy 95.100807 -187.725068) (xy 94.985316 -187.739091) (xy 94.869133 -187.745113) (xy 94.752811 -187.743105)
			(xy 94.636905 -187.733076) (xy 94.521968 -187.715075) (xy 94.408545 -187.689187) (xy 94.29718 -187.655536)
			(xy 94.188401 -187.614282) (xy 94.082727 -187.565621) (xy 93.980663 -187.509785) (xy 93.882694 -187.447042)
			(xy 93.789287 -187.377688) (xy 93.700887 -187.302056) (xy 93.617916 -187.220505) (xy 93.540769 -187.133424)
			(xy 93.469814 -187.041228) (xy 93.405388 -186.944356) (xy 93.347799 -186.843271) (xy 93.297322 -186.738453)
			(xy 93.254196 -186.630402) (xy 93.218627 -186.519634) (xy 93.190785 -186.406675) (xy 93.170803 -186.292065)
			(xy 93.158776 -186.17635) (xy 93.15476 -186.06008) (xy 92.308172 -186.06008) (xy 92.308172 -186.572398)
			(xy 90.668094 -188.212476) (xy 90.600276 -188.212476) (xy 87.779606 -191.033146) (xy 87.770462 -191.064642)
			(xy 87.762386 -191.091042) (xy 87.739682 -191.141366) (xy 87.709962 -191.187891) (xy 87.693537 -191.206882)
			(xy 91.71254 -191.206882) (xy 91.716611 -191.15126) (xy 91.728737 -191.096823) (xy 91.74866 -191.044732)
			(xy 91.775956 -190.996097) (xy 91.810042 -190.951954) (xy 91.850191 -190.913245) (xy 91.895549 -190.880794)
			(xy 91.945149 -190.855293) (xy 91.997933 -190.837286) (xy 92.052776 -190.827156) (xy 92.10851 -190.825119)
			(xy 92.163947 -190.831219) (xy 92.217904 -190.845325) (xy 92.269233 -190.867137) (xy 92.316839 -190.896191)
			(xy 92.359707 -190.931866) (xy 92.396924 -190.973403) (xy 92.427697 -191.019916) (xy 92.451369 -191.070413)
			(xy 92.467437 -191.12382) (xy 92.475557 -191.178996) (xy 92.476066 -191.206882) (xy 92.475557 -191.234768)
			(xy 92.467437 -191.289944) (xy 92.451369 -191.343351) (xy 92.427697 -191.393848) (xy 92.396924 -191.440361)
			(xy 92.359707 -191.481898) (xy 92.316839 -191.517573) (xy 92.269233 -191.546627) (xy 92.217904 -191.568439)
			(xy 92.163947 -191.582545) (xy 92.10851 -191.588645) (xy 92.052776 -191.586608) (xy 91.997933 -191.576478)
			(xy 91.945149 -191.558471) (xy 91.895549 -191.53297) (xy 91.850191 -191.500519) (xy 91.810042 -191.46181)
			(xy 91.775956 -191.417667) (xy 91.74866 -191.369032) (xy 91.728737 -191.316941) (xy 91.716611 -191.262504)
			(xy 91.71254 -191.206882) (xy 87.693537 -191.206882) (xy 87.673847 -191.229647) (xy 87.632091 -191.265762)
			(xy 87.585566 -191.295482) (xy 87.535242 -191.318186) (xy 87.508842 -191.326262) (xy 87.477346 -191.335406)
			(xy 87.10676 -191.705992) (xy 95.288098 -191.705992) (xy 95.292169 -191.65037) (xy 95.304295 -191.595933)
			(xy 95.324218 -191.543842) (xy 95.351514 -191.495207) (xy 95.3856 -191.451064) (xy 95.425749 -191.412355)
			(xy 95.471107 -191.379904) (xy 95.520707 -191.354403) (xy 95.573491 -191.336396) (xy 95.628334 -191.326266)
			(xy 95.684068 -191.324229) (xy 95.739505 -191.330329) (xy 95.793462 -191.344435) (xy 95.844791 -191.366247)
			(xy 95.892397 -191.395301) (xy 95.935265 -191.430976) (xy 95.972482 -191.472513) (xy 96.003255 -191.519026)
			(xy 96.026927 -191.569523) (xy 96.042995 -191.62293) (xy 96.051115 -191.678106) (xy 96.051624 -191.705992)
			(xy 96.051115 -191.733878) (xy 96.042995 -191.789054) (xy 96.026927 -191.842461) (xy 96.003255 -191.892958)
			(xy 95.972482 -191.939471) (xy 95.935265 -191.981008) (xy 95.892397 -192.016683) (xy 95.844791 -192.045737)
			(xy 95.793462 -192.067549) (xy 95.739505 -192.081655) (xy 95.684068 -192.087755) (xy 95.628334 -192.085718)
			(xy 95.573491 -192.075588) (xy 95.520707 -192.057581) (xy 95.471107 -192.03208) (xy 95.425749 -191.999629)
			(xy 95.3856 -191.96092) (xy 95.351514 -191.916777) (xy 95.324218 -191.868142) (xy 95.304295 -191.816051)
			(xy 95.292169 -191.761614) (xy 95.288098 -191.705992) (xy 87.10676 -191.705992) (xy 86.515194 -192.297558)
			(xy 86.50567 -192.308682) (xy 86.49148 -192.334288) (xy 86.483502 -192.362456) (xy 86.482428 -192.37706)
			(xy 86.482428 -197.81012) (xy 86.877404 -197.81012) (xy 86.881424 -197.619469) (xy 86.893478 -197.429156)
			(xy 86.913544 -197.239521) (xy 86.941587 -197.0509) (xy 86.977556 -196.86363) (xy 87.021388 -196.678042)
			(xy 87.073005 -196.494467) (xy 87.132315 -196.313231) (xy 87.199213 -196.134656) (xy 87.273579 -195.959061)
			(xy 87.355281 -195.786756) (xy 87.444175 -195.618049) (xy 87.540101 -195.453239) (xy 87.64289 -195.29262)
			(xy 87.752359 -195.136477) (xy 87.868313 -194.985088) (xy 87.990547 -194.838721) (xy 88.118841 -194.697637)
			(xy 88.252969 -194.562088) (xy 88.392693 -194.432313) (xy 88.537763 -194.308543) (xy 88.687921 -194.191)
			(xy 88.842902 -194.079891) (xy 89.002429 -193.975414) (xy 89.166218 -193.877755) (xy 89.333978 -193.787088)
			(xy 89.505412 -193.703574) (xy 89.680214 -193.627361) (xy 89.858073 -193.558585) (xy 90.038674 -193.497367)
			(xy 90.221694 -193.443818) (xy 90.40681 -193.398032) (xy 90.593691 -193.36009) (xy 90.782006 -193.330061)
			(xy 90.971419 -193.307996) (xy 91.161593 -193.293937) (xy 91.352192 -193.287907) (xy 91.542875 -193.289917)
			(xy 91.733304 -193.299964) (xy 91.92314 -193.31803) (xy 92.112046 -193.344083) (xy 92.299685 -193.378076)
			(xy 92.485725 -193.419949) (xy 92.669834 -193.469628) (xy 92.710516 -193.482468) (xy 96.185226 -193.482468)
			(xy 96.189297 -193.426846) (xy 96.201423 -193.372409) (xy 96.221346 -193.320318) (xy 96.248642 -193.271683)
			(xy 96.282728 -193.22754) (xy 96.322877 -193.188831) (xy 96.368235 -193.15638) (xy 96.417835 -193.130879)
			(xy 96.470619 -193.112872) (xy 96.525462 -193.102742) (xy 96.581196 -193.100705) (xy 96.636633 -193.106805)
			(xy 96.69059 -193.120911) (xy 96.741919 -193.142723) (xy 96.789525 -193.171777) (xy 96.832393 -193.207452)
			(xy 96.86961 -193.248989) (xy 96.900383 -193.295502) (xy 96.924055 -193.345999) (xy 96.940123 -193.399406)
			(xy 96.948243 -193.454582) (xy 96.948752 -193.482468) (xy 96.948243 -193.510354) (xy 96.940123 -193.56553)
			(xy 96.924055 -193.618937) (xy 96.900383 -193.669434) (xy 96.86961 -193.715947) (xy 96.832393 -193.757484)
			(xy 96.789525 -193.793159) (xy 96.741919 -193.822213) (xy 96.69059 -193.844025) (xy 96.636633 -193.858131)
			(xy 96.581196 -193.864231) (xy 96.525462 -193.862194) (xy 96.470619 -193.852064) (xy 96.417835 -193.834057)
			(xy 96.368235 -193.808556) (xy 96.322877 -193.776105) (xy 96.282728 -193.737396) (xy 96.248642 -193.693253)
			(xy 96.221346 -193.644618) (xy 96.201423 -193.592527) (xy 96.189297 -193.53809) (xy 96.185226 -193.482468)
			(xy 92.710516 -193.482468) (xy 92.851685 -193.527024) (xy 93.030955 -193.592035) (xy 93.207325 -193.664546)
			(xy 93.380481 -193.744427) (xy 93.550116 -193.831537) (xy 93.715928 -193.925721) (xy 93.877622 -194.026812)
			(xy 94.03491 -194.134628) (xy 94.187513 -194.24898) (xy 94.335161 -194.369663) (xy 94.477589 -194.496464)
			(xy 94.519506 -194.537076) (xy 99.002594 -194.537076) (xy 99.006665 -194.481454) (xy 99.018791 -194.427017)
			(xy 99.038714 -194.374926) (xy 99.06601 -194.326291) (xy 99.100096 -194.282148) (xy 99.140245 -194.243439)
			(xy 99.185603 -194.210988) (xy 99.235203 -194.185487) (xy 99.287987 -194.16748) (xy 99.34283 -194.15735)
			(xy 99.398564 -194.155313) (xy 99.454001 -194.161413) (xy 99.507958 -194.175519) (xy 99.559287 -194.197331)
			(xy 99.606893 -194.226385) (xy 99.649761 -194.26206) (xy 99.686978 -194.303597) (xy 99.717751 -194.35011)
			(xy 99.741423 -194.400607) (xy 99.757491 -194.454014) (xy 99.765611 -194.50919) (xy 99.76612 -194.537076)
			(xy 99.765611 -194.564962) (xy 99.757491 -194.620138) (xy 99.741423 -194.673545) (xy 99.717751 -194.724042)
			(xy 99.686978 -194.770555) (xy 99.649761 -194.812092) (xy 99.606893 -194.847767) (xy 99.559287 -194.876821)
			(xy 99.507958 -194.898633) (xy 99.454001 -194.912739) (xy 99.398564 -194.918839) (xy 99.34283 -194.916802)
			(xy 99.287987 -194.906672) (xy 99.235203 -194.888665) (xy 99.185603 -194.863164) (xy 99.140245 -194.830713)
			(xy 99.100096 -194.792004) (xy 99.06601 -194.747861) (xy 99.038714 -194.699226) (xy 99.018791 -194.647135)
			(xy 99.006665 -194.592698) (xy 99.002594 -194.537076) (xy 94.519506 -194.537076) (xy 94.614545 -194.629155)
			(xy 94.745786 -194.767503) (xy 94.871078 -194.91126) (xy 94.940737 -194.99834) (xy 96.87255 -194.99834)
			(xy 96.876621 -194.942718) (xy 96.888747 -194.888281) (xy 96.90867 -194.83619) (xy 96.935966 -194.787555)
			(xy 96.970052 -194.743412) (xy 97.010201 -194.704703) (xy 97.055559 -194.672252) (xy 97.105159 -194.646751)
			(xy 97.157943 -194.628744) (xy 97.212786 -194.618614) (xy 97.26852 -194.616577) (xy 97.323957 -194.622677)
			(xy 97.377914 -194.636783) (xy 97.429243 -194.658595) (xy 97.476849 -194.687649) (xy 97.519717 -194.723324)
			(xy 97.556934 -194.764861) (xy 97.587707 -194.811374) (xy 97.611379 -194.861871) (xy 97.627447 -194.915278)
			(xy 97.635567 -194.970454) (xy 97.636076 -194.99834) (xy 97.635567 -195.026226) (xy 97.627447 -195.081402)
			(xy 97.611379 -195.134809) (xy 97.587707 -195.185306) (xy 97.556934 -195.231819) (xy 97.519717 -195.273356)
			(xy 97.476849 -195.309031) (xy 97.429243 -195.338085) (xy 97.377914 -195.359897) (xy 97.323957 -195.374003)
			(xy 97.26852 -195.380103) (xy 97.212786 -195.378066) (xy 97.157943 -195.367936) (xy 97.105159 -195.349929)
			(xy 97.055559 -195.324428) (xy 97.010201 -195.291977) (xy 96.970052 -195.253268) (xy 96.935966 -195.209125)
			(xy 96.90867 -195.16049) (xy 96.888747 -195.108399) (xy 96.876621 -195.053962) (xy 96.87255 -194.99834)
			(xy 94.940737 -194.99834) (xy 94.990198 -195.060171) (xy 95.102934 -195.213972) (xy 95.209087 -195.372388)
			(xy 95.308467 -195.535139) (xy 95.400897 -195.701934) (xy 95.486214 -195.872478) (xy 95.564266 -196.046466)
			(xy 95.634913 -196.223591) (xy 95.698031 -196.403536) (xy 95.753507 -196.585982) (xy 95.778295 -196.681852)
			(xy 97.862642 -196.681852) (xy 97.866713 -196.62623) (xy 97.878839 -196.571793) (xy 97.898762 -196.519702)
			(xy 97.926058 -196.471067) (xy 97.960144 -196.426924) (xy 98.000293 -196.388215) (xy 98.045651 -196.355764)
			(xy 98.095251 -196.330263) (xy 98.148035 -196.312256) (xy 98.202878 -196.302126) (xy 98.258612 -196.300089)
			(xy 98.314049 -196.306189) (xy 98.368006 -196.320295) (xy 98.419335 -196.342107) (xy 98.466941 -196.371161)
			(xy 98.509809 -196.406836) (xy 98.547026 -196.448373) (xy 98.577799 -196.494886) (xy 98.601471 -196.545383)
			(xy 98.617539 -196.59879) (xy 98.625659 -196.653966) (xy 98.626168 -196.681852) (xy 98.625659 -196.709738)
			(xy 98.617539 -196.764914) (xy 98.601471 -196.818321) (xy 98.577799 -196.868818) (xy 98.547026 -196.915331)
			(xy 98.509809 -196.956868) (xy 98.466941 -196.992543) (xy 98.419335 -197.021597) (xy 98.368006 -197.043409)
			(xy 98.314049 -197.057515) (xy 98.258612 -197.063615) (xy 98.202878 -197.061578) (xy 98.148035 -197.051448)
			(xy 98.095251 -197.033441) (xy 98.045651 -197.00794) (xy 98.000293 -196.975489) (xy 97.960144 -196.93678)
			(xy 97.926058 -196.892637) (xy 97.898762 -196.844002) (xy 97.878839 -196.791911) (xy 97.866713 -196.737474)
			(xy 97.862642 -196.681852) (xy 95.778295 -196.681852) (xy 95.801242 -196.770605) (xy 95.841152 -196.957075)
			(xy 95.873165 -197.145063) (xy 95.897225 -197.334233) (xy 95.913288 -197.524249) (xy 95.921327 -197.714773)
			(xy 95.92183 -197.81012) (xy 95.921327 -197.905467) (xy 95.913288 -198.095991) (xy 95.897225 -198.286007)
			(xy 95.873165 -198.475177) (xy 95.841152 -198.663165) (xy 95.801242 -198.849635) (xy 95.753507 -199.034258)
			(xy 95.698031 -199.216704) (xy 95.634913 -199.396649) (xy 95.564266 -199.573774) (xy 95.486214 -199.747762)
			(xy 95.400897 -199.918306) (xy 95.308467 -200.085101) (xy 95.209087 -200.247852) (xy 95.102934 -200.406268)
			(xy 94.990198 -200.560069) (xy 94.871078 -200.70898) (xy 94.745786 -200.852737) (xy 94.614545 -200.991085)
			(xy 94.477589 -201.123776) (xy 94.335161 -201.250577) (xy 94.187513 -201.37126) (xy 94.03491 -201.485612)
			(xy 93.877622 -201.593428) (xy 93.715928 -201.694519) (xy 93.550116 -201.788703) (xy 93.380481 -201.875813)
			(xy 93.207325 -201.955694) (xy 93.030955 -202.028205) (xy 92.851685 -202.093216) (xy 92.669834 -202.150612)
			(xy 92.485725 -202.200291) (xy 92.299685 -202.242164) (xy 92.112046 -202.276157) (xy 91.92314 -202.30221)
			(xy 91.733304 -202.320276) (xy 91.542875 -202.330323) (xy 91.352192 -202.332333) (xy 91.161593 -202.326303)
			(xy 90.971419 -202.312244) (xy 90.782006 -202.290179) (xy 90.593691 -202.26015) (xy 90.40681 -202.222208)
			(xy 90.221694 -202.176422) (xy 90.038674 -202.122873) (xy 89.858073 -202.061655) (xy 89.680214 -201.992879)
			(xy 89.505412 -201.916666) (xy 89.333978 -201.833152) (xy 89.166218 -201.742485) (xy 89.002429 -201.644826)
			(xy 88.842902 -201.540349) (xy 88.687921 -201.42924) (xy 88.537763 -201.311697) (xy 88.392693 -201.187927)
			(xy 88.252969 -201.058152) (xy 88.118841 -200.922603) (xy 87.990547 -200.781519) (xy 87.868313 -200.635152)
			(xy 87.752359 -200.483763) (xy 87.64289 -200.32762) (xy 87.540101 -200.167001) (xy 87.444175 -200.002191)
			(xy 87.355281 -199.833484) (xy 87.273579 -199.661179) (xy 87.199213 -199.485584) (xy 87.132315 -199.307009)
			(xy 87.073005 -199.125773) (xy 87.021388 -198.942198) (xy 86.977556 -198.75661) (xy 86.941587 -198.56934)
			(xy 86.913544 -198.380719) (xy 86.893478 -198.191084) (xy 86.881424 -198.000771) (xy 86.877404 -197.81012)
			(xy 86.482428 -197.81012) (xy 86.482428 -216.026492) (xy 85.141816 -217.367104) (xy 85.141816 -227.25507)
			(xy 86.197697 -227.25507) (xy 86.201732 -227.179366) (xy 86.213791 -227.104521) (xy 86.233737 -227.03138)
			(xy 86.261344 -226.960775) (xy 86.2963 -226.893504) (xy 86.338208 -226.830329) (xy 86.386594 -226.771967)
			(xy 86.44091 -226.719079) (xy 86.500539 -226.672264) (xy 86.564807 -226.632052) (xy 86.632984 -226.5989)
			(xy 86.7043 -226.573182) (xy 86.777945 -226.55519) (xy 86.853085 -226.545128) (xy 86.928869 -226.543109)
			(xy 87.004439 -226.549158) (xy 87.078937 -226.563205) (xy 87.15152 -226.585091) (xy 87.221366 -226.614568)
			(xy 87.287683 -226.651303) (xy 87.349719 -226.694878) (xy 87.406772 -226.7448) (xy 87.458196 -226.800504)
			(xy 87.503407 -226.861359) (xy 87.541894 -226.926674) (xy 87.57322 -226.99571) (xy 87.59703 -227.067685)
			(xy 87.613055 -227.141783) (xy 87.621114 -227.217164) (xy 87.621618 -227.25507) (xy 87.621114 -227.292976)
			(xy 87.613055 -227.368357) (xy 87.59703 -227.442455) (xy 87.57322 -227.51443) (xy 87.541894 -227.583466)
			(xy 87.503407 -227.648781) (xy 87.458196 -227.709636) (xy 87.406772 -227.76534) (xy 87.349719 -227.815262)
			(xy 87.287683 -227.858837) (xy 87.221366 -227.895572) (xy 87.15152 -227.925049) (xy 87.078937 -227.946935)
			(xy 87.004439 -227.960982) (xy 86.928869 -227.967031) (xy 86.853085 -227.965012) (xy 86.777945 -227.95495)
			(xy 86.7043 -227.936958) (xy 86.632984 -227.91124) (xy 86.564807 -227.878088) (xy 86.500539 -227.837876)
			(xy 86.44091 -227.791061) (xy 86.386594 -227.738173) (xy 86.338208 -227.679811) (xy 86.2963 -227.616636)
			(xy 86.261344 -227.549365) (xy 86.233737 -227.47876) (xy 86.213791 -227.405619) (xy 86.201732 -227.330774)
			(xy 86.197697 -227.25507) (xy 85.141816 -227.25507) (xy 85.141816 -227.598732) (xy 85.143048 -227.62139)
			(xy 85.152535 -227.665759) (xy 85.169741 -227.707743) (xy 85.194119 -227.746009) (xy 85.224897 -227.779346)
			(xy 85.2611 -227.806696) (xy 85.301579 -227.827193) (xy 85.345051 -227.840186) (xy 85.390138 -227.845264)
			(xy 85.435411 -227.842265) (xy 85.457538 -227.837238) (xy 85.493635 -227.82817) (xy 85.567179 -227.816709)
			(xy 85.641517 -227.812988) (xy 85.715837 -227.817047) (xy 85.789328 -227.828841) (xy 85.861186 -227.848241)
			(xy 85.930627 -227.875036) (xy 85.996892 -227.908933) (xy 86.059257 -227.949561) (xy 86.11704 -227.996476)
			(xy 86.169611 -228.049167) (xy 86.216394 -228.107057) (xy 86.25688 -228.169515) (xy 86.290626 -228.235856)
			(xy 86.317262 -228.305358) (xy 86.336498 -228.377261) (xy 86.348124 -228.450778) (xy 86.352013 -228.525108)
			(xy 86.348123 -228.599437) (xy 86.336495 -228.672954) (xy 86.317257 -228.744856) (xy 86.290619 -228.814358)
			(xy 86.256872 -228.880699) (xy 86.216385 -228.943155) (xy 86.1696 -229.001044) (xy 86.117029 -229.053734)
			(xy 86.059244 -229.100648) (xy 85.996879 -229.141275) (xy 85.930613 -229.17517) (xy 85.861172 -229.201964)
			(xy 85.789313 -229.221362) (xy 85.715822 -229.233155) (xy 85.641501 -229.237212) (xy 85.567163 -229.233489)
			(xy 85.49362 -229.222027) (xy 85.457538 -229.212902) (xy 85.435405 -229.207874) (xy 85.390122 -229.204838)
			(xy 85.34502 -229.20989) (xy 85.301531 -229.222868) (xy 85.261037 -229.24336) (xy 85.224825 -229.270716)
			(xy 85.194044 -229.304067) (xy 85.169672 -229.342352) (xy 85.152485 -229.384355) (xy 85.143027 -229.428743)
			(xy 85.141816 -229.451408) (xy 85.141816 -230.138732) (xy 85.143048 -230.16139) (xy 85.152535 -230.205759)
			(xy 85.169741 -230.247743) (xy 85.194119 -230.286009) (xy 85.224897 -230.319346) (xy 85.2611 -230.346696)
			(xy 85.301579 -230.367193) (xy 85.345051 -230.380186) (xy 85.390138 -230.385264) (xy 85.435411 -230.382265)
			(xy 85.457538 -230.377238) (xy 85.493556 -230.368187) (xy 85.566937 -230.356737) (xy 85.641111 -230.352991)
			(xy 85.715272 -230.356989) (xy 85.788614 -230.368689) (xy 85.860338 -230.387963) (xy 85.929666 -230.414601)
			(xy 85.995842 -230.448314) (xy 86.058148 -230.488735) (xy 86.115905 -230.535424) (xy 86.168487 -230.587875)
			(xy 86.21532 -230.645516) (xy 86.255897 -230.707721) (xy 86.289774 -230.773813) (xy 86.303612 -230.808276)
			(xy 86.313264 -230.833168) (xy 86.332314 -230.852218) (xy 86.344446 -230.863679) (xy 86.373325 -230.880388)
			(xy 86.405548 -230.889039) (xy 86.438912 -230.889039) (xy 86.471135 -230.880388) (xy 86.500014 -230.863679)
			(xy 86.512146 -230.852218) (xy 86.583012 -230.781098) (xy 86.583012 -230.500428) (xy 86.582561 -230.484533)
			(xy 86.574767 -230.453717) (xy 86.559581 -230.425791) (xy 86.537952 -230.402498) (xy 86.524846 -230.393494)
			(xy 86.494062 -230.373121) (xy 86.436456 -230.326952) (xy 86.383939 -230.275069) (xy 86.337074 -230.218028)
			(xy 86.296365 -230.156442) (xy 86.262249 -230.090974) (xy 86.235093 -230.022326) (xy 86.215189 -229.951236)
			(xy 86.20275 -229.878468) (xy 86.19791 -229.804802) (xy 86.20072 -229.731032) (xy 86.211152 -229.657949)
			(xy 86.229092 -229.586338) (xy 86.254349 -229.516968) (xy 86.28665 -229.450586) (xy 86.325648 -229.387904)
			(xy 86.370926 -229.329595) (xy 86.396068 -229.302564) (xy 86.42284 -229.275348) (xy 86.481256 -229.226194)
			(xy 86.544599 -229.183576) (xy 86.612141 -229.147983) (xy 86.683104 -229.119826) (xy 86.756674 -229.099426)
			(xy 86.832004 -229.08702) (xy 86.908231 -229.082749) (xy 86.984476 -229.086662) (xy 87.059864 -229.098716)
			(xy 87.133529 -229.11877) (xy 87.204623 -229.146594) (xy 87.272331 -229.18187) (xy 87.335873 -229.224191)
			(xy 87.394519 -229.27307) (xy 87.447596 -229.327947) (xy 87.494494 -229.388191) (xy 87.534672 -229.453109)
			(xy 87.567671 -229.521954) (xy 87.59311 -229.593937) (xy 87.602314 -229.630986) (xy 87.606793 -229.647384)
			(xy 87.623141 -229.677174) (xy 87.646769 -229.701596) (xy 87.676001 -229.718921) (xy 87.708768 -229.727921)
			(xy 87.725758 -229.728522) (xy 87.726012 -229.728522) (xy 87.74266 -229.727977) (xy 87.774822 -229.719358)
			(xy 87.803658 -229.702709) (xy 87.827203 -229.679166) (xy 87.843854 -229.650331) (xy 87.852476 -229.61817)
			(xy 87.853012 -229.601522) (xy 87.853012 -229.230428) (xy 87.852561 -229.214533) (xy 87.844767 -229.183717)
			(xy 87.829581 -229.155791) (xy 87.807952 -229.132498) (xy 87.794846 -229.123494) (xy 87.764062 -229.103121)
			(xy 87.706456 -229.056952) (xy 87.653939 -229.005069) (xy 87.607074 -228.948028) (xy 87.566365 -228.886442)
			(xy 87.532249 -228.820974) (xy 87.505093 -228.752326) (xy 87.485189 -228.681236) (xy 87.47275 -228.608468)
			(xy 87.46791 -228.534802) (xy 87.47072 -228.461032) (xy 87.481152 -228.387949) (xy 87.499092 -228.316338)
			(xy 87.524349 -228.246968) (xy 87.55665 -228.180586) (xy 87.595648 -228.117904) (xy 87.640926 -228.059595)
			(xy 87.666068 -228.032564) (xy 87.692817 -228.005374) (xy 87.751181 -227.956264) (xy 87.814463 -227.913677)
			(xy 87.881936 -227.878101) (xy 87.952826 -227.849946) (xy 88.026321 -227.829533) (xy 88.101578 -227.817097)
			(xy 88.177733 -227.812781) (xy 88.253912 -227.816634) (xy 88.329243 -227.828611) (xy 88.402861 -227.848576)
			(xy 88.473922 -227.8763) (xy 88.54161 -227.911464) (xy 88.605149 -227.953665) (xy 88.663811 -228.00242)
			(xy 88.716923 -228.057168) (xy 88.763875 -228.117282) (xy 88.804129 -228.182073) (xy 88.837223 -228.250797)
			(xy 88.85047 -228.286564) (xy 88.863932 -228.32441) (xy 88.929718 -228.370892) (xy 88.970104 -228.370892)
			(xy 88.986758 -228.370397) (xy 89.018931 -228.361775) (xy 89.047776 -228.34512) (xy 89.071327 -228.321566)
			(xy 89.08798 -228.29272) (xy 89.096598 -228.260546) (xy 89.097104 -228.243892) (xy 89.097104 -227.943156)
			(xy 89.043256 -227.840032) (xy 89.02065 -227.823014) (xy 88.991041 -227.800034) (xy 88.936322 -227.74881)
			(xy 88.887288 -227.69212) (xy 88.844481 -227.630593) (xy 88.808375 -227.564908) (xy 88.779371 -227.495793)
			(xy 88.757789 -227.424013) (xy 88.743868 -227.350363) (xy 88.737763 -227.275658) (xy 88.73954 -227.200725)
			(xy 88.74918 -227.126394) (xy 88.766577 -227.053487) (xy 88.791538 -226.982811) (xy 88.823786 -226.915149)
			(xy 88.862965 -226.85125) (xy 88.90864 -226.79182) (xy 88.960307 -226.737519) (xy 89.017393 -226.688946)
			(xy 89.079267 -226.646641) (xy 89.145243 -226.61107) (xy 89.214591 -226.582628) (xy 89.286543 -226.56163)
			(xy 89.360304 -226.548308) (xy 89.435056 -226.542809) (xy 89.509972 -226.545195) (xy 89.584222 -226.555438)
			(xy 89.656986 -226.573427) (xy 89.727457 -226.598961) (xy 89.794855 -226.631757) (xy 89.858434 -226.671454)
			(xy 89.91749 -226.71761) (xy 89.97137 -226.769716) (xy 90.019477 -226.827195) (xy 90.061279 -226.88941)
			(xy 90.096313 -226.955673) (xy 90.12419 -227.02525) (xy 90.144604 -227.09737) (xy 90.157326 -227.171237)
			(xy 90.162218 -227.246031) (xy 90.161857 -227.25507) (xy 91.277697 -227.25507) (xy 91.281732 -227.179366)
			(xy 91.293791 -227.104521) (xy 91.313737 -227.03138) (xy 91.341344 -226.960775) (xy 91.3763 -226.893504)
			(xy 91.418208 -226.830329) (xy 91.466594 -226.771967) (xy 91.52091 -226.719079) (xy 91.580539 -226.672264)
			(xy 91.644807 -226.632052) (xy 91.712984 -226.5989) (xy 91.7843 -226.573182) (xy 91.857945 -226.55519)
			(xy 91.933085 -226.545128) (xy 92.008869 -226.543109) (xy 92.084439 -226.549158) (xy 92.158937 -226.563205)
			(xy 92.23152 -226.585091) (xy 92.301366 -226.614568) (xy 92.367683 -226.651303) (xy 92.429719 -226.694878)
			(xy 92.486772 -226.7448) (xy 92.538196 -226.800504) (xy 92.583407 -226.861359) (xy 92.621894 -226.926674)
			(xy 92.65322 -226.99571) (xy 92.67703 -227.067685) (xy 92.693055 -227.141783) (xy 92.701114 -227.217164)
			(xy 92.701618 -227.25507) (xy 92.701114 -227.292976) (xy 92.693055 -227.368357) (xy 92.67703 -227.442455)
			(xy 92.65322 -227.51443) (xy 92.621894 -227.583466) (xy 92.583407 -227.648781) (xy 92.538196 -227.709636)
			(xy 92.486772 -227.76534) (xy 92.429719 -227.815262) (xy 92.367683 -227.858837) (xy 92.301366 -227.895572)
			(xy 92.23152 -227.925049) (xy 92.158937 -227.946935) (xy 92.084439 -227.960982) (xy 92.008869 -227.967031)
			(xy 91.933085 -227.965012) (xy 91.857945 -227.95495) (xy 91.7843 -227.936958) (xy 91.712984 -227.91124)
			(xy 91.644807 -227.878088) (xy 91.580539 -227.837876) (xy 91.52091 -227.791061) (xy 91.466594 -227.738173)
			(xy 91.418208 -227.679811) (xy 91.3763 -227.616636) (xy 91.341344 -227.549365) (xy 91.313737 -227.47876)
			(xy 91.293791 -227.405619) (xy 91.281732 -227.330774) (xy 91.277697 -227.25507) (xy 90.161857 -227.25507)
			(xy 90.159224 -227.320925) (xy 90.148377 -227.39509) (xy 90.129799 -227.467705) (xy 90.103693 -227.537966)
			(xy 90.070351 -227.605095) (xy 90.030139 -227.66835) (xy 89.983504 -227.72703) (xy 89.930962 -227.780485)
			(xy 89.873095 -227.828123) (xy 89.842086 -227.849176) (xy 89.829201 -227.858209) (xy 89.807954 -227.881407)
			(xy 89.793047 -227.909107) (xy 89.78539 -227.939618) (xy 89.784936 -227.955348) (xy 89.784936 -228.300026)
			(xy 89.785434 -228.316677) (xy 89.79406 -228.348842) (xy 89.810718 -228.377678) (xy 89.834271 -228.40122)
			(xy 89.863116 -228.417864) (xy 89.895285 -228.426474) (xy 89.911936 -228.427026) (xy 89.928467 -228.426495)
			(xy 89.96042 -228.417996) (xy 89.989118 -228.401577) (xy 90.012638 -228.378339) (xy 90.029402 -228.349841)
			(xy 90.034364 -228.334062) (xy 90.044995 -228.297756) (xy 90.072912 -228.22744) (xy 90.10813 -228.160483)
			(xy 90.150252 -228.097639) (xy 90.198804 -228.039619) (xy 90.253237 -227.987077) (xy 90.312937 -227.940606)
			(xy 90.377229 -227.90073) (xy 90.44539 -227.8679) (xy 90.516648 -227.842487) (xy 90.5902 -227.824776)
			(xy 90.665216 -227.814968) (xy 90.74085 -227.813173) (xy 90.816247 -227.819413) (xy 90.890556 -227.833616)
			(xy 90.96294 -227.855621) (xy 91.03258 -227.885182) (xy 91.098692 -227.921964) (xy 91.160528 -227.965551)
			(xy 91.217391 -228.015453) (xy 91.26864 -228.071105) (xy 91.313695 -228.13188) (xy 91.352049 -228.197093)
			(xy 91.383268 -228.266005) (xy 91.407001 -228.337841) (xy 91.422978 -228.411789) (xy 91.431021 -228.487015)
			(xy 91.431038 -228.56267) (xy 91.423028 -228.637899) (xy 91.407084 -228.711855) (xy 91.383383 -228.783701)
			(xy 91.352194 -228.852628) (xy 91.313869 -228.917857) (xy 91.268841 -228.978652) (xy 91.217617 -229.034327)
			(xy 91.160776 -229.084254) (xy 91.098958 -229.127869) (xy 91.032863 -229.16468) (xy 90.963236 -229.194271)
			(xy 90.890862 -229.216309) (xy 90.816559 -229.230544) (xy 90.741165 -229.236817) (xy 90.665531 -229.235056)
			(xy 90.59051 -229.225282) (xy 90.51695 -229.207603) (xy 90.445681 -229.182221) (xy 90.377506 -229.149421)
			(xy 90.313195 -229.109574) (xy 90.253475 -229.06313) (xy 90.199019 -229.010612) (xy 90.150441 -228.952613)
			(xy 90.108291 -228.889788) (xy 90.090244 -228.85654) (xy 90.079783 -228.837615) (xy 90.053447 -228.803323)
			(xy 90.021688 -228.773981) (xy 89.985423 -228.750436) (xy 89.945697 -228.733366) (xy 89.903655 -228.723264)
			(xy 89.86051 -228.720421) (xy 89.817507 -228.724918) (xy 89.775884 -228.736627) (xy 89.736842 -228.75521)
			(xy 89.701508 -228.780131) (xy 89.685876 -228.795072) (xy 89.635076 -228.845872) (xy 89.628181 -228.867528)
			(xy 89.621324 -228.912452) (xy 89.622574 -228.957878) (xy 89.63189 -229.002356) (xy 89.648975 -229.044466)
			(xy 89.673284 -229.082862) (xy 89.704038 -229.116317) (xy 89.740257 -229.143763) (xy 89.760298 -229.154482)
			(xy 89.792496 -229.170614) (xy 89.853784 -229.208438) (xy 89.910949 -229.252246) (xy 89.963407 -229.301592)
			(xy 89.987374 -229.328472) (xy 90.012351 -229.358024) (xy 90.056438 -229.421617) (xy 90.093367 -229.489617)
			(xy 90.122703 -229.56122) (xy 90.1441 -229.635583) (xy 90.157306 -229.711828) (xy 90.162164 -229.789056)
			(xy 90.161888 -229.79507) (xy 91.277697 -229.79507) (xy 91.281732 -229.719366) (xy 91.293791 -229.644521)
			(xy 91.313737 -229.57138) (xy 91.341344 -229.500775) (xy 91.3763 -229.433504) (xy 91.418208 -229.370329)
			(xy 91.466594 -229.311967) (xy 91.52091 -229.259079) (xy 91.580539 -229.212264) (xy 91.644807 -229.172052)
			(xy 91.712984 -229.1389) (xy 91.7843 -229.113182) (xy 91.857945 -229.09519) (xy 91.933085 -229.085128)
			(xy 92.008869 -229.083109) (xy 92.084439 -229.089158) (xy 92.158937 -229.103205) (xy 92.23152 -229.125091)
			(xy 92.301366 -229.154568) (xy 92.367683 -229.191303) (xy 92.429719 -229.234878) (xy 92.486772 -229.2848)
			(xy 92.538196 -229.340504) (xy 92.583407 -229.401359) (xy 92.621894 -229.466674) (xy 92.65322 -229.53571)
			(xy 92.67703 -229.607685) (xy 92.693055 -229.681783) (xy 92.701114 -229.757164) (xy 92.701618 -229.79507)
			(xy 92.701114 -229.832976) (xy 92.693055 -229.908357) (xy 92.67703 -229.982455) (xy 92.65322 -230.05443)
			(xy 92.621894 -230.123466) (xy 92.583407 -230.188781) (xy 92.538196 -230.249636) (xy 92.486772 -230.30534)
			(xy 92.429719 -230.355262) (xy 92.367683 -230.398837) (xy 92.301366 -230.435572) (xy 92.23152 -230.465049)
			(xy 92.158937 -230.486935) (xy 92.084439 -230.500982) (xy 92.008869 -230.507031) (xy 91.933085 -230.505012)
			(xy 91.857945 -230.49495) (xy 91.7843 -230.476958) (xy 91.712984 -230.45124) (xy 91.644807 -230.418088)
			(xy 91.580539 -230.377876) (xy 91.52091 -230.331061) (xy 91.466594 -230.278173) (xy 91.418208 -230.219811)
			(xy 91.3763 -230.156636) (xy 91.341344 -230.089365) (xy 91.313737 -230.01876) (xy 91.293791 -229.945619)
			(xy 91.281732 -229.870774) (xy 91.277697 -229.79507) (xy 90.161888 -229.79507) (xy 90.158617 -229.866355)
			(xy 90.146707 -229.942813) (xy 90.126575 -230.017528) (xy 90.098458 -230.089619) (xy 90.062688 -230.158236)
			(xy 90.019686 -230.222567) (xy 89.969961 -230.281856) (xy 89.914099 -230.335401) (xy 89.852759 -230.382572)
			(xy 89.819988 -230.403146) (xy 89.79154 -230.420418) (xy 89.759028 -230.47833) (xy 89.759028 -230.975154)
			(xy 89.759517 -230.991811) (xy 89.768131 -231.023993) (xy 89.784783 -231.052847) (xy 89.808339 -231.076406)
			(xy 89.83719 -231.093062) (xy 89.869371 -231.10168) (xy 89.886028 -231.102154) (xy 89.934796 -231.102154)
			(xy 90.007186 -231.03713) (xy 90.012266 -230.98887) (xy 90.01685 -230.950961) (xy 90.033102 -230.876346)
			(xy 90.057251 -230.8039) (xy 90.089019 -230.734456) (xy 90.128039 -230.668814) (xy 90.173865 -230.607727)
			(xy 90.225967 -230.551898) (xy 90.283749 -230.50197) (xy 90.346544 -230.458515) (xy 90.413631 -230.422034)
			(xy 90.484239 -230.392947) (xy 90.557556 -230.371588) (xy 90.632738 -230.358201) (xy 90.708921 -230.352943)
			(xy 90.78523 -230.355872) (xy 90.860786 -230.366955) (xy 90.934721 -230.386065) (xy 91.006184 -230.412981)
			(xy 91.074355 -230.447396) (xy 91.138448 -230.488912) (xy 91.164514 -230.51008) (xy 93.154506 -230.51008)
			(xy 93.158522 -230.39381) (xy 93.170549 -230.278095) (xy 93.190531 -230.163485) (xy 93.218373 -230.050526)
			(xy 93.253942 -229.939758) (xy 93.297068 -229.831707) (xy 93.347545 -229.726889) (xy 93.405134 -229.625804)
			(xy 93.46956 -229.528932) (xy 93.540515 -229.436736) (xy 93.617662 -229.349655) (xy 93.700633 -229.268104)
			(xy 93.789033 -229.192472) (xy 93.88244 -229.123118) (xy 93.980409 -229.060375) (xy 94.082473 -229.004539)
			(xy 94.188147 -228.955878) (xy 94.296926 -228.914624) (xy 94.408291 -228.880973) (xy 94.521714 -228.855085)
			(xy 94.636651 -228.837084) (xy 94.752557 -228.827055) (xy 94.868879 -228.825047) (xy 94.985062 -228.831069)
			(xy 95.100553 -228.845092) (xy 95.214801 -228.86705) (xy 95.327262 -228.896837) (xy 95.4374 -228.934312)
			(xy 95.54469 -228.979297) (xy 95.648621 -229.031576) (xy 95.748697 -229.090901) (xy 95.844443 -229.156989)
			(xy 95.9354 -229.229525) (xy 96.021136 -229.308164) (xy 96.101243 -229.39253) (xy 96.175339 -229.482222)
			(xy 96.243069 -229.576812) (xy 96.304113 -229.67585) (xy 96.358178 -229.778863) (xy 96.405008 -229.88536)
			(xy 96.444379 -229.994835) (xy 96.476103 -230.106765) (xy 96.500029 -230.220617) (xy 96.516043 -230.335849)
			(xy 96.52407 -230.451911) (xy 96.524572 -230.51008) (xy 96.52407 -230.568249) (xy 96.516043 -230.684311)
			(xy 96.500029 -230.799543) (xy 96.476103 -230.913395) (xy 96.444379 -231.025325) (xy 96.405008 -231.1348)
			(xy 96.358178 -231.241297) (xy 96.304113 -231.34431) (xy 96.243069 -231.443348) (xy 96.175339 -231.537938)
			(xy 96.101243 -231.62763) (xy 96.021136 -231.711996) (xy 95.9354 -231.790635) (xy 95.844443 -231.863171)
			(xy 95.748697 -231.929259) (xy 95.648621 -231.988584) (xy 95.54469 -232.040863) (xy 95.4374 -232.085848)
			(xy 95.327262 -232.123323) (xy 95.214801 -232.15311) (xy 95.100553 -232.175068) (xy 94.985062 -232.189091)
			(xy 94.868879 -232.195113) (xy 94.752557 -232.193105) (xy 94.636651 -232.183076) (xy 94.521714 -232.165075)
			(xy 94.408291 -232.139187) (xy 94.296926 -232.105536) (xy 94.188147 -232.064282) (xy 94.082473 -232.015621)
			(xy 93.980409 -231.959785) (xy 93.88244 -231.897042) (xy 93.789033 -231.827688) (xy 93.700633 -231.752056)
			(xy 93.617662 -231.670505) (xy 93.540515 -231.583424) (xy 93.46956 -231.491228) (xy 93.405134 -231.394356)
			(xy 93.347545 -231.293271) (xy 93.297068 -231.188453) (xy 93.253942 -231.080402) (xy 93.218373 -230.969634)
			(xy 93.190531 -230.856675) (xy 93.170549 -230.742065) (xy 93.158522 -230.62635) (xy 93.154506 -230.51008)
			(xy 91.164514 -230.51008) (xy 91.197728 -230.537052) (xy 91.251512 -230.591263) (xy 91.299181 -230.650921)
			(xy 91.340189 -230.715341) (xy 91.374063 -230.783782) (xy 91.400414 -230.855456) (xy 91.418938 -230.92954)
			(xy 91.42476 -230.96728) (xy 91.429483 -231.0049) (xy 91.43185 -231.080689) (xy 91.426147 -231.156299)
			(xy 91.412438 -231.230875) (xy 91.390878 -231.303571) (xy 91.361712 -231.373562) (xy 91.325271 -231.440056)
			(xy 91.281966 -231.5023) (xy 91.23229 -231.559586) (xy 91.176805 -231.611267) (xy 91.116141 -231.656756)
			(xy 91.050984 -231.695539) (xy 90.982073 -231.727174) (xy 90.91019 -231.751304) (xy 90.836149 -231.767656)
			(xy 90.760789 -231.776043) (xy 90.684964 -231.776371) (xy 90.609534 -231.768636) (xy 90.535355 -231.752926)
			(xy 90.463265 -231.729418) (xy 90.394083 -231.69838) (xy 90.328593 -231.660163) (xy 90.297762 -231.638094)
			(xy 90.270853 -231.617739) (xy 90.2206 -231.572707) (xy 90.197432 -231.548178) (xy 90.181023 -231.53162)
			(xy 90.143335 -231.504194) (xy 90.101279 -231.484098) (xy 90.056264 -231.472006) (xy 90.009798 -231.468323)
			(xy 89.96344 -231.473173) (xy 89.918744 -231.486393) (xy 89.877206 -231.507541) (xy 89.84022 -231.535906)
			(xy 89.809025 -231.570539) (xy 89.784667 -231.610279) (xy 89.767961 -231.653794) (xy 89.759469 -231.699624)
			(xy 89.759028 -231.72293) (xy 89.759028 -232.24744) (xy 86.636352 -235.370116) (xy 86.631979 -235.390424)
			(xy 86.619377 -235.430011) (xy 86.611206 -235.44911) (xy 86.595966 -235.479336) (xy 86.579964 -235.508038)
			(xy 86.579964 -237.16615) (xy 86.906606 -237.16615) (xy 86.910677 -237.110528) (xy 86.922803 -237.056091)
			(xy 86.942726 -237.004) (xy 86.970022 -236.955365) (xy 87.004108 -236.911222) (xy 87.044257 -236.872513)
			(xy 87.089615 -236.840062) (xy 87.139215 -236.814561) (xy 87.191999 -236.796554) (xy 87.246842 -236.786424)
			(xy 87.302576 -236.784387) (xy 87.358013 -236.790487) (xy 87.41197 -236.804593) (xy 87.463299 -236.826405)
			(xy 87.510905 -236.855459) (xy 87.553773 -236.891134) (xy 87.59099 -236.932671) (xy 87.621763 -236.979184)
			(xy 87.645435 -237.029681) (xy 87.661503 -237.083088) (xy 87.669623 -237.138264) (xy 87.670132 -237.16615)
			(xy 87.669623 -237.194036) (xy 87.661503 -237.249212) (xy 87.645435 -237.302619) (xy 87.621763 -237.353116)
			(xy 87.59099 -237.399629) (xy 87.553773 -237.441166) (xy 87.510905 -237.476841) (xy 87.463299 -237.505895)
			(xy 87.41197 -237.527707) (xy 87.358013 -237.541813) (xy 87.302576 -237.547913) (xy 87.246842 -237.545876)
			(xy 87.191999 -237.535746) (xy 87.139215 -237.517739) (xy 87.089615 -237.492238) (xy 87.044257 -237.459787)
			(xy 87.004108 -237.421078) (xy 86.970022 -237.376935) (xy 86.942726 -237.3283) (xy 86.922803 -237.276209)
			(xy 86.910677 -237.221772) (xy 86.906606 -237.16615) (xy 86.579964 -237.16615) (xy 86.579964 -238.826548)
			(xy 85.617304 -239.789208) (xy 85.617304 -242.26012) (xy 86.877404 -242.26012) (xy 86.881424 -242.069469)
			(xy 86.893478 -241.879156) (xy 86.913544 -241.689521) (xy 86.941587 -241.5009) (xy 86.977556 -241.31363)
			(xy 87.021388 -241.128042) (xy 87.073005 -240.944467) (xy 87.132315 -240.763231) (xy 87.199213 -240.584656)
			(xy 87.273579 -240.409061) (xy 87.355281 -240.236756) (xy 87.444175 -240.068049) (xy 87.540101 -239.903239)
			(xy 87.64289 -239.74262) (xy 87.752359 -239.586477) (xy 87.868313 -239.435088) (xy 87.990547 -239.288721)
			(xy 88.118841 -239.147637) (xy 88.252969 -239.012088) (xy 88.392693 -238.882313) (xy 88.537763 -238.758543)
			(xy 88.687921 -238.641) (xy 88.842902 -238.529891) (xy 89.002429 -238.425414) (xy 89.166218 -238.327755)
			(xy 89.333978 -238.237088) (xy 89.505412 -238.153574) (xy 89.680214 -238.077361) (xy 89.858073 -238.008585)
			(xy 90.038674 -237.947367) (xy 90.221694 -237.893818) (xy 90.40681 -237.848032) (xy 90.593691 -237.81009)
			(xy 90.782006 -237.780061) (xy 90.971419 -237.757996) (xy 91.161593 -237.743937) (xy 91.352192 -237.737907)
			(xy 91.542875 -237.739917) (xy 91.733304 -237.749964) (xy 91.92314 -237.76803) (xy 92.112046 -237.794083)
			(xy 92.299685 -237.828076) (xy 92.485725 -237.869949) (xy 92.669834 -237.919628) (xy 92.851685 -237.977024)
			(xy 93.030955 -238.042035) (xy 93.207325 -238.114546) (xy 93.380481 -238.194427) (xy 93.550116 -238.281537)
			(xy 93.715928 -238.375721) (xy 93.877622 -238.476812) (xy 94.03491 -238.584628) (xy 94.187513 -238.69898)
			(xy 94.335161 -238.819663) (xy 94.477589 -238.946464) (xy 94.614545 -239.079155) (xy 94.745786 -239.217503)
			(xy 94.871078 -239.36126) (xy 94.990198 -239.510171) (xy 95.102934 -239.663972) (xy 95.209087 -239.822388)
			(xy 95.308467 -239.985139) (xy 95.400897 -240.151934) (xy 95.486214 -240.322478) (xy 95.564266 -240.496466)
			(xy 95.634913 -240.673591) (xy 95.698031 -240.853536) (xy 95.753507 -241.035982) (xy 95.801242 -241.220605)
			(xy 95.841152 -241.407075) (xy 95.873165 -241.595063) (xy 95.897225 -241.784233) (xy 95.913288 -241.974249)
			(xy 95.921327 -242.164773) (xy 95.92183 -242.26012) (xy 95.921327 -242.355467) (xy 95.913288 -242.545991)
			(xy 95.897225 -242.736007) (xy 95.873165 -242.925177) (xy 95.841152 -243.113165) (xy 95.801242 -243.299635)
			(xy 95.753507 -243.484258) (xy 95.698031 -243.666704) (xy 95.634913 -243.846649) (xy 95.564266 -244.023774)
			(xy 95.486214 -244.197762) (xy 95.400897 -244.368306) (xy 95.308467 -244.535101) (xy 95.209087 -244.697852)
			(xy 95.102934 -244.856268) (xy 94.990198 -245.010069) (xy 94.871078 -245.15898) (xy 94.745786 -245.302737)
			(xy 94.614545 -245.441085) (xy 94.477589 -245.573776) (xy 94.335161 -245.700577) (xy 94.187513 -245.82126)
			(xy 94.03491 -245.935612) (xy 93.877622 -246.043428) (xy 93.715928 -246.144519) (xy 93.550116 -246.238703)
			(xy 93.380481 -246.325813) (xy 93.207325 -246.405694) (xy 93.030955 -246.478205) (xy 92.851685 -246.543216)
			(xy 92.669834 -246.600612) (xy 92.485725 -246.650291) (xy 92.299685 -246.692164) (xy 92.112046 -246.726157)
			(xy 91.92314 -246.75221) (xy 91.733304 -246.770276) (xy 91.542875 -246.780323) (xy 91.352192 -246.782333)
			(xy 91.161593 -246.776303) (xy 90.971419 -246.762244) (xy 90.782006 -246.740179) (xy 90.593691 -246.71015)
			(xy 90.40681 -246.672208) (xy 90.221694 -246.626422) (xy 90.038674 -246.572873) (xy 89.858073 -246.511655)
			(xy 89.680214 -246.442879) (xy 89.505412 -246.366666) (xy 89.333978 -246.283152) (xy 89.166218 -246.192485)
			(xy 89.002429 -246.094826) (xy 88.842902 -245.990349) (xy 88.687921 -245.87924) (xy 88.537763 -245.761697)
			(xy 88.392693 -245.637927) (xy 88.252969 -245.508152) (xy 88.118841 -245.372603) (xy 87.990547 -245.231519)
			(xy 87.868313 -245.085152) (xy 87.752359 -244.933763) (xy 87.64289 -244.77762) (xy 87.540101 -244.617001)
			(xy 87.444175 -244.452191) (xy 87.355281 -244.283484) (xy 87.273579 -244.111179) (xy 87.199213 -243.935584)
			(xy 87.132315 -243.757009) (xy 87.073005 -243.575773) (xy 87.021388 -243.392198) (xy 86.977556 -243.20661)
			(xy 86.941587 -243.01934) (xy 86.913544 -242.830719) (xy 86.893478 -242.641084) (xy 86.881424 -242.450771)
			(xy 86.877404 -242.26012) (xy 85.617304 -242.26012) (xy 85.617304 -246.198136) (xy 69.900503 -261.915148)
			(xy 71.023478 -261.915148) (xy 71.027549 -261.859526) (xy 71.039675 -261.805089) (xy 71.059598 -261.752998)
			(xy 71.086894 -261.704363) (xy 71.12098 -261.66022) (xy 71.161129 -261.621511) (xy 71.206487 -261.58906)
			(xy 71.256087 -261.563559) (xy 71.308871 -261.545552) (xy 71.363714 -261.535422) (xy 71.419448 -261.533385)
			(xy 71.474885 -261.539485) (xy 71.528842 -261.553591) (xy 71.580171 -261.575403) (xy 71.627777 -261.604457)
			(xy 71.670645 -261.640132) (xy 71.707862 -261.681669) (xy 71.738635 -261.728182) (xy 71.762307 -261.778679)
			(xy 71.778375 -261.832086) (xy 71.786495 -261.887262) (xy 71.787004 -261.915148) (xy 72.177146 -261.915148)
			(xy 72.181217 -261.859526) (xy 72.193343 -261.805089) (xy 72.213266 -261.752998) (xy 72.240562 -261.704363)
			(xy 72.274648 -261.66022) (xy 72.314797 -261.621511) (xy 72.360155 -261.58906) (xy 72.409755 -261.563559)
			(xy 72.462539 -261.545552) (xy 72.517382 -261.535422) (xy 72.573116 -261.533385) (xy 72.628553 -261.539485)
			(xy 72.68251 -261.553591) (xy 72.733839 -261.575403) (xy 72.781445 -261.604457) (xy 72.824313 -261.640132)
			(xy 72.86153 -261.681669) (xy 72.892303 -261.728182) (xy 72.915975 -261.778679) (xy 72.932043 -261.832086)
			(xy 72.940163 -261.887262) (xy 72.940672 -261.915148) (xy 73.30516 -261.915148) (xy 73.309231 -261.859526)
			(xy 73.321357 -261.805089) (xy 73.34128 -261.752998) (xy 73.368576 -261.704363) (xy 73.402662 -261.66022)
			(xy 73.442811 -261.621511) (xy 73.488169 -261.58906) (xy 73.537769 -261.563559) (xy 73.590553 -261.545552)
			(xy 73.645396 -261.535422) (xy 73.70113 -261.533385) (xy 73.756567 -261.539485) (xy 73.810524 -261.553591)
			(xy 73.861853 -261.575403) (xy 73.909459 -261.604457) (xy 73.952327 -261.640132) (xy 73.989544 -261.681669)
			(xy 74.020317 -261.728182) (xy 74.043989 -261.778679) (xy 74.060057 -261.832086) (xy 74.068177 -261.887262)
			(xy 74.068686 -261.915148) (xy 74.4507 -261.915148) (xy 74.454771 -261.859526) (xy 74.466897 -261.805089)
			(xy 74.48682 -261.752998) (xy 74.514116 -261.704363) (xy 74.548202 -261.66022) (xy 74.588351 -261.621511)
			(xy 74.633709 -261.58906) (xy 74.683309 -261.563559) (xy 74.736093 -261.545552) (xy 74.790936 -261.535422)
			(xy 74.84667 -261.533385) (xy 74.902107 -261.539485) (xy 74.956064 -261.553591) (xy 75.007393 -261.575403)
			(xy 75.054999 -261.604457) (xy 75.097867 -261.640132) (xy 75.135084 -261.681669) (xy 75.165857 -261.728182)
			(xy 75.189529 -261.778679) (xy 75.205597 -261.832086) (xy 75.213717 -261.887262) (xy 75.214226 -261.915148)
			(xy 75.213717 -261.943034) (xy 75.205597 -261.99821) (xy 75.189529 -262.051617) (xy 75.165857 -262.102114)
			(xy 75.135084 -262.148627) (xy 75.097867 -262.190164) (xy 75.054999 -262.225839) (xy 75.007393 -262.254893)
			(xy 74.956064 -262.276705) (xy 74.902107 -262.290811) (xy 74.84667 -262.296911) (xy 74.790936 -262.294874)
			(xy 74.736093 -262.284744) (xy 74.683309 -262.266737) (xy 74.633709 -262.241236) (xy 74.588351 -262.208785)
			(xy 74.548202 -262.170076) (xy 74.514116 -262.125933) (xy 74.48682 -262.077298) (xy 74.466897 -262.025207)
			(xy 74.454771 -261.97077) (xy 74.4507 -261.915148) (xy 74.068686 -261.915148) (xy 74.068177 -261.943034)
			(xy 74.060057 -261.99821) (xy 74.043989 -262.051617) (xy 74.020317 -262.102114) (xy 73.989544 -262.148627)
			(xy 73.952327 -262.190164) (xy 73.909459 -262.225839) (xy 73.861853 -262.254893) (xy 73.810524 -262.276705)
			(xy 73.756567 -262.290811) (xy 73.70113 -262.296911) (xy 73.645396 -262.294874) (xy 73.590553 -262.284744)
			(xy 73.537769 -262.266737) (xy 73.488169 -262.241236) (xy 73.442811 -262.208785) (xy 73.402662 -262.170076)
			(xy 73.368576 -262.125933) (xy 73.34128 -262.077298) (xy 73.321357 -262.025207) (xy 73.309231 -261.97077)
			(xy 73.30516 -261.915148) (xy 72.940672 -261.915148) (xy 72.940163 -261.943034) (xy 72.932043 -261.99821)
			(xy 72.915975 -262.051617) (xy 72.892303 -262.102114) (xy 72.86153 -262.148627) (xy 72.824313 -262.190164)
			(xy 72.781445 -262.225839) (xy 72.733839 -262.254893) (xy 72.68251 -262.276705) (xy 72.628553 -262.290811)
			(xy 72.573116 -262.296911) (xy 72.517382 -262.294874) (xy 72.462539 -262.284744) (xy 72.409755 -262.266737)
			(xy 72.360155 -262.241236) (xy 72.314797 -262.208785) (xy 72.274648 -262.170076) (xy 72.240562 -262.125933)
			(xy 72.213266 -262.077298) (xy 72.193343 -262.025207) (xy 72.181217 -261.97077) (xy 72.177146 -261.915148)
			(xy 71.787004 -261.915148) (xy 71.786495 -261.943034) (xy 71.778375 -261.99821) (xy 71.762307 -262.051617)
			(xy 71.738635 -262.102114) (xy 71.707862 -262.148627) (xy 71.670645 -262.190164) (xy 71.627777 -262.225839)
			(xy 71.580171 -262.254893) (xy 71.528842 -262.276705) (xy 71.474885 -262.290811) (xy 71.419448 -262.296911)
			(xy 71.363714 -262.294874) (xy 71.308871 -262.284744) (xy 71.256087 -262.266737) (xy 71.206487 -262.241236)
			(xy 71.161129 -262.208785) (xy 71.12098 -262.170076) (xy 71.086894 -262.125933) (xy 71.059598 -262.077298)
			(xy 71.039675 -262.025207) (xy 71.027549 -261.97077) (xy 71.023478 -261.915148) (xy 69.900503 -261.915148)
			(xy 66.669666 -265.146028) (xy 66.654747 -265.162731) (xy 66.630427 -265.200334) (xy 66.613069 -265.241616)
			(xy 66.603212 -265.285299) (xy 66.601158 -265.330034) (xy 66.606972 -265.374437) (xy 66.620474 -265.417136)
			(xy 66.641247 -265.456809) (xy 66.668647 -265.49223) (xy 66.701829 -265.522303) (xy 66.739765 -265.5461)
			(xy 66.781283 -265.562884) (xy 66.825099 -265.572135) (xy 66.847466 -265.573256) (xy 87.647018 -265.573256)
			(xy 87.850472 -265.776456) (xy 87.881968 -265.7856) (xy 87.908368 -265.793677) (xy 87.958691 -265.816382)
			(xy 88.005216 -265.846102) (xy 88.046973 -265.882217) (xy 88.083089 -265.923972) (xy 88.112811 -265.970496)
			(xy 88.135518 -266.020818) (xy 88.143588 -266.04722) (xy 88.152732 -266.078716) (xy 93.178884 -271.105122)
			(xy 93.178884 -272.326862) (xy 92.212922 -273.292824) (xy 92.140786 -273.292824) (xy 92.124134 -273.29332)
			(xy 92.091965 -273.301944) (xy 92.063124 -273.318601) (xy 92.039577 -273.342154) (xy 92.02293 -273.371)
			(xy 92.014315 -273.403171) (xy 92.013786 -273.419824) (xy 92.013786 -273.466052) (xy 92.07246 -273.53641)
			(xy 92.117926 -273.544792) (xy 92.154139 -273.551894) (xy 92.224968 -273.572617) (xy 92.293274 -273.600557)
			(xy 92.358322 -273.635414) (xy 92.419414 -273.676814) (xy 92.475895 -273.724313) (xy 92.527159 -273.777401)
			(xy 92.572654 -273.835508) (xy 92.611894 -273.89801) (xy 92.644456 -273.964237) (xy 92.657676 -273.99869)
			(xy 92.670149 -274.033924) (xy 92.688497 -274.106385) (xy 92.699152 -274.180369) (xy 92.701998 -274.255063)
			(xy 92.697002 -274.329643) (xy 92.68422 -274.40329) (xy 92.663792 -274.475192) (xy 92.635944 -274.544558)
			(xy 92.600982 -274.610625) (xy 92.55929 -274.672666) (xy 92.511328 -274.729997) (xy 92.457623 -274.781987)
			(xy 92.398767 -274.828065) (xy 92.367354 -274.84832) (xy 92.35396 -274.857253) (xy 92.331812 -274.880607)
			(xy 92.316216 -274.908761) (xy 92.308163 -274.939923) (xy 92.307664 -274.956016) (xy 92.307664 -274.96008)
			(xy 93.154506 -274.96008) (xy 93.158522 -274.84381) (xy 93.170549 -274.728095) (xy 93.190531 -274.613485)
			(xy 93.218373 -274.500526) (xy 93.253942 -274.389758) (xy 93.297068 -274.281707) (xy 93.347545 -274.176889)
			(xy 93.405134 -274.075804) (xy 93.46956 -273.978932) (xy 93.540515 -273.886736) (xy 93.617662 -273.799655)
			(xy 93.700633 -273.718104) (xy 93.789033 -273.642472) (xy 93.88244 -273.573118) (xy 93.980409 -273.510375)
			(xy 94.082473 -273.454539) (xy 94.188147 -273.405878) (xy 94.296926 -273.364624) (xy 94.408291 -273.330973)
			(xy 94.521714 -273.305085) (xy 94.636651 -273.287084) (xy 94.752557 -273.277055) (xy 94.868879 -273.275047)
			(xy 94.985062 -273.281069) (xy 95.100553 -273.295092) (xy 95.214801 -273.31705) (xy 95.327262 -273.346837)
			(xy 95.4374 -273.384312) (xy 95.54469 -273.429297) (xy 95.648621 -273.481576) (xy 95.748697 -273.540901)
			(xy 95.844443 -273.606989) (xy 95.9354 -273.679525) (xy 96.021136 -273.758164) (xy 96.101243 -273.84253)
			(xy 96.175339 -273.932222) (xy 96.243069 -274.026812) (xy 96.304113 -274.12585) (xy 96.358178 -274.228863)
			(xy 96.405008 -274.33536) (xy 96.444379 -274.444835) (xy 96.476103 -274.556765) (xy 96.500029 -274.670617)
			(xy 96.516043 -274.785849) (xy 96.52407 -274.901911) (xy 96.524572 -274.96008) (xy 96.52407 -275.018249)
			(xy 96.516043 -275.134311) (xy 96.500029 -275.249543) (xy 96.476103 -275.363395) (xy 96.444379 -275.475325)
			(xy 96.405008 -275.5848) (xy 96.358178 -275.691297) (xy 96.304113 -275.79431) (xy 96.243069 -275.893348)
			(xy 96.175339 -275.987938) (xy 96.101243 -276.07763) (xy 96.021136 -276.161996) (xy 95.9354 -276.240635)
			(xy 95.844443 -276.313171) (xy 95.748697 -276.379259) (xy 95.648621 -276.438584) (xy 95.54469 -276.490863)
			(xy 95.4374 -276.535848) (xy 95.327262 -276.573323) (xy 95.214801 -276.60311) (xy 95.100553 -276.625068)
			(xy 94.985062 -276.639091) (xy 94.868879 -276.645113) (xy 94.752557 -276.643105) (xy 94.636651 -276.633076)
			(xy 94.521714 -276.615075) (xy 94.408291 -276.589187) (xy 94.296926 -276.555536) (xy 94.188147 -276.514282)
			(xy 94.082473 -276.465621) (xy 93.980409 -276.409785) (xy 93.88244 -276.347042) (xy 93.789033 -276.277688)
			(xy 93.700633 -276.202056) (xy 93.617662 -276.120505) (xy 93.540515 -276.033424) (xy 93.46956 -275.941228)
			(xy 93.405134 -275.844356) (xy 93.347545 -275.743271) (xy 93.297068 -275.638453) (xy 93.253942 -275.530402)
			(xy 93.218373 -275.419634) (xy 93.190531 -275.306675) (xy 93.170549 -275.192065) (xy 93.158522 -275.07635)
			(xy 93.154506 -274.96008) (xy 92.307664 -274.96008) (xy 92.307664 -275.66112) (xy 89.932256 -278.036528)
			(xy 85.01126 -278.036528) (xy 83.981036 -277.006558) (xy 83.851496 -276.877018) (xy 83.851496 -272.469356)
			(xy 79.790544 -268.408404) (xy 22.315932 -268.408404) (xy 21.397722 -269.326614) (xy 21.388578 -269.35811)
			(xy 21.380504 -269.384512) (xy 21.357803 -269.43484) (xy 21.328086 -269.48137) (xy 21.291973 -269.523131)
			(xy 21.250217 -269.559251) (xy 21.203692 -269.588975) (xy 21.153368 -269.611683) (xy 21.126958 -269.61973)
			(xy 21.095462 -269.628874) (xy 20.890969 -269.83336) (xy 29.519874 -269.83336) (xy 29.519874 -269.74646)
			(xy 29.527892 -269.659931) (xy 29.54386 -269.574511) (xy 29.567641 -269.490929) (xy 29.599033 -269.409897)
			(xy 29.637767 -269.332108) (xy 29.683514 -269.258224) (xy 29.735883 -269.188877) (xy 29.794427 -269.124657)
			(xy 29.858647 -269.066113) (xy 29.927994 -269.013744) (xy 30.001878 -268.967997) (xy 30.079667 -268.929263)
			(xy 30.160699 -268.897871) (xy 30.244281 -268.87409) (xy 30.329701 -268.858122) (xy 30.41623 -268.850104)
			(xy 30.50313 -268.850104) (xy 30.589659 -268.858122) (xy 30.675079 -268.87409) (xy 30.758661 -268.897871)
			(xy 30.839693 -268.929263) (xy 30.917482 -268.967997) (xy 30.991366 -269.013744) (xy 31.060713 -269.066113)
			(xy 31.124933 -269.124657) (xy 31.183477 -269.188877) (xy 31.235846 -269.258224) (xy 31.281593 -269.332108)
			(xy 31.320327 -269.409897) (xy 31.351719 -269.490929) (xy 31.3755 -269.574511) (xy 31.391468 -269.659931)
			(xy 31.399486 -269.74646) (xy 31.399988 -269.78991) (xy 31.399486 -269.83336) (xy 34.599874 -269.83336)
			(xy 34.599874 -269.74646) (xy 34.607892 -269.659931) (xy 34.62386 -269.574511) (xy 34.647641 -269.490929)
			(xy 34.679033 -269.409897) (xy 34.717767 -269.332108) (xy 34.763514 -269.258224) (xy 34.815883 -269.188877)
			(xy 34.874427 -269.124657) (xy 34.938647 -269.066113) (xy 35.007994 -269.013744) (xy 35.081878 -268.967997)
			(xy 35.159667 -268.929263) (xy 35.240699 -268.897871) (xy 35.324281 -268.87409) (xy 35.409701 -268.858122)
			(xy 35.49623 -268.850104) (xy 35.58313 -268.850104) (xy 35.669659 -268.858122) (xy 35.755079 -268.87409)
			(xy 35.838661 -268.897871) (xy 35.919693 -268.929263) (xy 35.997482 -268.967997) (xy 36.071366 -269.013744)
			(xy 36.140713 -269.066113) (xy 36.204933 -269.124657) (xy 36.263477 -269.188877) (xy 36.315846 -269.258224)
			(xy 36.361593 -269.332108) (xy 36.400327 -269.409897) (xy 36.431719 -269.490929) (xy 36.4555 -269.574511)
			(xy 36.471468 -269.659931) (xy 36.479486 -269.74646) (xy 36.479988 -269.78991) (xy 36.479486 -269.83336)
			(xy 36.471468 -269.919889) (xy 36.4555 -270.005309) (xy 36.431719 -270.088891) (xy 36.400327 -270.169923)
			(xy 36.361593 -270.247712) (xy 36.315846 -270.321596) (xy 36.263477 -270.390943) (xy 36.204933 -270.455163)
			(xy 36.140713 -270.513707) (xy 36.071366 -270.566076) (xy 35.997482 -270.611823) (xy 35.919693 -270.650557)
			(xy 35.838661 -270.681949) (xy 35.755079 -270.70573) (xy 35.669659 -270.721698) (xy 35.58313 -270.729716)
			(xy 35.49623 -270.729716) (xy 35.409701 -270.721698) (xy 35.324281 -270.70573) (xy 35.240699 -270.681949)
			(xy 35.159667 -270.650557) (xy 35.081878 -270.611823) (xy 35.007994 -270.566076) (xy 34.938647 -270.513707)
			(xy 34.874427 -270.455163) (xy 34.815883 -270.390943) (xy 34.763514 -270.321596) (xy 34.717767 -270.247712)
			(xy 34.679033 -270.169923) (xy 34.647641 -270.088891) (xy 34.62386 -270.005309) (xy 34.607892 -269.919889)
			(xy 34.599874 -269.83336) (xy 31.399486 -269.83336) (xy 31.391468 -269.919889) (xy 31.3755 -270.005309)
			(xy 31.351719 -270.088891) (xy 31.320327 -270.169923) (xy 31.281593 -270.247712) (xy 31.235846 -270.321596)
			(xy 31.183477 -270.390943) (xy 31.124933 -270.455163) (xy 31.060713 -270.513707) (xy 30.991366 -270.566076)
			(xy 30.917482 -270.611823) (xy 30.839693 -270.650557) (xy 30.758661 -270.681949) (xy 30.675079 -270.70573)
			(xy 30.589659 -270.721698) (xy 30.50313 -270.729716) (xy 30.41623 -270.729716) (xy 30.329701 -270.721698)
			(xy 30.244281 -270.70573) (xy 30.160699 -270.681949) (xy 30.079667 -270.650557) (xy 30.001878 -270.611823)
			(xy 29.927994 -270.566076) (xy 29.858647 -270.513707) (xy 29.794427 -270.455163) (xy 29.735883 -270.390943)
			(xy 29.683514 -270.321596) (xy 29.637767 -270.247712) (xy 29.599033 -270.169923) (xy 29.567641 -270.088891)
			(xy 29.54386 -270.005309) (xy 29.527892 -269.919889) (xy 29.519874 -269.83336) (xy 20.890969 -269.83336)
			(xy 19.575476 -271.14881) (xy 24.231598 -271.14881) (xy 24.235669 -271.093188) (xy 24.247795 -271.038751)
			(xy 24.267718 -270.98666) (xy 24.295014 -270.938025) (xy 24.3291 -270.893882) (xy 24.369249 -270.855173)
			(xy 24.414607 -270.822722) (xy 24.464207 -270.797221) (xy 24.516991 -270.779214) (xy 24.571834 -270.769084)
			(xy 24.627568 -270.767047) (xy 24.683005 -270.773147) (xy 24.736962 -270.787253) (xy 24.788291 -270.809065)
			(xy 24.835897 -270.838119) (xy 24.878765 -270.873794) (xy 24.915982 -270.915331) (xy 24.946755 -270.961844)
			(xy 24.970427 -271.012341) (xy 24.986495 -271.065748) (xy 24.994615 -271.120924) (xy 24.995124 -271.14881)
			(xy 24.994615 -271.176696) (xy 24.986495 -271.231872) (xy 24.970427 -271.285279) (xy 24.946755 -271.335776)
			(xy 24.915982 -271.382289) (xy 24.878765 -271.423826) (xy 24.835897 -271.459501) (xy 24.788291 -271.488555)
			(xy 24.736962 -271.510367) (xy 24.683005 -271.524473) (xy 24.627568 -271.530573) (xy 24.571834 -271.528536)
			(xy 24.516991 -271.518406) (xy 24.464207 -271.500399) (xy 24.414607 -271.474898) (xy 24.369249 -271.442447)
			(xy 24.3291 -271.403738) (xy 24.295014 -271.359595) (xy 24.267718 -271.31096) (xy 24.247795 -271.258869)
			(xy 24.235669 -271.204432) (xy 24.231598 -271.14881) (xy 19.575476 -271.14881) (xy 18.378842 -272.345404)
			(xy 24.198578 -272.345404) (xy 24.202649 -272.289782) (xy 24.214775 -272.235345) (xy 24.234698 -272.183254)
			(xy 24.261994 -272.134619) (xy 24.29608 -272.090476) (xy 24.336229 -272.051767) (xy 24.381587 -272.019316)
			(xy 24.431187 -271.993815) (xy 24.483971 -271.975808) (xy 24.538814 -271.965678) (xy 24.594548 -271.963641)
			(xy 24.649985 -271.969741) (xy 24.703942 -271.983847) (xy 24.755271 -272.005659) (xy 24.802877 -272.034713)
			(xy 24.845745 -272.070388) (xy 24.882962 -272.111925) (xy 24.913735 -272.158438) (xy 24.937407 -272.208935)
			(xy 24.953475 -272.262342) (xy 24.961595 -272.317518) (xy 24.962021 -272.340832) (xy 26.850592 -272.340832)
			(xy 26.854663 -272.28521) (xy 26.866789 -272.230773) (xy 26.886712 -272.178682) (xy 26.914008 -272.130047)
			(xy 26.948094 -272.085904) (xy 26.988243 -272.047195) (xy 27.033601 -272.014744) (xy 27.083201 -271.989243)
			(xy 27.135985 -271.971236) (xy 27.190828 -271.961106) (xy 27.246562 -271.959069) (xy 27.301999 -271.965169)
			(xy 27.355956 -271.979275) (xy 27.407285 -272.001087) (xy 27.454891 -272.030141) (xy 27.497759 -272.065816)
			(xy 27.534976 -272.107353) (xy 27.565749 -272.153866) (xy 27.589421 -272.204363) (xy 27.605489 -272.25777)
			(xy 27.613609 -272.312946) (xy 27.614118 -272.340832) (xy 27.613609 -272.368718) (xy 27.612926 -272.37336)
			(xy 29.519874 -272.37336) (xy 29.519874 -272.28646) (xy 29.527892 -272.199931) (xy 29.54386 -272.114511)
			(xy 29.567641 -272.030929) (xy 29.599033 -271.949897) (xy 29.637767 -271.872108) (xy 29.683514 -271.798224)
			(xy 29.735883 -271.728877) (xy 29.794427 -271.664657) (xy 29.858647 -271.606113) (xy 29.927994 -271.553744)
			(xy 30.001878 -271.507997) (xy 30.079667 -271.469263) (xy 30.160699 -271.437871) (xy 30.244281 -271.41409)
			(xy 30.329701 -271.398122) (xy 30.41623 -271.390104) (xy 30.50313 -271.390104) (xy 30.589659 -271.398122)
			(xy 30.675079 -271.41409) (xy 30.758661 -271.437871) (xy 30.839693 -271.469263) (xy 30.917482 -271.507997)
			(xy 30.991366 -271.553744) (xy 31.060713 -271.606113) (xy 31.124933 -271.664657) (xy 31.183477 -271.728877)
			(xy 31.235846 -271.798224) (xy 31.281593 -271.872108) (xy 31.320327 -271.949897) (xy 31.351719 -272.030929)
			(xy 31.3755 -272.114511) (xy 31.391468 -272.199931) (xy 31.399486 -272.28646) (xy 31.399988 -272.32991)
			(xy 31.399486 -272.37336) (xy 34.599874 -272.37336) (xy 34.599874 -272.28646) (xy 34.607892 -272.199931)
			(xy 34.62386 -272.114511) (xy 34.647641 -272.030929) (xy 34.679033 -271.949897) (xy 34.717767 -271.872108)
			(xy 34.763514 -271.798224) (xy 34.815883 -271.728877) (xy 34.874427 -271.664657) (xy 34.938647 -271.606113)
			(xy 35.007994 -271.553744) (xy 35.081878 -271.507997) (xy 35.159667 -271.469263) (xy 35.240699 -271.437871)
			(xy 35.324281 -271.41409) (xy 35.409701 -271.398122) (xy 35.49623 -271.390104) (xy 35.58313 -271.390104)
			(xy 35.669659 -271.398122) (xy 35.755079 -271.41409) (xy 35.838661 -271.437871) (xy 35.919693 -271.469263)
			(xy 35.997482 -271.507997) (xy 36.071366 -271.553744) (xy 36.140713 -271.606113) (xy 36.204933 -271.664657)
			(xy 36.263477 -271.728877) (xy 36.315846 -271.798224) (xy 36.361593 -271.872108) (xy 36.400327 -271.949897)
			(xy 36.431719 -272.030929) (xy 36.4555 -272.114511) (xy 36.471468 -272.199931) (xy 36.479486 -272.28646)
			(xy 36.479988 -272.32991) (xy 36.479486 -272.37336) (xy 36.471468 -272.459889) (xy 36.4555 -272.545309)
			(xy 36.431719 -272.628891) (xy 36.400327 -272.709923) (xy 36.361593 -272.787712) (xy 36.315846 -272.861596)
			(xy 36.263477 -272.930943) (xy 36.204933 -272.995163) (xy 36.140713 -273.053707) (xy 36.071366 -273.106076)
			(xy 35.997482 -273.151823) (xy 35.919693 -273.190557) (xy 35.838661 -273.221949) (xy 35.755079 -273.24573)
			(xy 35.669659 -273.261698) (xy 35.58313 -273.269716) (xy 35.49623 -273.269716) (xy 35.409701 -273.261698)
			(xy 35.324281 -273.24573) (xy 35.240699 -273.221949) (xy 35.159667 -273.190557) (xy 35.081878 -273.151823)
			(xy 35.007994 -273.106076) (xy 34.938647 -273.053707) (xy 34.874427 -272.995163) (xy 34.815883 -272.930943)
			(xy 34.763514 -272.861596) (xy 34.717767 -272.787712) (xy 34.679033 -272.709923) (xy 34.647641 -272.628891)
			(xy 34.62386 -272.545309) (xy 34.607892 -272.459889) (xy 34.599874 -272.37336) (xy 31.399486 -272.37336)
			(xy 31.391468 -272.459889) (xy 31.3755 -272.545309) (xy 31.351719 -272.628891) (xy 31.320327 -272.709923)
			(xy 31.281593 -272.787712) (xy 31.235846 -272.861596) (xy 31.183477 -272.930943) (xy 31.124933 -272.995163)
			(xy 31.060713 -273.053707) (xy 30.991366 -273.106076) (xy 30.917482 -273.151823) (xy 30.839693 -273.190557)
			(xy 30.758661 -273.221949) (xy 30.675079 -273.24573) (xy 30.589659 -273.261698) (xy 30.50313 -273.269716)
			(xy 30.41623 -273.269716) (xy 30.329701 -273.261698) (xy 30.244281 -273.24573) (xy 30.160699 -273.221949)
			(xy 30.079667 -273.190557) (xy 30.001878 -273.151823) (xy 29.927994 -273.106076) (xy 29.858647 -273.053707)
			(xy 29.794427 -272.995163) (xy 29.735883 -272.930943) (xy 29.683514 -272.861596) (xy 29.637767 -272.787712)
			(xy 29.599033 -272.709923) (xy 29.567641 -272.628891) (xy 29.54386 -272.545309) (xy 29.527892 -272.459889)
			(xy 29.519874 -272.37336) (xy 27.612926 -272.37336) (xy 27.605489 -272.423894) (xy 27.589421 -272.477301)
			(xy 27.565749 -272.527798) (xy 27.534976 -272.574311) (xy 27.497759 -272.615848) (xy 27.454891 -272.651523)
			(xy 27.407285 -272.680577) (xy 27.355956 -272.702389) (xy 27.301999 -272.716495) (xy 27.246562 -272.722595)
			(xy 27.190828 -272.720558) (xy 27.135985 -272.710428) (xy 27.083201 -272.692421) (xy 27.033601 -272.66692)
			(xy 26.988243 -272.634469) (xy 26.948094 -272.59576) (xy 26.914008 -272.551617) (xy 26.886712 -272.502982)
			(xy 26.866789 -272.450891) (xy 26.854663 -272.396454) (xy 26.850592 -272.340832) (xy 24.962021 -272.340832)
			(xy 24.962104 -272.345404) (xy 24.961595 -272.37329) (xy 24.953475 -272.428466) (xy 24.937407 -272.481873)
			(xy 24.913735 -272.53237) (xy 24.882962 -272.578883) (xy 24.845745 -272.62042) (xy 24.802877 -272.656095)
			(xy 24.755271 -272.685149) (xy 24.703942 -272.706961) (xy 24.649985 -272.721067) (xy 24.594548 -272.727167)
			(xy 24.538814 -272.72513) (xy 24.483971 -272.715) (xy 24.431187 -272.696993) (xy 24.381587 -272.671492)
			(xy 24.336229 -272.639041) (xy 24.29608 -272.600332) (xy 24.261994 -272.556189) (xy 24.234698 -272.507554)
			(xy 24.214775 -272.455463) (xy 24.202649 -272.401026) (xy 24.198578 -272.345404) (xy 18.378842 -272.345404)
			(xy 17.114134 -273.61007) (xy 39.818063 -273.61007) (xy 39.82207 -273.494046) (xy 39.834072 -273.378574)
			(xy 39.854012 -273.264206) (xy 39.881795 -273.151486) (xy 39.917289 -273.040952) (xy 39.960324 -272.933129)
			(xy 40.010695 -272.828532) (xy 40.068162 -272.72766) (xy 40.132452 -272.630993) (xy 40.203257 -272.538992)
			(xy 40.280241 -272.452095) (xy 40.363037 -272.370716) (xy 40.45125 -272.295243) (xy 40.54446 -272.226036)
			(xy 40.642223 -272.163424) (xy 40.744072 -272.107707) (xy 40.849522 -272.059149) (xy 40.958071 -272.017981)
			(xy 41.069202 -271.984401) (xy 41.182385 -271.958568) (xy 41.29708 -271.940605) (xy 41.412742 -271.930597)
			(xy 41.528818 -271.928594) (xy 41.644756 -271.934603) (xy 41.760003 -271.948596) (xy 41.874009 -271.970507)
			(xy 41.986233 -272.000232) (xy 42.096139 -272.037628) (xy 42.203202 -272.082517) (xy 42.306914 -272.134686)
			(xy 42.406779 -272.193886) (xy 42.502322 -272.259835) (xy 42.502604 -272.26006) (xy 43.327577 -272.26006)
			(xy 43.331612 -272.184356) (xy 43.343671 -272.109511) (xy 43.363617 -272.03637) (xy 43.391224 -271.965765)
			(xy 43.42618 -271.898494) (xy 43.468088 -271.835319) (xy 43.516474 -271.776957) (xy 43.57079 -271.724069)
			(xy 43.630419 -271.677254) (xy 43.694687 -271.637042) (xy 43.762864 -271.60389) (xy 43.83418 -271.578172)
			(xy 43.907825 -271.56018) (xy 43.982965 -271.550118) (xy 44.058749 -271.548099) (xy 44.134319 -271.554148)
			(xy 44.208817 -271.568195) (xy 44.2814 -271.590081) (xy 44.351246 -271.619558) (xy 44.417563 -271.656293)
			(xy 44.479599 -271.699868) (xy 44.536652 -271.74979) (xy 44.588076 -271.805494) (xy 44.633287 -271.866349)
			(xy 44.671774 -271.931664) (xy 44.7031 -272.0007) (xy 44.72691 -272.072675) (xy 44.742935 -272.146773)
			(xy 44.750994 -272.222154) (xy 44.751498 -272.26006) (xy 45.867577 -272.26006) (xy 45.871612 -272.184356)
			(xy 45.883671 -272.109511) (xy 45.903617 -272.03637) (xy 45.931224 -271.965765) (xy 45.96618 -271.898494)
			(xy 46.008088 -271.835319) (xy 46.056474 -271.776957) (xy 46.11079 -271.724069) (xy 46.170419 -271.677254)
			(xy 46.234687 -271.637042) (xy 46.302864 -271.60389) (xy 46.37418 -271.578172) (xy 46.447825 -271.56018)
			(xy 46.522965 -271.550118) (xy 46.598749 -271.548099) (xy 46.674319 -271.554148) (xy 46.748817 -271.568195)
			(xy 46.8214 -271.590081) (xy 46.891246 -271.619558) (xy 46.957563 -271.656293) (xy 47.019599 -271.699868)
			(xy 47.076652 -271.74979) (xy 47.128076 -271.805494) (xy 47.173287 -271.866349) (xy 47.211774 -271.931664)
			(xy 47.2431 -272.0007) (xy 47.26691 -272.072675) (xy 47.282935 -272.146773) (xy 47.290994 -272.222154)
			(xy 47.291498 -272.26006) (xy 48.407577 -272.26006) (xy 48.411612 -272.184356) (xy 48.423671 -272.109511)
			(xy 48.443617 -272.03637) (xy 48.471224 -271.965765) (xy 48.50618 -271.898494) (xy 48.548088 -271.835319)
			(xy 48.596474 -271.776957) (xy 48.65079 -271.724069) (xy 48.710419 -271.677254) (xy 48.774687 -271.637042)
			(xy 48.842864 -271.60389) (xy 48.91418 -271.578172) (xy 48.987825 -271.56018) (xy 49.062965 -271.550118)
			(xy 49.138749 -271.548099) (xy 49.214319 -271.554148) (xy 49.288817 -271.568195) (xy 49.3614 -271.590081)
			(xy 49.431246 -271.619558) (xy 49.497563 -271.656293) (xy 49.559599 -271.699868) (xy 49.616652 -271.74979)
			(xy 49.668076 -271.805494) (xy 49.713287 -271.866349) (xy 49.751774 -271.931664) (xy 49.7831 -272.0007)
			(xy 49.80691 -272.072675) (xy 49.822935 -272.146773) (xy 49.830994 -272.222154) (xy 49.831498 -272.26006)
			(xy 50.947577 -272.26006) (xy 50.951612 -272.184356) (xy 50.963671 -272.109511) (xy 50.983617 -272.03637)
			(xy 51.011224 -271.965765) (xy 51.04618 -271.898494) (xy 51.088088 -271.835319) (xy 51.136474 -271.776957)
			(xy 51.19079 -271.724069) (xy 51.250419 -271.677254) (xy 51.314687 -271.637042) (xy 51.382864 -271.60389)
			(xy 51.45418 -271.578172) (xy 51.527825 -271.56018) (xy 51.602965 -271.550118) (xy 51.678749 -271.548099)
			(xy 51.754319 -271.554148) (xy 51.828817 -271.568195) (xy 51.9014 -271.590081) (xy 51.971246 -271.619558)
			(xy 52.037563 -271.656293) (xy 52.099599 -271.699868) (xy 52.156652 -271.74979) (xy 52.208076 -271.805494)
			(xy 52.253287 -271.866349) (xy 52.291774 -271.931664) (xy 52.3231 -272.0007) (xy 52.34691 -272.072675)
			(xy 52.362935 -272.146773) (xy 52.370994 -272.222154) (xy 52.371498 -272.26006) (xy 53.487577 -272.26006)
			(xy 53.491612 -272.184356) (xy 53.503671 -272.109511) (xy 53.523617 -272.03637) (xy 53.551224 -271.965765)
			(xy 53.58618 -271.898494) (xy 53.628088 -271.835319) (xy 53.676474 -271.776957) (xy 53.73079 -271.724069)
			(xy 53.790419 -271.677254) (xy 53.854687 -271.637042) (xy 53.922864 -271.60389) (xy 53.99418 -271.578172)
			(xy 54.067825 -271.56018) (xy 54.142965 -271.550118) (xy 54.218749 -271.548099) (xy 54.294319 -271.554148)
			(xy 54.368817 -271.568195) (xy 54.4414 -271.590081) (xy 54.511246 -271.619558) (xy 54.577563 -271.656293)
			(xy 54.639599 -271.699868) (xy 54.696652 -271.74979) (xy 54.748076 -271.805494) (xy 54.793287 -271.866349)
			(xy 54.831774 -271.931664) (xy 54.8631 -272.0007) (xy 54.88691 -272.072675) (xy 54.902935 -272.146773)
			(xy 54.910994 -272.222154) (xy 54.911498 -272.26006) (xy 56.027577 -272.26006) (xy 56.031612 -272.184356)
			(xy 56.043671 -272.109511) (xy 56.063617 -272.03637) (xy 56.091224 -271.965765) (xy 56.12618 -271.898494)
			(xy 56.168088 -271.835319) (xy 56.216474 -271.776957) (xy 56.27079 -271.724069) (xy 56.330419 -271.677254)
			(xy 56.394687 -271.637042) (xy 56.462864 -271.60389) (xy 56.53418 -271.578172) (xy 56.607825 -271.56018)
			(xy 56.682965 -271.550118) (xy 56.758749 -271.548099) (xy 56.834319 -271.554148) (xy 56.908817 -271.568195)
			(xy 56.9814 -271.590081) (xy 57.051246 -271.619558) (xy 57.117563 -271.656293) (xy 57.179599 -271.699868)
			(xy 57.236652 -271.74979) (xy 57.288076 -271.805494) (xy 57.333287 -271.866349) (xy 57.371774 -271.931664)
			(xy 57.4031 -272.0007) (xy 57.42691 -272.072675) (xy 57.442935 -272.146773) (xy 57.450994 -272.222154)
			(xy 57.451498 -272.26006) (xy 58.567577 -272.26006) (xy 58.571612 -272.184356) (xy 58.583671 -272.109511)
			(xy 58.603617 -272.03637) (xy 58.631224 -271.965765) (xy 58.66618 -271.898494) (xy 58.708088 -271.835319)
			(xy 58.756474 -271.776957) (xy 58.81079 -271.724069) (xy 58.870419 -271.677254) (xy 58.934687 -271.637042)
			(xy 59.002864 -271.60389) (xy 59.07418 -271.578172) (xy 59.147825 -271.56018) (xy 59.222965 -271.550118)
			(xy 59.298749 -271.548099) (xy 59.374319 -271.554148) (xy 59.448817 -271.568195) (xy 59.5214 -271.590081)
			(xy 59.591246 -271.619558) (xy 59.657563 -271.656293) (xy 59.719599 -271.699868) (xy 59.776652 -271.74979)
			(xy 59.828076 -271.805494) (xy 59.873287 -271.866349) (xy 59.911774 -271.931664) (xy 59.9431 -272.0007)
			(xy 59.96691 -272.072675) (xy 59.982935 -272.146773) (xy 59.990994 -272.222154) (xy 59.991498 -272.26006)
			(xy 61.107577 -272.26006) (xy 61.111612 -272.184356) (xy 61.123671 -272.109511) (xy 61.143617 -272.03637)
			(xy 61.171224 -271.965765) (xy 61.20618 -271.898494) (xy 61.248088 -271.835319) (xy 61.296474 -271.776957)
			(xy 61.35079 -271.724069) (xy 61.410419 -271.677254) (xy 61.474687 -271.637042) (xy 61.542864 -271.60389)
			(xy 61.61418 -271.578172) (xy 61.687825 -271.56018) (xy 61.762965 -271.550118) (xy 61.838749 -271.548099)
			(xy 61.914319 -271.554148) (xy 61.988817 -271.568195) (xy 62.0614 -271.590081) (xy 62.131246 -271.619558)
			(xy 62.197563 -271.656293) (xy 62.259599 -271.699868) (xy 62.316652 -271.74979) (xy 62.368076 -271.805494)
			(xy 62.413287 -271.866349) (xy 62.451774 -271.931664) (xy 62.4831 -272.0007) (xy 62.50691 -272.072675)
			(xy 62.522935 -272.146773) (xy 62.530994 -272.222154) (xy 62.531498 -272.26006) (xy 62.530994 -272.297966)
			(xy 62.522935 -272.373347) (xy 62.50691 -272.447445) (xy 62.4831 -272.51942) (xy 62.451774 -272.588456)
			(xy 62.413287 -272.653771) (xy 62.368076 -272.714626) (xy 62.316652 -272.77033) (xy 62.259599 -272.820252)
			(xy 62.197563 -272.863827) (xy 62.131246 -272.900562) (xy 62.0614 -272.930039) (xy 61.988817 -272.951925)
			(xy 61.914319 -272.965972) (xy 61.838749 -272.972021) (xy 61.762965 -272.970002) (xy 61.687825 -272.95994)
			(xy 61.61418 -272.941948) (xy 61.542864 -272.91623) (xy 61.474687 -272.883078) (xy 61.410419 -272.842866)
			(xy 61.35079 -272.796051) (xy 61.296474 -272.743163) (xy 61.248088 -272.684801) (xy 61.20618 -272.621626)
			(xy 61.171224 -272.554355) (xy 61.143617 -272.48375) (xy 61.123671 -272.410609) (xy 61.111612 -272.335764)
			(xy 61.107577 -272.26006) (xy 59.991498 -272.26006) (xy 59.990994 -272.297966) (xy 59.982935 -272.373347)
			(xy 59.96691 -272.447445) (xy 59.9431 -272.51942) (xy 59.911774 -272.588456) (xy 59.873287 -272.653771)
			(xy 59.828076 -272.714626) (xy 59.776652 -272.77033) (xy 59.719599 -272.820252) (xy 59.657563 -272.863827)
			(xy 59.591246 -272.900562) (xy 59.5214 -272.930039) (xy 59.448817 -272.951925) (xy 59.374319 -272.965972)
			(xy 59.298749 -272.972021) (xy 59.222965 -272.970002) (xy 59.147825 -272.95994) (xy 59.07418 -272.941948)
			(xy 59.002864 -272.91623) (xy 58.934687 -272.883078) (xy 58.870419 -272.842866) (xy 58.81079 -272.796051)
			(xy 58.756474 -272.743163) (xy 58.708088 -272.684801) (xy 58.66618 -272.621626) (xy 58.631224 -272.554355)
			(xy 58.603617 -272.48375) (xy 58.583671 -272.410609) (xy 58.571612 -272.335764) (xy 58.567577 -272.26006)
			(xy 57.451498 -272.26006) (xy 57.450994 -272.297966) (xy 57.442935 -272.373347) (xy 57.42691 -272.447445)
			(xy 57.4031 -272.51942) (xy 57.371774 -272.588456) (xy 57.333287 -272.653771) (xy 57.288076 -272.714626)
			(xy 57.236652 -272.77033) (xy 57.179599 -272.820252) (xy 57.117563 -272.863827) (xy 57.051246 -272.900562)
			(xy 56.9814 -272.930039) (xy 56.908817 -272.951925) (xy 56.834319 -272.965972) (xy 56.758749 -272.972021)
			(xy 56.682965 -272.970002) (xy 56.607825 -272.95994) (xy 56.53418 -272.941948) (xy 56.462864 -272.91623)
			(xy 56.394687 -272.883078) (xy 56.330419 -272.842866) (xy 56.27079 -272.796051) (xy 56.216474 -272.743163)
			(xy 56.168088 -272.684801) (xy 56.12618 -272.621626) (xy 56.091224 -272.554355) (xy 56.063617 -272.48375)
			(xy 56.043671 -272.410609) (xy 56.031612 -272.335764) (xy 56.027577 -272.26006) (xy 54.911498 -272.26006)
			(xy 54.910994 -272.297966) (xy 54.902935 -272.373347) (xy 54.88691 -272.447445) (xy 54.8631 -272.51942)
			(xy 54.831774 -272.588456) (xy 54.793287 -272.653771) (xy 54.748076 -272.714626) (xy 54.696652 -272.77033)
			(xy 54.639599 -272.820252) (xy 54.577563 -272.863827) (xy 54.511246 -272.900562) (xy 54.4414 -272.930039)
			(xy 54.368817 -272.951925) (xy 54.294319 -272.965972) (xy 54.218749 -272.972021) (xy 54.142965 -272.970002)
			(xy 54.067825 -272.95994) (xy 53.99418 -272.941948) (xy 53.922864 -272.91623) (xy 53.854687 -272.883078)
			(xy 53.790419 -272.842866) (xy 53.73079 -272.796051) (xy 53.676474 -272.743163) (xy 53.628088 -272.684801)
			(xy 53.58618 -272.621626) (xy 53.551224 -272.554355) (xy 53.523617 -272.48375) (xy 53.503671 -272.410609)
			(xy 53.491612 -272.335764) (xy 53.487577 -272.26006) (xy 52.371498 -272.26006) (xy 52.370994 -272.297966)
			(xy 52.362935 -272.373347) (xy 52.34691 -272.447445) (xy 52.3231 -272.51942) (xy 52.291774 -272.588456)
			(xy 52.253287 -272.653771) (xy 52.208076 -272.714626) (xy 52.156652 -272.77033) (xy 52.099599 -272.820252)
			(xy 52.037563 -272.863827) (xy 51.971246 -272.900562) (xy 51.9014 -272.930039) (xy 51.828817 -272.951925)
			(xy 51.754319 -272.965972) (xy 51.678749 -272.972021) (xy 51.602965 -272.970002) (xy 51.527825 -272.95994)
			(xy 51.45418 -272.941948) (xy 51.382864 -272.91623) (xy 51.314687 -272.883078) (xy 51.250419 -272.842866)
			(xy 51.19079 -272.796051) (xy 51.136474 -272.743163) (xy 51.088088 -272.684801) (xy 51.04618 -272.621626)
			(xy 51.011224 -272.554355) (xy 50.983617 -272.48375) (xy 50.963671 -272.410609) (xy 50.951612 -272.335764)
			(xy 50.947577 -272.26006) (xy 49.831498 -272.26006) (xy 49.830994 -272.297966) (xy 49.822935 -272.373347)
			(xy 49.80691 -272.447445) (xy 49.7831 -272.51942) (xy 49.751774 -272.588456) (xy 49.713287 -272.653771)
			(xy 49.668076 -272.714626) (xy 49.616652 -272.77033) (xy 49.559599 -272.820252) (xy 49.497563 -272.863827)
			(xy 49.431246 -272.900562) (xy 49.3614 -272.930039) (xy 49.288817 -272.951925) (xy 49.214319 -272.965972)
			(xy 49.138749 -272.972021) (xy 49.062965 -272.970002) (xy 48.987825 -272.95994) (xy 48.91418 -272.941948)
			(xy 48.842864 -272.91623) (xy 48.774687 -272.883078) (xy 48.710419 -272.842866) (xy 48.65079 -272.796051)
			(xy 48.596474 -272.743163) (xy 48.548088 -272.684801) (xy 48.50618 -272.621626) (xy 48.471224 -272.554355)
			(xy 48.443617 -272.48375) (xy 48.423671 -272.410609) (xy 48.411612 -272.335764) (xy 48.407577 -272.26006)
			(xy 47.291498 -272.26006) (xy 47.290994 -272.297966) (xy 47.282935 -272.373347) (xy 47.26691 -272.447445)
			(xy 47.2431 -272.51942) (xy 47.211774 -272.588456) (xy 47.173287 -272.653771) (xy 47.128076 -272.714626)
			(xy 47.076652 -272.77033) (xy 47.019599 -272.820252) (xy 46.957563 -272.863827) (xy 46.891246 -272.900562)
			(xy 46.8214 -272.930039) (xy 46.748817 -272.951925) (xy 46.674319 -272.965972) (xy 46.598749 -272.972021)
			(xy 46.522965 -272.970002) (xy 46.447825 -272.95994) (xy 46.37418 -272.941948) (xy 46.302864 -272.91623)
			(xy 46.234687 -272.883078) (xy 46.170419 -272.842866) (xy 46.11079 -272.796051) (xy 46.056474 -272.743163)
			(xy 46.008088 -272.684801) (xy 45.96618 -272.621626) (xy 45.931224 -272.554355) (xy 45.903617 -272.48375)
			(xy 45.883671 -272.410609) (xy 45.871612 -272.335764) (xy 45.867577 -272.26006) (xy 44.751498 -272.26006)
			(xy 44.750994 -272.297966) (xy 44.742935 -272.373347) (xy 44.72691 -272.447445) (xy 44.7031 -272.51942)
			(xy 44.671774 -272.588456) (xy 44.633287 -272.653771) (xy 44.588076 -272.714626) (xy 44.536652 -272.77033)
			(xy 44.479599 -272.820252) (xy 44.417563 -272.863827) (xy 44.351246 -272.900562) (xy 44.2814 -272.930039)
			(xy 44.208817 -272.951925) (xy 44.134319 -272.965972) (xy 44.058749 -272.972021) (xy 43.982965 -272.970002)
			(xy 43.907825 -272.95994) (xy 43.83418 -272.941948) (xy 43.762864 -272.91623) (xy 43.694687 -272.883078)
			(xy 43.630419 -272.842866) (xy 43.57079 -272.796051) (xy 43.516474 -272.743163) (xy 43.468088 -272.684801)
			(xy 43.42618 -272.621626) (xy 43.391224 -272.554355) (xy 43.363617 -272.48375) (xy 43.343671 -272.410609)
			(xy 43.331612 -272.335764) (xy 43.327577 -272.26006) (xy 42.502604 -272.26006) (xy 42.593088 -272.332218)
			(xy 42.678643 -272.410691) (xy 42.758581 -272.494879) (xy 42.83252 -272.584381) (xy 42.900108 -272.678772)
			(xy 42.961022 -272.7776) (xy 43.014974 -272.880396) (xy 43.061704 -272.986669) (xy 43.100992 -273.095913)
			(xy 43.132649 -273.207606) (xy 43.156525 -273.321218) (xy 43.172506 -273.436206) (xy 43.180515 -273.552023)
			(xy 43.181016 -273.61007) (xy 43.180515 -273.668117) (xy 43.172506 -273.783934) (xy 43.156525 -273.898922)
			(xy 43.132649 -274.012534) (xy 43.100992 -274.124227) (xy 43.061704 -274.233471) (xy 43.014974 -274.339744)
			(xy 42.961022 -274.44254) (xy 42.900108 -274.541368) (xy 42.83252 -274.635759) (xy 42.758581 -274.725261)
			(xy 42.678643 -274.809449) (xy 42.593088 -274.887922) (xy 42.502604 -274.96008) (xy 43.327577 -274.96008)
			(xy 43.331612 -274.884376) (xy 43.343671 -274.809531) (xy 43.363617 -274.73639) (xy 43.391224 -274.665785)
			(xy 43.42618 -274.598514) (xy 43.468088 -274.535339) (xy 43.516474 -274.476977) (xy 43.57079 -274.424089)
			(xy 43.630419 -274.377274) (xy 43.694687 -274.337062) (xy 43.762864 -274.30391) (xy 43.83418 -274.278192)
			(xy 43.907825 -274.2602) (xy 43.982965 -274.250138) (xy 44.058749 -274.248119) (xy 44.134319 -274.254168)
			(xy 44.208817 -274.268215) (xy 44.2814 -274.290101) (xy 44.351246 -274.319578) (xy 44.417563 -274.356313)
			(xy 44.479599 -274.399888) (xy 44.536652 -274.44981) (xy 44.588076 -274.505514) (xy 44.633287 -274.566369)
			(xy 44.671774 -274.631684) (xy 44.7031 -274.70072) (xy 44.72691 -274.772695) (xy 44.742935 -274.846793)
			(xy 44.750994 -274.922174) (xy 44.751498 -274.96008) (xy 45.867577 -274.96008) (xy 45.871612 -274.884376)
			(xy 45.883671 -274.809531) (xy 45.903617 -274.73639) (xy 45.931224 -274.665785) (xy 45.96618 -274.598514)
			(xy 46.008088 -274.535339) (xy 46.056474 -274.476977) (xy 46.11079 -274.424089) (xy 46.170419 -274.377274)
			(xy 46.234687 -274.337062) (xy 46.302864 -274.30391) (xy 46.37418 -274.278192) (xy 46.447825 -274.2602)
			(xy 46.522965 -274.250138) (xy 46.598749 -274.248119) (xy 46.674319 -274.254168) (xy 46.748817 -274.268215)
			(xy 46.8214 -274.290101) (xy 46.891246 -274.319578) (xy 46.957563 -274.356313) (xy 47.019599 -274.399888)
			(xy 47.076652 -274.44981) (xy 47.128076 -274.505514) (xy 47.173287 -274.566369) (xy 47.211774 -274.631684)
			(xy 47.2431 -274.70072) (xy 47.26691 -274.772695) (xy 47.282935 -274.846793) (xy 47.290994 -274.922174)
			(xy 47.291498 -274.96008) (xy 48.407577 -274.96008) (xy 48.411612 -274.884376) (xy 48.423671 -274.809531)
			(xy 48.443617 -274.73639) (xy 48.471224 -274.665785) (xy 48.50618 -274.598514) (xy 48.548088 -274.535339)
			(xy 48.596474 -274.476977) (xy 48.65079 -274.424089) (xy 48.710419 -274.377274) (xy 48.774687 -274.337062)
			(xy 48.842864 -274.30391) (xy 48.91418 -274.278192) (xy 48.987825 -274.2602) (xy 49.062965 -274.250138)
			(xy 49.138749 -274.248119) (xy 49.214319 -274.254168) (xy 49.288817 -274.268215) (xy 49.3614 -274.290101)
			(xy 49.431246 -274.319578) (xy 49.497563 -274.356313) (xy 49.559599 -274.399888) (xy 49.616652 -274.44981)
			(xy 49.668076 -274.505514) (xy 49.713287 -274.566369) (xy 49.751774 -274.631684) (xy 49.7831 -274.70072)
			(xy 49.80691 -274.772695) (xy 49.822935 -274.846793) (xy 49.830994 -274.922174) (xy 49.831498 -274.96008)
			(xy 50.947577 -274.96008) (xy 50.951612 -274.884376) (xy 50.963671 -274.809531) (xy 50.983617 -274.73639)
			(xy 51.011224 -274.665785) (xy 51.04618 -274.598514) (xy 51.088088 -274.535339) (xy 51.136474 -274.476977)
			(xy 51.19079 -274.424089) (xy 51.250419 -274.377274) (xy 51.314687 -274.337062) (xy 51.382864 -274.30391)
			(xy 51.45418 -274.278192) (xy 51.527825 -274.2602) (xy 51.602965 -274.250138) (xy 51.678749 -274.248119)
			(xy 51.754319 -274.254168) (xy 51.828817 -274.268215) (xy 51.9014 -274.290101) (xy 51.971246 -274.319578)
			(xy 52.037563 -274.356313) (xy 52.099599 -274.399888) (xy 52.156652 -274.44981) (xy 52.208076 -274.505514)
			(xy 52.253287 -274.566369) (xy 52.291774 -274.631684) (xy 52.3231 -274.70072) (xy 52.34691 -274.772695)
			(xy 52.362935 -274.846793) (xy 52.370994 -274.922174) (xy 52.371498 -274.96008) (xy 53.487577 -274.96008)
			(xy 53.491612 -274.884376) (xy 53.503671 -274.809531) (xy 53.523617 -274.73639) (xy 53.551224 -274.665785)
			(xy 53.58618 -274.598514) (xy 53.628088 -274.535339) (xy 53.676474 -274.476977) (xy 53.73079 -274.424089)
			(xy 53.790419 -274.377274) (xy 53.854687 -274.337062) (xy 53.922864 -274.30391) (xy 53.99418 -274.278192)
			(xy 54.067825 -274.2602) (xy 54.142965 -274.250138) (xy 54.218749 -274.248119) (xy 54.294319 -274.254168)
			(xy 54.368817 -274.268215) (xy 54.4414 -274.290101) (xy 54.511246 -274.319578) (xy 54.577563 -274.356313)
			(xy 54.639599 -274.399888) (xy 54.696652 -274.44981) (xy 54.748076 -274.505514) (xy 54.793287 -274.566369)
			(xy 54.831774 -274.631684) (xy 54.8631 -274.70072) (xy 54.88691 -274.772695) (xy 54.902935 -274.846793)
			(xy 54.910994 -274.922174) (xy 54.911498 -274.96008) (xy 56.027577 -274.96008) (xy 56.031612 -274.884376)
			(xy 56.043671 -274.809531) (xy 56.063617 -274.73639) (xy 56.091224 -274.665785) (xy 56.12618 -274.598514)
			(xy 56.168088 -274.535339) (xy 56.216474 -274.476977) (xy 56.27079 -274.424089) (xy 56.330419 -274.377274)
			(xy 56.394687 -274.337062) (xy 56.462864 -274.30391) (xy 56.53418 -274.278192) (xy 56.607825 -274.2602)
			(xy 56.682965 -274.250138) (xy 56.758749 -274.248119) (xy 56.834319 -274.254168) (xy 56.908817 -274.268215)
			(xy 56.9814 -274.290101) (xy 57.051246 -274.319578) (xy 57.117563 -274.356313) (xy 57.179599 -274.399888)
			(xy 57.236652 -274.44981) (xy 57.288076 -274.505514) (xy 57.333287 -274.566369) (xy 57.371774 -274.631684)
			(xy 57.4031 -274.70072) (xy 57.42691 -274.772695) (xy 57.442935 -274.846793) (xy 57.450994 -274.922174)
			(xy 57.451498 -274.96008) (xy 58.567577 -274.96008) (xy 58.571612 -274.884376) (xy 58.583671 -274.809531)
			(xy 58.603617 -274.73639) (xy 58.631224 -274.665785) (xy 58.66618 -274.598514) (xy 58.708088 -274.535339)
			(xy 58.756474 -274.476977) (xy 58.81079 -274.424089) (xy 58.870419 -274.377274) (xy 58.934687 -274.337062)
			(xy 59.002864 -274.30391) (xy 59.07418 -274.278192) (xy 59.147825 -274.2602) (xy 59.222965 -274.250138)
			(xy 59.298749 -274.248119) (xy 59.374319 -274.254168) (xy 59.448817 -274.268215) (xy 59.5214 -274.290101)
			(xy 59.591246 -274.319578) (xy 59.657563 -274.356313) (xy 59.719599 -274.399888) (xy 59.776652 -274.44981)
			(xy 59.828076 -274.505514) (xy 59.873287 -274.566369) (xy 59.911774 -274.631684) (xy 59.9431 -274.70072)
			(xy 59.96691 -274.772695) (xy 59.982935 -274.846793) (xy 59.990994 -274.922174) (xy 59.991498 -274.96008)
			(xy 61.107577 -274.96008) (xy 61.111612 -274.884376) (xy 61.123671 -274.809531) (xy 61.143617 -274.73639)
			(xy 61.171224 -274.665785) (xy 61.20618 -274.598514) (xy 61.248088 -274.535339) (xy 61.296474 -274.476977)
			(xy 61.35079 -274.424089) (xy 61.410419 -274.377274) (xy 61.474687 -274.337062) (xy 61.542864 -274.30391)
			(xy 61.61418 -274.278192) (xy 61.687825 -274.2602) (xy 61.762965 -274.250138) (xy 61.838749 -274.248119)
			(xy 61.914319 -274.254168) (xy 61.988817 -274.268215) (xy 62.0614 -274.290101) (xy 62.131246 -274.319578)
			(xy 62.197563 -274.356313) (xy 62.259599 -274.399888) (xy 62.316652 -274.44981) (xy 62.368076 -274.505514)
			(xy 62.413287 -274.566369) (xy 62.451774 -274.631684) (xy 62.4831 -274.70072) (xy 62.50691 -274.772695)
			(xy 62.522935 -274.846793) (xy 62.530994 -274.922174) (xy 62.531498 -274.96008) (xy 62.530994 -274.997986)
			(xy 62.522935 -275.073367) (xy 62.50691 -275.147465) (xy 62.4831 -275.21944) (xy 62.451774 -275.288476)
			(xy 62.413287 -275.353791) (xy 62.368076 -275.414646) (xy 62.316652 -275.47035) (xy 62.259599 -275.520272)
			(xy 62.197563 -275.563847) (xy 62.131246 -275.600582) (xy 62.0614 -275.630059) (xy 61.988817 -275.651945)
			(xy 61.914319 -275.665992) (xy 61.838749 -275.672041) (xy 61.762965 -275.670022) (xy 61.687825 -275.65996)
			(xy 61.61418 -275.641968) (xy 61.542864 -275.61625) (xy 61.474687 -275.583098) (xy 61.410419 -275.542886)
			(xy 61.35079 -275.496071) (xy 61.296474 -275.443183) (xy 61.248088 -275.384821) (xy 61.20618 -275.321646)
			(xy 61.171224 -275.254375) (xy 61.143617 -275.18377) (xy 61.123671 -275.110629) (xy 61.111612 -275.035784)
			(xy 61.107577 -274.96008) (xy 59.991498 -274.96008) (xy 59.990994 -274.997986) (xy 59.982935 -275.073367)
			(xy 59.96691 -275.147465) (xy 59.9431 -275.21944) (xy 59.911774 -275.288476) (xy 59.873287 -275.353791)
			(xy 59.828076 -275.414646) (xy 59.776652 -275.47035) (xy 59.719599 -275.520272) (xy 59.657563 -275.563847)
			(xy 59.591246 -275.600582) (xy 59.5214 -275.630059) (xy 59.448817 -275.651945) (xy 59.374319 -275.665992)
			(xy 59.298749 -275.672041) (xy 59.222965 -275.670022) (xy 59.147825 -275.65996) (xy 59.07418 -275.641968)
			(xy 59.002864 -275.61625) (xy 58.934687 -275.583098) (xy 58.870419 -275.542886) (xy 58.81079 -275.496071)
			(xy 58.756474 -275.443183) (xy 58.708088 -275.384821) (xy 58.66618 -275.321646) (xy 58.631224 -275.254375)
			(xy 58.603617 -275.18377) (xy 58.583671 -275.110629) (xy 58.571612 -275.035784) (xy 58.567577 -274.96008)
			(xy 57.451498 -274.96008) (xy 57.450994 -274.997986) (xy 57.442935 -275.073367) (xy 57.42691 -275.147465)
			(xy 57.4031 -275.21944) (xy 57.371774 -275.288476) (xy 57.333287 -275.353791) (xy 57.288076 -275.414646)
			(xy 57.236652 -275.47035) (xy 57.179599 -275.520272) (xy 57.117563 -275.563847) (xy 57.051246 -275.600582)
			(xy 56.9814 -275.630059) (xy 56.908817 -275.651945) (xy 56.834319 -275.665992) (xy 56.758749 -275.672041)
			(xy 56.682965 -275.670022) (xy 56.607825 -275.65996) (xy 56.53418 -275.641968) (xy 56.462864 -275.61625)
			(xy 56.394687 -275.583098) (xy 56.330419 -275.542886) (xy 56.27079 -275.496071) (xy 56.216474 -275.443183)
			(xy 56.168088 -275.384821) (xy 56.12618 -275.321646) (xy 56.091224 -275.254375) (xy 56.063617 -275.18377)
			(xy 56.043671 -275.110629) (xy 56.031612 -275.035784) (xy 56.027577 -274.96008) (xy 54.911498 -274.96008)
			(xy 54.910994 -274.997986) (xy 54.902935 -275.073367) (xy 54.88691 -275.147465) (xy 54.8631 -275.21944)
			(xy 54.831774 -275.288476) (xy 54.793287 -275.353791) (xy 54.748076 -275.414646) (xy 54.696652 -275.47035)
			(xy 54.639599 -275.520272) (xy 54.577563 -275.563847) (xy 54.511246 -275.600582) (xy 54.4414 -275.630059)
			(xy 54.368817 -275.651945) (xy 54.294319 -275.665992) (xy 54.218749 -275.672041) (xy 54.142965 -275.670022)
			(xy 54.067825 -275.65996) (xy 53.99418 -275.641968) (xy 53.922864 -275.61625) (xy 53.854687 -275.583098)
			(xy 53.790419 -275.542886) (xy 53.73079 -275.496071) (xy 53.676474 -275.443183) (xy 53.628088 -275.384821)
			(xy 53.58618 -275.321646) (xy 53.551224 -275.254375) (xy 53.523617 -275.18377) (xy 53.503671 -275.110629)
			(xy 53.491612 -275.035784) (xy 53.487577 -274.96008) (xy 52.371498 -274.96008) (xy 52.370994 -274.997986)
			(xy 52.362935 -275.073367) (xy 52.34691 -275.147465) (xy 52.3231 -275.21944) (xy 52.291774 -275.288476)
			(xy 52.253287 -275.353791) (xy 52.208076 -275.414646) (xy 52.156652 -275.47035) (xy 52.099599 -275.520272)
			(xy 52.037563 -275.563847) (xy 51.971246 -275.600582) (xy 51.9014 -275.630059) (xy 51.828817 -275.651945)
			(xy 51.754319 -275.665992) (xy 51.678749 -275.672041) (xy 51.602965 -275.670022) (xy 51.527825 -275.65996)
			(xy 51.45418 -275.641968) (xy 51.382864 -275.61625) (xy 51.314687 -275.583098) (xy 51.250419 -275.542886)
			(xy 51.19079 -275.496071) (xy 51.136474 -275.443183) (xy 51.088088 -275.384821) (xy 51.04618 -275.321646)
			(xy 51.011224 -275.254375) (xy 50.983617 -275.18377) (xy 50.963671 -275.110629) (xy 50.951612 -275.035784)
			(xy 50.947577 -274.96008) (xy 49.831498 -274.96008) (xy 49.830994 -274.997986) (xy 49.822935 -275.073367)
			(xy 49.80691 -275.147465) (xy 49.7831 -275.21944) (xy 49.751774 -275.288476) (xy 49.713287 -275.353791)
			(xy 49.668076 -275.414646) (xy 49.616652 -275.47035) (xy 49.559599 -275.520272) (xy 49.497563 -275.563847)
			(xy 49.431246 -275.600582) (xy 49.3614 -275.630059) (xy 49.288817 -275.651945) (xy 49.214319 -275.665992)
			(xy 49.138749 -275.672041) (xy 49.062965 -275.670022) (xy 48.987825 -275.65996) (xy 48.91418 -275.641968)
			(xy 48.842864 -275.61625) (xy 48.774687 -275.583098) (xy 48.710419 -275.542886) (xy 48.65079 -275.496071)
			(xy 48.596474 -275.443183) (xy 48.548088 -275.384821) (xy 48.50618 -275.321646) (xy 48.471224 -275.254375)
			(xy 48.443617 -275.18377) (xy 48.423671 -275.110629) (xy 48.411612 -275.035784) (xy 48.407577 -274.96008)
			(xy 47.291498 -274.96008) (xy 47.290994 -274.997986) (xy 47.282935 -275.073367) (xy 47.26691 -275.147465)
			(xy 47.2431 -275.21944) (xy 47.211774 -275.288476) (xy 47.173287 -275.353791) (xy 47.128076 -275.414646)
			(xy 47.076652 -275.47035) (xy 47.019599 -275.520272) (xy 46.957563 -275.563847) (xy 46.891246 -275.600582)
			(xy 46.8214 -275.630059) (xy 46.748817 -275.651945) (xy 46.674319 -275.665992) (xy 46.598749 -275.672041)
			(xy 46.522965 -275.670022) (xy 46.447825 -275.65996) (xy 46.37418 -275.641968) (xy 46.302864 -275.61625)
			(xy 46.234687 -275.583098) (xy 46.170419 -275.542886) (xy 46.11079 -275.496071) (xy 46.056474 -275.443183)
			(xy 46.008088 -275.384821) (xy 45.96618 -275.321646) (xy 45.931224 -275.254375) (xy 45.903617 -275.18377)
			(xy 45.883671 -275.110629) (xy 45.871612 -275.035784) (xy 45.867577 -274.96008) (xy 44.751498 -274.96008)
			(xy 44.750994 -274.997986) (xy 44.742935 -275.073367) (xy 44.72691 -275.147465) (xy 44.7031 -275.21944)
			(xy 44.671774 -275.288476) (xy 44.633287 -275.353791) (xy 44.588076 -275.414646) (xy 44.536652 -275.47035)
			(xy 44.479599 -275.520272) (xy 44.417563 -275.563847) (xy 44.351246 -275.600582) (xy 44.2814 -275.630059)
			(xy 44.208817 -275.651945) (xy 44.134319 -275.665992) (xy 44.058749 -275.672041) (xy 43.982965 -275.670022)
			(xy 43.907825 -275.65996) (xy 43.83418 -275.641968) (xy 43.762864 -275.61625) (xy 43.694687 -275.583098)
			(xy 43.630419 -275.542886) (xy 43.57079 -275.496071) (xy 43.516474 -275.443183) (xy 43.468088 -275.384821)
			(xy 43.42618 -275.321646) (xy 43.391224 -275.254375) (xy 43.363617 -275.18377) (xy 43.343671 -275.110629)
			(xy 43.331612 -275.035784) (xy 43.327577 -274.96008) (xy 42.502604 -274.96008) (xy 42.502322 -274.960305)
			(xy 42.406779 -275.026254) (xy 42.306914 -275.085454) (xy 42.203202 -275.137623) (xy 42.096139 -275.182512)
			(xy 41.986233 -275.219908) (xy 41.874009 -275.249633) (xy 41.760003 -275.271544) (xy 41.644756 -275.285537)
			(xy 41.528818 -275.291546) (xy 41.412742 -275.289543) (xy 41.29708 -275.279535) (xy 41.182385 -275.261572)
			(xy 41.069202 -275.235739) (xy 40.958071 -275.202159) (xy 40.849522 -275.160991) (xy 40.744072 -275.112433)
			(xy 40.642223 -275.056716) (xy 40.54446 -274.994104) (xy 40.45125 -274.924897) (xy 40.363037 -274.849424)
			(xy 40.280241 -274.768045) (xy 40.203257 -274.681148) (xy 40.132452 -274.589147) (xy 40.068162 -274.49248)
			(xy 40.010695 -274.391608) (xy 39.960324 -274.287011) (xy 39.917289 -274.179188) (xy 39.881795 -274.068654)
			(xy 39.854012 -273.955934) (xy 39.834072 -273.841566) (xy 39.82207 -273.726094) (xy 39.818063 -273.61007)
			(xy 17.114134 -273.61007) (xy 15.949252 -274.774914) (xy 24.175718 -274.774914) (xy 24.179789 -274.719292)
			(xy 24.191915 -274.664855) (xy 24.211838 -274.612764) (xy 24.239134 -274.564129) (xy 24.27322 -274.519986)
			(xy 24.313369 -274.481277) (xy 24.358727 -274.448826) (xy 24.408327 -274.423325) (xy 24.461111 -274.405318)
			(xy 24.515954 -274.395188) (xy 24.571688 -274.393151) (xy 24.627125 -274.399251) (xy 24.681082 -274.413357)
			(xy 24.732411 -274.435169) (xy 24.780017 -274.464223) (xy 24.822885 -274.499898) (xy 24.860102 -274.541435)
			(xy 24.890875 -274.587948) (xy 24.914547 -274.638445) (xy 24.930615 -274.691852) (xy 24.938735 -274.747028)
			(xy 24.939244 -274.774914) (xy 26.855672 -274.774914) (xy 26.859743 -274.719292) (xy 26.871869 -274.664855)
			(xy 26.891792 -274.612764) (xy 26.919088 -274.564129) (xy 26.953174 -274.519986) (xy 26.993323 -274.481277)
			(xy 27.038681 -274.448826) (xy 27.088281 -274.423325) (xy 27.141065 -274.405318) (xy 27.195908 -274.395188)
			(xy 27.251642 -274.393151) (xy 27.307079 -274.399251) (xy 27.361036 -274.413357) (xy 27.412365 -274.435169)
			(xy 27.459971 -274.464223) (xy 27.502839 -274.499898) (xy 27.540056 -274.541435) (xy 27.570829 -274.587948)
			(xy 27.594501 -274.638445) (xy 27.610569 -274.691852) (xy 27.618689 -274.747028) (xy 27.619198 -274.774914)
			(xy 27.618689 -274.8028) (xy 27.610569 -274.857976) (xy 27.594501 -274.911383) (xy 27.593574 -274.91336)
			(xy 29.519874 -274.91336) (xy 29.519874 -274.82646) (xy 29.527892 -274.739931) (xy 29.54386 -274.654511)
			(xy 29.567641 -274.570929) (xy 29.599033 -274.489897) (xy 29.637767 -274.412108) (xy 29.683514 -274.338224)
			(xy 29.735883 -274.268877) (xy 29.794427 -274.204657) (xy 29.858647 -274.146113) (xy 29.927994 -274.093744)
			(xy 30.001878 -274.047997) (xy 30.079667 -274.009263) (xy 30.160699 -273.977871) (xy 30.244281 -273.95409)
			(xy 30.329701 -273.938122) (xy 30.41623 -273.930104) (xy 30.50313 -273.930104) (xy 30.589659 -273.938122)
			(xy 30.675079 -273.95409) (xy 30.758661 -273.977871) (xy 30.839693 -274.009263) (xy 30.917482 -274.047997)
			(xy 30.991366 -274.093744) (xy 31.060713 -274.146113) (xy 31.124933 -274.204657) (xy 31.183477 -274.268877)
			(xy 31.235846 -274.338224) (xy 31.281593 -274.412108) (xy 31.320327 -274.489897) (xy 31.351719 -274.570929)
			(xy 31.3755 -274.654511) (xy 31.391468 -274.739931) (xy 31.399486 -274.82646) (xy 31.399988 -274.86991)
			(xy 31.399486 -274.91336) (xy 34.599874 -274.91336) (xy 34.599874 -274.82646) (xy 34.607892 -274.739931)
			(xy 34.62386 -274.654511) (xy 34.647641 -274.570929) (xy 34.679033 -274.489897) (xy 34.717767 -274.412108)
			(xy 34.763514 -274.338224) (xy 34.815883 -274.268877) (xy 34.874427 -274.204657) (xy 34.938647 -274.146113)
			(xy 35.007994 -274.093744) (xy 35.081878 -274.047997) (xy 35.159667 -274.009263) (xy 35.240699 -273.977871)
			(xy 35.324281 -273.95409) (xy 35.409701 -273.938122) (xy 35.49623 -273.930104) (xy 35.58313 -273.930104)
			(xy 35.669659 -273.938122) (xy 35.755079 -273.95409) (xy 35.838661 -273.977871) (xy 35.919693 -274.009263)
			(xy 35.997482 -274.047997) (xy 36.071366 -274.093744) (xy 36.140713 -274.146113) (xy 36.204933 -274.204657)
			(xy 36.263477 -274.268877) (xy 36.315846 -274.338224) (xy 36.361593 -274.412108) (xy 36.400327 -274.489897)
			(xy 36.431719 -274.570929) (xy 36.4555 -274.654511) (xy 36.471468 -274.739931) (xy 36.479486 -274.82646)
			(xy 36.479988 -274.86991) (xy 36.479486 -274.91336) (xy 36.471468 -274.999889) (xy 36.4555 -275.085309)
			(xy 36.431719 -275.168891) (xy 36.400327 -275.249923) (xy 36.361593 -275.327712) (xy 36.315846 -275.401596)
			(xy 36.263477 -275.470943) (xy 36.204933 -275.535163) (xy 36.140713 -275.593707) (xy 36.071366 -275.646076)
			(xy 35.997482 -275.691823) (xy 35.919693 -275.730557) (xy 35.838661 -275.761949) (xy 35.755079 -275.78573)
			(xy 35.669659 -275.801698) (xy 35.58313 -275.809716) (xy 35.49623 -275.809716) (xy 35.409701 -275.801698)
			(xy 35.324281 -275.78573) (xy 35.240699 -275.761949) (xy 35.159667 -275.730557) (xy 35.081878 -275.691823)
			(xy 35.007994 -275.646076) (xy 34.938647 -275.593707) (xy 34.874427 -275.535163) (xy 34.815883 -275.470943)
			(xy 34.763514 -275.401596) (xy 34.717767 -275.327712) (xy 34.679033 -275.249923) (xy 34.647641 -275.168891)
			(xy 34.62386 -275.085309) (xy 34.607892 -274.999889) (xy 34.599874 -274.91336) (xy 31.399486 -274.91336)
			(xy 31.391468 -274.999889) (xy 31.3755 -275.085309) (xy 31.351719 -275.168891) (xy 31.320327 -275.249923)
			(xy 31.281593 -275.327712) (xy 31.235846 -275.401596) (xy 31.183477 -275.470943) (xy 31.124933 -275.535163)
			(xy 31.060713 -275.593707) (xy 30.991366 -275.646076) (xy 30.917482 -275.691823) (xy 30.839693 -275.730557)
			(xy 30.758661 -275.761949) (xy 30.675079 -275.78573) (xy 30.589659 -275.801698) (xy 30.50313 -275.809716)
			(xy 30.41623 -275.809716) (xy 30.329701 -275.801698) (xy 30.244281 -275.78573) (xy 30.160699 -275.761949)
			(xy 30.079667 -275.730557) (xy 30.001878 -275.691823) (xy 29.927994 -275.646076) (xy 29.858647 -275.593707)
			(xy 29.794427 -275.535163) (xy 29.735883 -275.470943) (xy 29.683514 -275.401596) (xy 29.637767 -275.327712)
			(xy 29.599033 -275.249923) (xy 29.567641 -275.168891) (xy 29.54386 -275.085309) (xy 29.527892 -274.999889)
			(xy 29.519874 -274.91336) (xy 27.593574 -274.91336) (xy 27.570829 -274.96188) (xy 27.540056 -275.008393)
			(xy 27.502839 -275.04993) (xy 27.459971 -275.085605) (xy 27.412365 -275.114659) (xy 27.361036 -275.136471)
			(xy 27.307079 -275.150577) (xy 27.251642 -275.156677) (xy 27.195908 -275.15464) (xy 27.141065 -275.14451)
			(xy 27.088281 -275.126503) (xy 27.038681 -275.101002) (xy 26.993323 -275.068551) (xy 26.953174 -275.029842)
			(xy 26.919088 -274.985699) (xy 26.891792 -274.937064) (xy 26.871869 -274.884973) (xy 26.859743 -274.830536)
			(xy 26.855672 -274.774914) (xy 24.939244 -274.774914) (xy 24.938735 -274.8028) (xy 24.930615 -274.857976)
			(xy 24.914547 -274.911383) (xy 24.890875 -274.96188) (xy 24.860102 -275.008393) (xy 24.822885 -275.04993)
			(xy 24.780017 -275.085605) (xy 24.732411 -275.114659) (xy 24.681082 -275.136471) (xy 24.627125 -275.150577)
			(xy 24.571688 -275.156677) (xy 24.515954 -275.15464) (xy 24.461111 -275.14451) (xy 24.408327 -275.126503)
			(xy 24.358727 -275.101002) (xy 24.313369 -275.068551) (xy 24.27322 -275.029842) (xy 24.239134 -274.985699)
			(xy 24.211838 -274.937064) (xy 24.191915 -274.884973) (xy 24.179789 -274.830536) (xy 24.175718 -274.774914)
			(xy 15.949252 -274.774914) (xy 14.601992 -276.12213) (xy 24.243028 -276.12213) (xy 24.247099 -276.066508)
			(xy 24.259225 -276.012071) (xy 24.279148 -275.95998) (xy 24.306444 -275.911345) (xy 24.34053 -275.867202)
			(xy 24.380679 -275.828493) (xy 24.426037 -275.796042) (xy 24.475637 -275.770541) (xy 24.528421 -275.752534)
			(xy 24.583264 -275.742404) (xy 24.638998 -275.740367) (xy 24.694435 -275.746467) (xy 24.748392 -275.760573)
			(xy 24.799721 -275.782385) (xy 24.847327 -275.811439) (xy 24.890195 -275.847114) (xy 24.927412 -275.888651)
			(xy 24.958185 -275.935164) (xy 24.981857 -275.985661) (xy 24.997925 -276.039068) (xy 25.006045 -276.094244)
			(xy 25.006554 -276.12213) (xy 25.006045 -276.150016) (xy 24.997925 -276.205192) (xy 24.981857 -276.258599)
			(xy 24.958185 -276.309096) (xy 24.927412 -276.355609) (xy 24.890195 -276.397146) (xy 24.847327 -276.432821)
			(xy 24.799721 -276.461875) (xy 24.748392 -276.483687) (xy 24.694435 -276.497793) (xy 24.638998 -276.503893)
			(xy 24.583264 -276.501856) (xy 24.528421 -276.491726) (xy 24.475637 -276.473719) (xy 24.426037 -276.448218)
			(xy 24.380679 -276.415767) (xy 24.34053 -276.377058) (xy 24.306444 -276.332915) (xy 24.279148 -276.28428)
			(xy 24.259225 -276.232189) (xy 24.247099 -276.177752) (xy 24.243028 -276.12213) (xy 14.601992 -276.12213)
			(xy 13.405866 -277.318216) (xy 11.297666 -277.318216) (xy 11.283063 -277.319297) (xy 11.254896 -277.327273)
			(xy 11.229289 -277.341461) (xy 11.218164 -277.350982) (xy 11.192002 -277.377144) (xy 24.242774 -277.377144)
			(xy 24.246845 -277.321522) (xy 24.258971 -277.267085) (xy 24.278894 -277.214994) (xy 24.30619 -277.166359)
			(xy 24.340276 -277.122216) (xy 24.380425 -277.083507) (xy 24.425783 -277.051056) (xy 24.475383 -277.025555)
			(xy 24.528167 -277.007548) (xy 24.58301 -276.997418) (xy 24.638744 -276.995381) (xy 24.694181 -277.001481)
			(xy 24.748138 -277.015587) (xy 24.799467 -277.037399) (xy 24.847073 -277.066453) (xy 24.889941 -277.102128)
			(xy 24.927158 -277.143665) (xy 24.957931 -277.190178) (xy 24.981603 -277.240675) (xy 24.997671 -277.294082)
			(xy 25.005791 -277.349258) (xy 25.0063 -277.377144) (xy 25.005791 -277.40503) (xy 24.997671 -277.460206)
			(xy 24.981603 -277.513613) (xy 24.957931 -277.56411) (xy 24.927158 -277.610623) (xy 24.889941 -277.65216)
			(xy 24.847073 -277.687835) (xy 24.799467 -277.716889) (xy 24.748138 -277.738701) (xy 24.724288 -277.744936)
			(xy 26.885136 -277.744936) (xy 26.889207 -277.689314) (xy 26.901333 -277.634877) (xy 26.921256 -277.582786)
			(xy 26.948552 -277.534151) (xy 26.982638 -277.490008) (xy 27.022787 -277.451299) (xy 27.068145 -277.418848)
			(xy 27.117745 -277.393347) (xy 27.170529 -277.37534) (xy 27.225372 -277.36521) (xy 27.281106 -277.363173)
			(xy 27.336543 -277.369273) (xy 27.3905 -277.383379) (xy 27.441829 -277.405191) (xy 27.489435 -277.434245)
			(xy 27.512404 -277.45336) (xy 29.519874 -277.45336) (xy 29.519874 -277.36646) (xy 29.527892 -277.279931)
			(xy 29.54386 -277.194511) (xy 29.567641 -277.110929) (xy 29.599033 -277.029897) (xy 29.637767 -276.952108)
			(xy 29.683514 -276.878224) (xy 29.735883 -276.808877) (xy 29.794427 -276.744657) (xy 29.858647 -276.686113)
			(xy 29.927994 -276.633744) (xy 30.001878 -276.587997) (xy 30.079667 -276.549263) (xy 30.160699 -276.517871)
			(xy 30.244281 -276.49409) (xy 30.329701 -276.478122) (xy 30.41623 -276.470104) (xy 30.50313 -276.470104)
			(xy 30.589659 -276.478122) (xy 30.675079 -276.49409) (xy 30.758661 -276.517871) (xy 30.839693 -276.549263)
			(xy 30.917482 -276.587997) (xy 30.991366 -276.633744) (xy 31.060713 -276.686113) (xy 31.124933 -276.744657)
			(xy 31.183477 -276.808877) (xy 31.235846 -276.878224) (xy 31.281593 -276.952108) (xy 31.320327 -277.029897)
			(xy 31.351719 -277.110929) (xy 31.3755 -277.194511) (xy 31.391468 -277.279931) (xy 31.399486 -277.36646)
			(xy 31.399988 -277.40991) (xy 31.399486 -277.45336) (xy 34.599874 -277.45336) (xy 34.599874 -277.36646)
			(xy 34.607892 -277.279931) (xy 34.62386 -277.194511) (xy 34.647641 -277.110929) (xy 34.679033 -277.029897)
			(xy 34.717767 -276.952108) (xy 34.763514 -276.878224) (xy 34.815883 -276.808877) (xy 34.874427 -276.744657)
			(xy 34.938647 -276.686113) (xy 35.007994 -276.633744) (xy 35.081878 -276.587997) (xy 35.159667 -276.549263)
			(xy 35.240699 -276.517871) (xy 35.324281 -276.49409) (xy 35.409701 -276.478122) (xy 35.49623 -276.470104)
			(xy 35.58313 -276.470104) (xy 35.669659 -276.478122) (xy 35.755079 -276.49409) (xy 35.838661 -276.517871)
			(xy 35.919693 -276.549263) (xy 35.997482 -276.587997) (xy 36.071366 -276.633744) (xy 36.140713 -276.686113)
			(xy 36.204933 -276.744657) (xy 36.263477 -276.808877) (xy 36.315846 -276.878224) (xy 36.361593 -276.952108)
			(xy 36.400327 -277.029897) (xy 36.431719 -277.110929) (xy 36.4555 -277.194511) (xy 36.471468 -277.279931)
			(xy 36.479486 -277.36646) (xy 36.479988 -277.40991) (xy 36.479486 -277.45336) (xy 36.471468 -277.539889)
			(xy 36.4555 -277.625309) (xy 36.431719 -277.708891) (xy 36.400327 -277.789923) (xy 36.361593 -277.867712)
			(xy 36.315846 -277.941596) (xy 36.263477 -278.010943) (xy 36.204933 -278.075163) (xy 36.140713 -278.133707)
			(xy 36.071366 -278.186076) (xy 35.997482 -278.231823) (xy 35.919693 -278.270557) (xy 35.838661 -278.301949)
			(xy 35.755079 -278.32573) (xy 35.669659 -278.341698) (xy 35.58313 -278.349716) (xy 35.49623 -278.349716)
			(xy 35.409701 -278.341698) (xy 35.324281 -278.32573) (xy 35.240699 -278.301949) (xy 35.159667 -278.270557)
			(xy 35.081878 -278.231823) (xy 35.007994 -278.186076) (xy 34.938647 -278.133707) (xy 34.874427 -278.075163)
			(xy 34.815883 -278.010943) (xy 34.763514 -277.941596) (xy 34.717767 -277.867712) (xy 34.679033 -277.789923)
			(xy 34.647641 -277.708891) (xy 34.62386 -277.625309) (xy 34.607892 -277.539889) (xy 34.599874 -277.45336)
			(xy 31.399486 -277.45336) (xy 31.391468 -277.539889) (xy 31.3755 -277.625309) (xy 31.351719 -277.708891)
			(xy 31.320327 -277.789923) (xy 31.281593 -277.867712) (xy 31.235846 -277.941596) (xy 31.183477 -278.010943)
			(xy 31.124933 -278.075163) (xy 31.060713 -278.133707) (xy 30.991366 -278.186076) (xy 30.917482 -278.231823)
			(xy 30.839693 -278.270557) (xy 30.758661 -278.301949) (xy 30.675079 -278.32573) (xy 30.589659 -278.341698)
			(xy 30.50313 -278.349716) (xy 30.41623 -278.349716) (xy 30.329701 -278.341698) (xy 30.244281 -278.32573)
			(xy 30.160699 -278.301949) (xy 30.079667 -278.270557) (xy 30.001878 -278.231823) (xy 29.927994 -278.186076)
			(xy 29.858647 -278.133707) (xy 29.794427 -278.075163) (xy 29.735883 -278.010943) (xy 29.683514 -277.941596)
			(xy 29.637767 -277.867712) (xy 29.599033 -277.789923) (xy 29.567641 -277.708891) (xy 29.54386 -277.625309)
			(xy 29.527892 -277.539889) (xy 29.519874 -277.45336) (xy 27.512404 -277.45336) (xy 27.532303 -277.46992)
			(xy 27.56952 -277.511457) (xy 27.600293 -277.55797) (xy 27.623965 -277.608467) (xy 27.640033 -277.661874)
			(xy 27.648153 -277.71705) (xy 27.648662 -277.744936) (xy 27.648153 -277.772822) (xy 27.640033 -277.827998)
			(xy 27.623965 -277.881405) (xy 27.600293 -277.931902) (xy 27.56952 -277.978415) (xy 27.532303 -278.019952)
			(xy 27.489435 -278.055627) (xy 27.441829 -278.084681) (xy 27.3905 -278.106493) (xy 27.336543 -278.120599)
			(xy 27.281106 -278.126699) (xy 27.225372 -278.124662) (xy 27.170529 -278.114532) (xy 27.117745 -278.096525)
			(xy 27.068145 -278.071024) (xy 27.022787 -278.038573) (xy 26.982638 -277.999864) (xy 26.948552 -277.955721)
			(xy 26.921256 -277.907086) (xy 26.901333 -277.854995) (xy 26.889207 -277.800558) (xy 26.885136 -277.744936)
			(xy 24.724288 -277.744936) (xy 24.694181 -277.752807) (xy 24.638744 -277.758907) (xy 24.58301 -277.75687)
			(xy 24.528167 -277.74674) (xy 24.475383 -277.728733) (xy 24.425783 -277.703232) (xy 24.380425 -277.670781)
			(xy 24.340276 -277.632072) (xy 24.30619 -277.587929) (xy 24.278894 -277.539294) (xy 24.258971 -277.487203)
			(xy 24.246845 -277.432766) (xy 24.242774 -277.377144) (xy 11.192002 -277.377144) (xy 10.082784 -278.486362)
			(xy 24.67559 -278.486362) (xy 24.679661 -278.43074) (xy 24.691787 -278.376303) (xy 24.71171 -278.324212)
			(xy 24.739006 -278.275577) (xy 24.773092 -278.231434) (xy 24.813241 -278.192725) (xy 24.858599 -278.160274)
			(xy 24.908199 -278.134773) (xy 24.960983 -278.116766) (xy 25.015826 -278.106636) (xy 25.07156 -278.104599)
			(xy 25.126997 -278.110699) (xy 25.180954 -278.124805) (xy 25.232283 -278.146617) (xy 25.279889 -278.175671)
			(xy 25.322757 -278.211346) (xy 25.359974 -278.252883) (xy 25.390747 -278.299396) (xy 25.414419 -278.349893)
			(xy 25.430487 -278.4033) (xy 25.438607 -278.458476) (xy 25.439116 -278.486362) (xy 25.438607 -278.514248)
			(xy 25.430487 -278.569424) (xy 25.414419 -278.622831) (xy 25.390747 -278.673328) (xy 25.359974 -278.719841)
			(xy 25.322757 -278.761378) (xy 25.279889 -278.797053) (xy 25.232283 -278.826107) (xy 25.180954 -278.847919)
			(xy 25.126997 -278.862025) (xy 25.07156 -278.868125) (xy 25.015826 -278.866088) (xy 24.960983 -278.855958)
			(xy 24.908199 -278.837951) (xy 24.858599 -278.81245) (xy 24.813241 -278.779999) (xy 24.773092 -278.74129)
			(xy 24.739006 -278.697147) (xy 24.71171 -278.648512) (xy 24.691787 -278.596421) (xy 24.679661 -278.541984)
			(xy 24.67559 -278.486362) (xy 10.082784 -278.486362) (xy 9.113012 -279.456134) (xy 9.100423 -279.469546)
			(xy 9.082874 -279.501857) (xy 9.075295 -279.537836) (xy 9.076182 -279.55621) (xy 9.076944 -279.566624)
			(xy 9.077706 -279.57145) (xy 9.08271 -279.606578) (xy 9.085808 -279.677469) (xy 9.08099 -279.748263)
			(xy 9.068317 -279.818081) (xy 9.047945 -279.886052) (xy 9.020129 -279.951331) (xy 8.996374 -279.99336)
			(xy 29.519874 -279.99336) (xy 29.519874 -279.90646) (xy 29.527892 -279.819931) (xy 29.54386 -279.734511)
			(xy 29.567641 -279.650929) (xy 29.599033 -279.569897) (xy 29.637767 -279.492108) (xy 29.683514 -279.418224)
			(xy 29.735883 -279.348877) (xy 29.794427 -279.284657) (xy 29.858647 -279.226113) (xy 29.927994 -279.173744)
			(xy 30.001878 -279.127997) (xy 30.079667 -279.089263) (xy 30.160699 -279.057871) (xy 30.244281 -279.03409)
			(xy 30.329701 -279.018122) (xy 30.41623 -279.010104) (xy 30.50313 -279.010104) (xy 30.589659 -279.018122)
			(xy 30.675079 -279.03409) (xy 30.758661 -279.057871) (xy 30.839693 -279.089263) (xy 30.917482 -279.127997)
			(xy 30.991366 -279.173744) (xy 31.060713 -279.226113) (xy 31.124933 -279.284657) (xy 31.183477 -279.348877)
			(xy 31.235846 -279.418224) (xy 31.281593 -279.492108) (xy 31.320327 -279.569897) (xy 31.351719 -279.650929)
			(xy 31.3755 -279.734511) (xy 31.391468 -279.819931) (xy 31.399486 -279.90646) (xy 31.399988 -279.94991)
			(xy 31.399486 -279.99336) (xy 34.599874 -279.99336) (xy 34.599874 -279.90646) (xy 34.607892 -279.819931)
			(xy 34.62386 -279.734511) (xy 34.647641 -279.650929) (xy 34.679033 -279.569897) (xy 34.717767 -279.492108)
			(xy 34.763514 -279.418224) (xy 34.815883 -279.348877) (xy 34.874427 -279.284657) (xy 34.938647 -279.226113)
			(xy 35.007994 -279.173744) (xy 35.081878 -279.127997) (xy 35.159667 -279.089263) (xy 35.240699 -279.057871)
			(xy 35.324281 -279.03409) (xy 35.409701 -279.018122) (xy 35.49623 -279.010104) (xy 35.58313 -279.010104)
			(xy 35.669659 -279.018122) (xy 35.755079 -279.03409) (xy 35.838661 -279.057871) (xy 35.919693 -279.089263)
			(xy 35.997482 -279.127997) (xy 36.071366 -279.173744) (xy 36.140713 -279.226113) (xy 36.204933 -279.284657)
			(xy 36.263477 -279.348877) (xy 36.315846 -279.418224) (xy 36.361593 -279.492108) (xy 36.400327 -279.569897)
			(xy 36.431719 -279.650929) (xy 36.434833 -279.661874) (xy 39.458898 -279.661874) (xy 39.462969 -279.606252)
			(xy 39.475095 -279.551815) (xy 39.495018 -279.499724) (xy 39.522314 -279.451089) (xy 39.5564 -279.406946)
			(xy 39.596549 -279.368237) (xy 39.641907 -279.335786) (xy 39.691507 -279.310285) (xy 39.744291 -279.292278)
			(xy 39.799134 -279.282148) (xy 39.854868 -279.280111) (xy 39.910305 -279.286211) (xy 39.964262 -279.300317)
			(xy 40.015591 -279.322129) (xy 40.063197 -279.351183) (xy 40.106065 -279.386858) (xy 40.143282 -279.428395)
			(xy 40.174055 -279.474908) (xy 40.197727 -279.525405) (xy 40.213795 -279.578812) (xy 40.221915 -279.633988)
			(xy 40.222424 -279.661874) (xy 40.221915 -279.68976) (xy 40.213795 -279.744936) (xy 40.197727 -279.798343)
			(xy 40.174055 -279.84884) (xy 40.143282 -279.895353) (xy 40.106065 -279.93689) (xy 40.063197 -279.972565)
			(xy 40.015591 -280.001619) (xy 39.964262 -280.023431) (xy 39.910305 -280.037537) (xy 39.854868 -280.043637)
			(xy 39.799134 -280.0416) (xy 39.744291 -280.03147) (xy 39.691507 -280.013463) (xy 39.641907 -279.987962)
			(xy 39.596549 -279.955511) (xy 39.5564 -279.916802) (xy 39.522314 -279.872659) (xy 39.495018 -279.824024)
			(xy 39.475095 -279.771933) (xy 39.462969 -279.717496) (xy 39.458898 -279.661874) (xy 36.434833 -279.661874)
			(xy 36.4555 -279.734511) (xy 36.471468 -279.819931) (xy 36.479486 -279.90646) (xy 36.479988 -279.94991)
			(xy 36.479486 -279.99336) (xy 36.471468 -280.079889) (xy 36.4555 -280.165309) (xy 36.431719 -280.248891)
			(xy 36.400327 -280.329923) (xy 36.361593 -280.407712) (xy 36.315846 -280.481596) (xy 36.307455 -280.492708)
			(xy 88.481152 -280.492708) (xy 88.485223 -280.437086) (xy 88.497349 -280.382649) (xy 88.517272 -280.330558)
			(xy 88.544568 -280.281923) (xy 88.578654 -280.23778) (xy 88.618803 -280.199071) (xy 88.664161 -280.16662)
			(xy 88.713761 -280.141119) (xy 88.766545 -280.123112) (xy 88.821388 -280.112982) (xy 88.877122 -280.110945)
			(xy 88.932559 -280.117045) (xy 88.986516 -280.131151) (xy 89.037845 -280.152963) (xy 89.085451 -280.182017)
			(xy 89.128319 -280.217692) (xy 89.165536 -280.259229) (xy 89.196309 -280.305742) (xy 89.219981 -280.356239)
			(xy 89.236049 -280.409646) (xy 89.244169 -280.464822) (xy 89.244678 -280.492708) (xy 89.244169 -280.520594)
			(xy 89.236049 -280.57577) (xy 89.219981 -280.629177) (xy 89.196309 -280.679674) (xy 89.165536 -280.726187)
			(xy 89.128319 -280.767724) (xy 89.085451 -280.803399) (xy 89.037845 -280.832453) (xy 88.986516 -280.854265)
			(xy 88.932559 -280.868371) (xy 88.877122 -280.874471) (xy 88.821388 -280.872434) (xy 88.766545 -280.862304)
			(xy 88.713761 -280.844297) (xy 88.664161 -280.818796) (xy 88.618803 -280.786345) (xy 88.578654 -280.747636)
			(xy 88.544568 -280.703493) (xy 88.517272 -280.654858) (xy 88.497349 -280.602767) (xy 88.485223 -280.54833)
			(xy 88.481152 -280.492708) (xy 36.307455 -280.492708) (xy 36.263477 -280.550943) (xy 36.204933 -280.615163)
			(xy 36.140713 -280.673707) (xy 36.071366 -280.726076) (xy 35.997482 -280.771823) (xy 35.919693 -280.810557)
			(xy 35.838661 -280.841949) (xy 35.755079 -280.86573) (xy 35.669659 -280.881698) (xy 35.58313 -280.889716)
			(xy 35.49623 -280.889716) (xy 35.409701 -280.881698) (xy 35.324281 -280.86573) (xy 35.240699 -280.841949)
			(xy 35.159667 -280.810557) (xy 35.081878 -280.771823) (xy 35.007994 -280.726076) (xy 34.938647 -280.673707)
			(xy 34.874427 -280.615163) (xy 34.815883 -280.550943) (xy 34.763514 -280.481596) (xy 34.717767 -280.407712)
			(xy 34.679033 -280.329923) (xy 34.647641 -280.248891) (xy 34.62386 -280.165309) (xy 34.607892 -280.079889)
			(xy 34.599874 -279.99336) (xy 31.399486 -279.99336) (xy 31.391468 -280.079889) (xy 31.3755 -280.165309)
			(xy 31.351719 -280.248891) (xy 31.320327 -280.329923) (xy 31.281593 -280.407712) (xy 31.235846 -280.481596)
			(xy 31.183477 -280.550943) (xy 31.124933 -280.615163) (xy 31.060713 -280.673707) (xy 30.991366 -280.726076)
			(xy 30.917482 -280.771823) (xy 30.839693 -280.810557) (xy 30.758661 -280.841949) (xy 30.675079 -280.86573)
			(xy 30.589659 -280.881698) (xy 30.50313 -280.889716) (xy 30.41623 -280.889716) (xy 30.329701 -280.881698)
			(xy 30.244281 -280.86573) (xy 30.160699 -280.841949) (xy 30.079667 -280.810557) (xy 30.001878 -280.771823)
			(xy 29.927994 -280.726076) (xy 29.858647 -280.673707) (xy 29.794427 -280.615163) (xy 29.735883 -280.550943)
			(xy 29.683514 -280.481596) (xy 29.637767 -280.407712) (xy 29.599033 -280.329923) (xy 29.567641 -280.248891)
			(xy 29.54386 -280.165309) (xy 29.527892 -280.079889) (xy 29.519874 -279.99336) (xy 8.996374 -279.99336)
			(xy 8.985214 -280.013106) (xy 8.943636 -280.070606) (xy 8.895912 -280.123118) (xy 8.842635 -280.169987)
			(xy 8.784469 -280.210629) (xy 8.722138 -280.24454) (xy 8.656417 -280.271296) (xy 8.588125 -280.290565)
			(xy 8.518112 -280.302108) (xy 8.447249 -280.30578) (xy 8.376417 -280.301535) (xy 8.306499 -280.289427)
			(xy 8.238366 -280.269606) (xy 8.172864 -280.242319) (xy 8.110809 -280.207906) (xy 8.052973 -280.166794)
			(xy 8.000077 -280.119496) (xy 7.952779 -280.0666) (xy 7.911667 -280.008765) (xy 7.877253 -279.946711)
			(xy 7.849966 -279.881209) (xy 7.830144 -279.813075) (xy 7.818036 -279.743157) (xy 7.813791 -279.672326)
			(xy 7.817462 -279.601463) (xy 7.829004 -279.531449) (xy 7.848272 -279.463157) (xy 7.875028 -279.397436)
			(xy 7.908938 -279.335105) (xy 7.949581 -279.276939) (xy 7.996449 -279.223662) (xy 8.04896 -279.175937)
			(xy 8.106461 -279.134358) (xy 8.168235 -279.099443) (xy 8.233514 -279.071627) (xy 8.301485 -279.051254)
			(xy 8.371302 -279.03858) (xy 8.442097 -279.033762) (xy 8.512987 -279.03686) (xy 8.548116 -279.04186)
			(xy 8.552942 -279.042622) (xy 8.563356 -279.043384) (xy 8.581727 -279.044244) (xy 8.617696 -279.036643)
			(xy 8.650025 -279.019141) (xy 8.663432 -279.006554) (xy 10.526522 -277.143464) (xy 10.541437 -277.126761)
			(xy 10.565749 -277.089161) (xy 10.583099 -277.047884) (xy 10.592951 -277.004206) (xy 10.595001 -276.959477)
			(xy 10.589185 -276.915081) (xy 10.575682 -276.87239) (xy 10.554911 -276.832724) (xy 10.527513 -276.797309)
			(xy 10.494336 -276.76724) (xy 10.456405 -276.743447) (xy 10.414893 -276.726666) (xy 10.371083 -276.717415)
			(xy 10.348722 -276.716236) (xy 8.905494 -276.716236) (xy 8.888766 -276.716703) (xy 8.856444 -276.725333)
			(xy 8.827481 -276.742075) (xy 8.815324 -276.753574) (xy 8.798306 -276.770846) (xy 8.796274 -276.772878)
			(xy 8.78111 -276.788683) (xy 8.755905 -276.8245) (xy 8.737219 -276.86411) (xy 8.725607 -276.906339)
			(xy 8.721412 -276.949935) (xy 8.724761 -276.993603) (xy 8.735552 -277.036049) (xy 8.753467 -277.076015)
			(xy 8.777973 -277.112313) (xy 8.808344 -277.143869) (xy 8.825738 -277.15718) (xy 8.853956 -277.178473)
			(xy 8.905972 -277.226349) (xy 8.952355 -277.279701) (xy 8.992531 -277.33787) (xy 9.026004 -277.400137)
			(xy 9.052362 -277.465734) (xy 9.071279 -277.533851) (xy 9.08252 -277.603646) (xy 9.085948 -277.674258)
			(xy 9.08152 -277.744814) (xy 9.06929 -277.814443) (xy 9.04941 -277.882285) (xy 9.022125 -277.947502)
			(xy 8.987773 -278.009289) (xy 8.946776 -278.066882) (xy 8.899642 -278.119572) (xy 8.846953 -278.166706)
			(xy 8.78936 -278.207702) (xy 8.727573 -278.242055) (xy 8.662356 -278.26934) (xy 8.594514 -278.28922)
			(xy 8.524885 -278.30145) (xy 8.454329 -278.305878) (xy 8.383717 -278.302451) (xy 8.313922 -278.291209)
			(xy 8.245805 -278.272293) (xy 8.180208 -278.245935) (xy 8.11794 -278.212461) (xy 8.059771 -278.172285)
			(xy 8.006419 -278.125903) (xy 7.958543 -278.073887) (xy 7.937246 -278.045672) (xy 7.923927 -278.028286)
			(xy 7.892359 -277.997935) (xy 7.856055 -277.973444) (xy 7.81609 -277.95554) (xy 7.773647 -277.944751)
			(xy 7.729983 -277.941398) (xy 7.686391 -277.94558) (xy 7.64416 -277.957173) (xy 7.604543 -277.975833)
			(xy 7.56871 -278.001009) (xy 7.552944 -278.016208) (xy 7.112508 -278.456644) (xy 7.102136 -278.467572)
			(xy 7.086388 -278.49325) (xy 7.077135 -278.521915) (xy 7.074896 -278.551954) (xy 7.076948 -278.56688)
			(xy 7.082218 -278.602072) (xy 7.085821 -278.673142) (xy 7.081461 -278.74417) (xy 7.069193 -278.814266)
			(xy 7.049172 -278.882553) (xy 7.021648 -278.948176) (xy 6.986965 -279.010313) (xy 6.945558 -279.068187)
			(xy 6.897945 -279.121073) (xy 6.844721 -279.168309) (xy 6.786554 -279.209304) (xy 6.724172 -279.243544)
			(xy 6.658355 -279.270601) (xy 6.589927 -279.290135) (xy 6.519746 -279.301904) (xy 6.448689 -279.305759)
			(xy 6.377646 -279.301651) (xy 6.307506 -279.289633) (xy 6.239149 -279.269855) (xy 6.173428 -279.242564)
			(xy 6.111168 -279.208102) (xy 6.053147 -279.166901) (xy 6.000093 -279.119476) (xy 5.952668 -279.066421)
			(xy 5.911467 -279.0084) (xy 5.877005 -278.94614) (xy 5.849714 -278.880419) (xy 5.829936 -278.812061)
			(xy 5.817919 -278.741922) (xy 5.813811 -278.670879) (xy 5.817666 -278.599822) (xy 5.829435 -278.529641)
			(xy 5.84897 -278.461213) (xy 5.876027 -278.395396) (xy 5.910268 -278.333014) (xy 5.951262 -278.274847)
			(xy 5.998499 -278.221624) (xy 6.051385 -278.174011) (xy 6.109259 -278.132604) (xy 6.171396 -278.097921)
			(xy 6.237019 -278.070397) (xy 6.305306 -278.050376) (xy 6.375403 -278.038109) (xy 6.44643 -278.033749)
			(xy 6.517501 -278.037352) (xy 6.552692 -278.042624) (xy 6.567619 -278.044607) (xy 6.597638 -278.042325)
			(xy 6.626291 -278.033091) (xy 6.651994 -278.017416) (xy 6.662928 -278.007064) (xy 8.103362 -276.56663)
			(xy 8.118525 -276.550824) (xy 8.143728 -276.515005) (xy 8.162412 -276.475394) (xy 8.174024 -276.433165)
			(xy 8.178219 -276.38957) (xy 8.174872 -276.345901) (xy 8.164082 -276.303455) (xy 8.146171 -276.263488)
			(xy 8.121668 -276.227187) (xy 8.0913 -276.195629) (xy 8.073898 -276.182328) (xy 8.048056 -276.162877)
			(xy 8.000052 -276.119523) (xy 7.9567 -276.071516) (xy 7.937246 -276.045676) (xy 7.923927 -276.02829)
			(xy 7.892359 -275.997938) (xy 7.856055 -275.973447) (xy 7.81609 -275.955542) (xy 7.773647 -275.944754)
			(xy 7.729983 -275.941401) (xy 7.68639 -275.945582) (xy 7.64416 -275.957175) (xy 7.604542 -275.975836)
			(xy 7.56871 -276.001012) (xy 7.552944 -276.016212) (xy 7.112508 -276.456648) (xy 7.102136 -276.467577)
			(xy 7.086389 -276.493254) (xy 7.077137 -276.521919) (xy 7.074899 -276.551958) (xy 7.076948 -276.566884)
			(xy 7.082212 -276.602025) (xy 7.085817 -276.672992) (xy 7.081484 -276.743919) (xy 7.069266 -276.81392)
			(xy 7.049315 -276.88212) (xy 7.021881 -276.94767) (xy 6.987306 -277.00975) (xy 6.946022 -277.067586)
			(xy 6.898544 -277.120456) (xy 6.845464 -277.167699) (xy 6.787446 -277.208727) (xy 6.725213 -277.243026)
			(xy 6.659543 -277.27017) (xy 6.591254 -277.289818) (xy 6.5212 -277.301726) (xy 6.450255 -277.305745)
			(xy 6.379304 -277.301825) (xy 6.309234 -277.290015) (xy 6.240918 -277.270463) (xy 6.175209 -277.243411)
			(xy 6.112929 -277.209199) (xy 6.054853 -277.168253) (xy 6.001707 -277.121083) (xy 5.954155 -277.06828)
			(xy 5.91279 -277.010502) (xy 5.878129 -276.94847) (xy 5.850603 -276.882959) (xy 5.830557 -276.814786)
			(xy 5.818241 -276.744803) (xy 5.813808 -276.673882) (xy 5.817314 -276.60291) (xy 5.828716 -276.532772)
			(xy 5.84787 -276.464343) (xy 5.874538 -276.398478) (xy 5.908387 -276.335999) (xy 5.948994 -276.277686)
			(xy 5.995852 -276.224266) (xy 6.048377 -276.176407) (xy 6.105913 -276.134706) (xy 6.167742 -276.099683)
			(xy 6.233092 -276.071776) (xy 6.301147 -276.051333) (xy 6.371057 -276.038609) (xy 6.441951 -276.033763)
			(xy 6.512942 -276.036856) (xy 6.54812 -276.041866) (xy 6.552946 -276.042628) (xy 6.56336 -276.04339)
			(xy 6.581731 -276.044249) (xy 6.617699 -276.036648) (xy 6.650028 -276.019146) (xy 6.663436 -276.00656)
			(xy 7.255256 -275.41474) (xy 7.270171 -275.398037) (xy 7.294483 -275.360435) (xy 7.311833 -275.319157)
			(xy 7.321686 -275.275478) (xy 7.323735 -275.230748) (xy 7.317919 -275.186351) (xy 7.304417 -275.143658)
			(xy 7.283646 -275.103991) (xy 7.256249 -275.068575) (xy 7.223072 -275.038504) (xy 7.185141 -275.014709)
			(xy 7.143629 -274.997926) (xy 7.099819 -274.988673) (xy 7.077456 -274.987512) (xy 7.069328 -274.987512)
			(xy 7.054237 -274.987914) (xy 7.024889 -274.994952) (xy 6.998016 -275.008688) (xy 6.975122 -275.028354)
			(xy 6.96595 -275.040344) (xy 6.96595 -275.040598) (xy 6.940386 -275.074956) (xy 6.881507 -275.137142)
			(xy 6.848602 -275.16455) (xy 6.821028 -275.186175) (xy 6.761957 -275.223881) (xy 6.699095 -275.254859)
			(xy 6.633208 -275.278732) (xy 6.565093 -275.295212) (xy 6.49558 -275.304097) (xy 6.42551 -275.305281)
			(xy 6.355736 -275.298748) (xy 6.287104 -275.284578) (xy 6.220448 -275.262944) (xy 6.156576 -275.234107)
			(xy 6.096265 -275.198418) (xy 6.040247 -275.15631) (xy 5.989201 -275.108294) (xy 5.943748 -275.054954)
			(xy 5.90444 -274.996937) (xy 5.871753 -274.934947) (xy 5.846085 -274.869738) (xy 5.827748 -274.8021)
			(xy 5.816963 -274.732855) (xy 5.813862 -274.662845) (xy 5.818482 -274.592918) (xy 5.830768 -274.523924)
			(xy 5.840222 -274.49018) (xy 5.845418 -274.467632) (xy 5.848493 -274.421469) (xy 5.843163 -274.375511)
			(xy 5.829602 -274.331277) (xy 5.808259 -274.290228) (xy 5.77984 -274.253719) (xy 5.745282 -274.222958)
			(xy 5.705727 -274.198958) (xy 5.662482 -274.182515) (xy 5.616975 -274.174169) (xy 5.593842 -274.173696)
			(xy 4.895596 -274.173696) (xy 4.61264 -274.456652) (xy 4.602266 -274.467579) (xy 4.586516 -274.493257)
			(xy 4.577262 -274.521923) (xy 4.575025 -274.551962) (xy 4.57708 -274.566888) (xy 4.577842 -274.571968)
			(xy 4.582792 -274.606892) (xy 4.585852 -274.677366) (xy 4.58109 -274.747745) (xy 4.568564 -274.817164)
			(xy 4.548429 -274.884769) (xy 4.520931 -274.949729) (xy 4.48641 -275.011245) (xy 4.44529 -275.06856)
			(xy 4.398076 -275.12097) (xy 4.345349 -275.167829) (xy 4.287758 -275.208562) (xy 4.226011 -275.242667)
			(xy 4.160867 -275.269726) (xy 4.093128 -275.289405) (xy 4.023626 -275.301462) (xy 3.953216 -275.305749)
			(xy 3.882765 -275.302214) (xy 3.813138 -275.2909) (xy 3.745192 -275.271945) (xy 3.679763 -275.245584)
			(xy 3.617655 -275.212139) (xy 3.559632 -275.172024) (xy 3.506408 -275.12573) (xy 3.458637 -275.073828)
			(xy 3.437382 -275.045678) (xy 3.424063 -275.028297) (xy 3.392496 -274.997955) (xy 3.356195 -274.973474)
			(xy 3.316235 -274.955579) (xy 3.273798 -274.944799) (xy 3.230141 -274.941454) (xy 3.186557 -274.945642)
			(xy 3.144337 -274.95724) (xy 3.10473 -274.975904) (xy 3.068908 -275.001082) (xy 3.05308 -275.016214)
			(xy 2.612644 -275.45665) (xy 2.602269 -275.467577) (xy 2.586519 -275.493254) (xy 2.577264 -275.52192)
			(xy 2.575026 -275.55196) (xy 2.577084 -275.566886) (xy 2.582361 -275.602145) (xy 2.585952 -275.673351)
			(xy 2.581552 -275.744512) (xy 2.569216 -275.814733) (xy 2.549097 -275.883133) (xy 2.52145 -275.948851)
			(xy 2.486622 -276.011062) (xy 2.44505 -276.068984) (xy 2.397257 -276.12189) (xy 2.343843 -276.169115)
			(xy 2.285479 -276.210064) (xy 2.222899 -276.244225) (xy 2.156888 -276.271167) (xy 2.088278 -276.290552)
			(xy 2.017928 -276.302136) (xy 1.946725 -276.305774) (xy 1.875561 -276.301421) (xy 1.805332 -276.28913)
			(xy 1.736919 -276.269057) (xy 1.671183 -276.241453) (xy 1.639824 -276.224492) (xy 1.620357 -276.215008)
			(xy 1.579032 -276.202079) (xy 1.536113 -276.196345) (xy 1.492844 -276.197971) (xy 1.450477 -276.206911)
			(xy 1.410239 -276.222904) (xy 1.373295 -276.245489) (xy 1.340716 -276.274011) (xy 1.313445 -276.307644)
			(xy 1.292271 -276.345414) (xy 1.277808 -276.386227) (xy 1.270475 -276.428902) (xy 1.27 -276.450552)
			(xy 1.27 -276.705415) (xy 3.314946 -276.705415) (xy 3.314946 -276.634093) (xy 3.322932 -276.563219)
			(xy 3.338802 -276.493684) (xy 3.362359 -276.426364) (xy 3.393304 -276.362105) (xy 3.43125 -276.301714)
			(xy 3.475719 -276.245952) (xy 3.526152 -276.195519) (xy 3.581914 -276.15105) (xy 3.642305 -276.113104)
			(xy 3.706564 -276.082159) (xy 3.773884 -276.058602) (xy 3.843419 -276.042732) (xy 3.914293 -276.034746)
			(xy 3.985615 -276.034746) (xy 4.056489 -276.042732) (xy 4.126024 -276.058602) (xy 4.193344 -276.082159)
			(xy 4.257603 -276.113104) (xy 4.317994 -276.15105) (xy 4.373756 -276.195519) (xy 4.424189 -276.245952)
			(xy 4.468658 -276.301714) (xy 4.506604 -276.362105) (xy 4.537549 -276.426364) (xy 4.561106 -276.493684)
			(xy 4.576976 -276.563219) (xy 4.584962 -276.634093) (xy 4.585462 -276.669754) (xy 4.584962 -276.705415)
			(xy 4.576976 -276.776289) (xy 4.561106 -276.845824) (xy 4.537549 -276.913144) (xy 4.506604 -276.977403)
			(xy 4.468658 -277.037794) (xy 4.424189 -277.093556) (xy 4.373756 -277.143989) (xy 4.317994 -277.188458)
			(xy 4.257603 -277.226404) (xy 4.193344 -277.257349) (xy 4.126024 -277.280906) (xy 4.056489 -277.296776)
			(xy 3.985615 -277.304762) (xy 3.914293 -277.304762) (xy 3.843419 -277.296776) (xy 3.773884 -277.280906)
			(xy 3.706564 -277.257349) (xy 3.642305 -277.226404) (xy 3.581914 -277.188458) (xy 3.526152 -277.143989)
			(xy 3.475719 -277.093556) (xy 3.43125 -277.037794) (xy 3.393304 -276.977403) (xy 3.362359 -276.913144)
			(xy 3.338802 -276.845824) (xy 3.322932 -276.776289) (xy 3.314946 -276.705415) (xy 1.27 -276.705415)
			(xy 1.27 -276.888956) (xy 1.270438 -276.910606) (xy 1.27778 -276.953279) (xy 1.29225 -276.99409)
			(xy 1.313429 -277.031857) (xy 1.340704 -277.065487) (xy 1.373286 -277.094006) (xy 1.410231 -277.116588)
			(xy 1.45047 -277.132581) (xy 1.492837 -277.14152) (xy 1.536106 -277.143147) (xy 1.579026 -277.137415)
			(xy 1.620352 -277.12449) (xy 1.639824 -277.115016) (xy 1.671264 -277.097996) (xy 1.737191 -277.070331)
			(xy 1.805806 -277.050239) (xy 1.876242 -277.037975) (xy 1.94761 -277.033693) (xy 2.019007 -277.037447)
			(xy 2.089532 -277.049191) (xy 2.158294 -277.068775) (xy 2.224423 -277.095952) (xy 2.287084 -277.130379)
			(xy 2.345487 -277.171621) (xy 2.398891 -277.219156) (xy 2.446624 -277.272385) (xy 2.488081 -277.330634)
			(xy 2.52274 -277.393168) (xy 2.550161 -277.459196) (xy 2.569999 -277.527885) (xy 2.582003 -277.598366)
			(xy 2.586021 -277.669749) (xy 2.582003 -277.741132) (xy 2.569999 -277.811613) (xy 2.550162 -277.880302)
			(xy 2.52274 -277.94633) (xy 2.488082 -278.008864) (xy 2.446625 -278.067114) (xy 2.398893 -278.120343)
			(xy 2.345488 -278.167878) (xy 2.287086 -278.20912) (xy 2.224425 -278.243547) (xy 2.158295 -278.270725)
			(xy 2.089534 -278.290309) (xy 2.019009 -278.302052) (xy 1.947612 -278.305807) (xy 1.876244 -278.301525)
			(xy 1.805808 -278.289261) (xy 1.737193 -278.26917) (xy 1.671266 -278.241505) (xy 1.639824 -278.224488)
			(xy 1.620357 -278.215004) (xy 1.579032 -278.202076) (xy 1.536113 -278.196342) (xy 1.492843 -278.197968)
			(xy 1.450476 -278.206907) (xy 1.410238 -278.222901) (xy 1.373294 -278.245486) (xy 1.340715 -278.274007)
			(xy 1.313443 -278.30764) (xy 1.292269 -278.34541) (xy 1.277806 -278.386223) (xy 1.270472 -278.428898)
			(xy 1.27 -278.450548) (xy 1.27 -278.705411) (xy 3.314946 -278.705411) (xy 3.314946 -278.634089) (xy 3.322932 -278.563215)
			(xy 3.338802 -278.49368) (xy 3.362359 -278.42636) (xy 3.393304 -278.362101) (xy 3.43125 -278.30171)
			(xy 3.475719 -278.245948) (xy 3.526152 -278.195515) (xy 3.581914 -278.151046) (xy 3.642305 -278.1131)
			(xy 3.706564 -278.082155) (xy 3.773884 -278.058598) (xy 3.843419 -278.042728) (xy 3.914293 -278.034742)
			(xy 3.985615 -278.034742) (xy 4.056489 -278.042728) (xy 4.126024 -278.058598) (xy 4.193344 -278.082155)
			(xy 4.257603 -278.1131) (xy 4.317994 -278.151046) (xy 4.373756 -278.195515) (xy 4.424189 -278.245948)
			(xy 4.468658 -278.30171) (xy 4.506604 -278.362101) (xy 4.537549 -278.42636) (xy 4.561106 -278.49368)
			(xy 4.576976 -278.563215) (xy 4.584962 -278.634089) (xy 4.585462 -278.66975) (xy 4.584962 -278.705411)
			(xy 4.576976 -278.776285) (xy 4.561106 -278.84582) (xy 4.537549 -278.91314) (xy 4.506604 -278.977399)
			(xy 4.468658 -279.03779) (xy 4.424189 -279.093552) (xy 4.373756 -279.143985) (xy 4.317994 -279.188454)
			(xy 4.257603 -279.2264) (xy 4.193344 -279.257345) (xy 4.126024 -279.280902) (xy 4.056489 -279.296772)
			(xy 3.985615 -279.304758) (xy 3.914293 -279.304758) (xy 3.843419 -279.296772) (xy 3.773884 -279.280902)
			(xy 3.706564 -279.257345) (xy 3.642305 -279.2264) (xy 3.581914 -279.188454) (xy 3.526152 -279.143985)
			(xy 3.475719 -279.093552) (xy 3.43125 -279.03779) (xy 3.393304 -278.977399) (xy 3.362359 -278.91314)
			(xy 3.338802 -278.84582) (xy 3.322932 -278.776285) (xy 3.314946 -278.705411) (xy 1.27 -278.705411)
			(xy 1.27 -278.888952) (xy 1.270438 -278.910602) (xy 1.277779 -278.953276) (xy 1.292249 -278.994088)
			(xy 1.313428 -279.031855) (xy 1.340703 -279.065486) (xy 1.373285 -279.094005) (xy 1.41023 -279.116588)
			(xy 1.450469 -279.132581) (xy 1.492837 -279.14152) (xy 1.536107 -279.143147) (xy 1.579027 -279.137415)
			(xy 1.620353 -279.124489) (xy 1.639824 -279.115012) (xy 1.671264 -279.097992) (xy 1.737191 -279.070327)
			(xy 1.805807 -279.050235) (xy 1.876243 -279.037971) (xy 1.947612 -279.033689) (xy 2.019009 -279.037444)
			(xy 2.089535 -279.049188) (xy 2.158297 -279.068772) (xy 2.224426 -279.09595) (xy 2.287088 -279.130377)
			(xy 2.34549 -279.171619) (xy 2.398895 -279.219155) (xy 2.446628 -279.272384) (xy 2.488085 -279.330634)
			(xy 2.522744 -279.393168) (xy 2.550165 -279.459197) (xy 2.570003 -279.527886) (xy 2.582007 -279.598368)
			(xy 2.586025 -279.669751) (xy 2.582007 -279.741134) (xy 2.570002 -279.811616) (xy 2.550164 -279.880305)
			(xy 2.522743 -279.946334) (xy 2.488084 -280.008868) (xy 2.446627 -280.067117) (xy 2.398894 -280.120346)
			(xy 2.345489 -280.167882) (xy 2.287086 -280.209124) (xy 2.224424 -280.243551) (xy 2.158295 -280.270729)
			(xy 2.089533 -280.290313) (xy 2.019007 -280.302056) (xy 1.94761 -280.305811) (xy 1.876242 -280.301529)
			(xy 1.805805 -280.289264) (xy 1.73719 -280.269172) (xy 1.671263 -280.241507) (xy 1.639824 -280.224484)
			(xy 1.620357 -280.215) (xy 1.579031 -280.202072) (xy 1.536112 -280.196338) (xy 1.492843 -280.197964)
			(xy 1.450475 -280.206904) (xy 1.410237 -280.222897) (xy 1.373293 -280.245482) (xy 1.340713 -280.274004)
			(xy 1.313441 -280.307636) (xy 1.292267 -280.345406) (xy 1.277803 -280.386219) (xy 1.270469 -280.428894)
			(xy 1.27 -280.450544) (xy 1.27 -280.705407) (xy 3.314946 -280.705407) (xy 3.314946 -280.634085) (xy 3.322932 -280.563211)
			(xy 3.338802 -280.493676) (xy 3.362359 -280.426356) (xy 3.393304 -280.362097) (xy 3.43125 -280.301706)
			(xy 3.475719 -280.245944) (xy 3.526152 -280.195511) (xy 3.581914 -280.151042) (xy 3.642305 -280.113096)
			(xy 3.706564 -280.082151) (xy 3.773884 -280.058594) (xy 3.843419 -280.042724) (xy 3.914293 -280.034738)
			(xy 3.985615 -280.034738) (xy 4.056489 -280.042724) (xy 4.126024 -280.058594) (xy 4.193344 -280.082151)
			(xy 4.257603 -280.113096) (xy 4.317994 -280.151042) (xy 4.373756 -280.195511) (xy 4.424189 -280.245944)
			(xy 4.468658 -280.301706) (xy 4.506604 -280.362097) (xy 4.537549 -280.426356) (xy 4.561106 -280.493676)
			(xy 4.576976 -280.563211) (xy 4.584962 -280.634085) (xy 4.585462 -280.669746) (xy 4.584962 -280.705407)
			(xy 5.814814 -280.705407) (xy 5.814814 -280.634085) (xy 5.8228 -280.563211) (xy 5.83867 -280.493676)
			(xy 5.862227 -280.426356) (xy 5.893172 -280.362097) (xy 5.931118 -280.301706) (xy 5.975587 -280.245944)
			(xy 6.02602 -280.195511) (xy 6.081782 -280.151042) (xy 6.142173 -280.113096) (xy 6.206432 -280.082151)
			(xy 6.273752 -280.058594) (xy 6.343287 -280.042724) (xy 6.414161 -280.034738) (xy 6.485483 -280.034738)
			(xy 6.556357 -280.042724) (xy 6.625892 -280.058594) (xy 6.693212 -280.082151) (xy 6.757471 -280.113096)
			(xy 6.817862 -280.151042) (xy 6.873624 -280.195511) (xy 6.924057 -280.245944) (xy 6.968526 -280.301706)
			(xy 7.006472 -280.362097) (xy 7.037417 -280.426356) (xy 7.060974 -280.493676) (xy 7.076844 -280.563211)
			(xy 7.08483 -280.634085) (xy 7.08533 -280.669746) (xy 7.08483 -280.705407) (xy 7.076844 -280.776281)
			(xy 7.060974 -280.845816) (xy 7.054947 -280.86304) (xy 27.247848 -280.86304) (xy 27.251919 -280.807418)
			(xy 27.264045 -280.752981) (xy 27.283968 -280.70089) (xy 27.311264 -280.652255) (xy 27.34535 -280.608112)
			(xy 27.385499 -280.569403) (xy 27.430857 -280.536952) (xy 27.480457 -280.511451) (xy 27.533241 -280.493444)
			(xy 27.588084 -280.483314) (xy 27.643818 -280.481277) (xy 27.699255 -280.487377) (xy 27.753212 -280.501483)
			(xy 27.804541 -280.523295) (xy 27.852147 -280.552349) (xy 27.895015 -280.588024) (xy 27.932232 -280.629561)
			(xy 27.963005 -280.676074) (xy 27.986677 -280.726571) (xy 28.002745 -280.779978) (xy 28.010865 -280.835154)
			(xy 28.011374 -280.86304) (xy 28.010865 -280.890926) (xy 28.002745 -280.946102) (xy 27.986677 -280.999509)
			(xy 27.963005 -281.050006) (xy 27.932232 -281.096519) (xy 27.895015 -281.138056) (xy 27.891884 -281.140662)
			(xy 40.801542 -281.140662) (xy 40.805613 -281.08504) (xy 40.817739 -281.030603) (xy 40.837662 -280.978512)
			(xy 40.864958 -280.929877) (xy 40.899044 -280.885734) (xy 40.939193 -280.847025) (xy 40.984551 -280.814574)
			(xy 41.034151 -280.789073) (xy 41.086935 -280.771066) (xy 41.141778 -280.760936) (xy 41.197512 -280.758899)
			(xy 41.252949 -280.764999) (xy 41.306906 -280.779105) (xy 41.358235 -280.800917) (xy 41.405841 -280.829971)
			(xy 41.448709 -280.865646) (xy 41.485926 -280.907183) (xy 41.516699 -280.953696) (xy 41.540371 -281.004193)
			(xy 41.556439 -281.0576) (xy 41.564559 -281.112776) (xy 41.564813 -281.126692) (xy 87.019128 -281.126692)
			(xy 87.023199 -281.07107) (xy 87.035325 -281.016633) (xy 87.055248 -280.964542) (xy 87.082544 -280.915907)
			(xy 87.11663 -280.871764) (xy 87.156779 -280.833055) (xy 87.202137 -280.800604) (xy 87.251737 -280.775103)
			(xy 87.304521 -280.757096) (xy 87.359364 -280.746966) (xy 87.415098 -280.744929) (xy 87.470535 -280.751029)
			(xy 87.524492 -280.765135) (xy 87.575821 -280.786947) (xy 87.623427 -280.816001) (xy 87.666295 -280.851676)
			(xy 87.703512 -280.893213) (xy 87.734285 -280.939726) (xy 87.757957 -280.990223) (xy 87.774025 -281.04363)
			(xy 87.782145 -281.098806) (xy 87.782654 -281.126692) (xy 87.782145 -281.154578) (xy 87.774025 -281.209754)
			(xy 87.757957 -281.263161) (xy 87.734285 -281.313658) (xy 87.703512 -281.360171) (xy 87.666295 -281.401708)
			(xy 87.623427 -281.437383) (xy 87.575821 -281.466437) (xy 87.524492 -281.488249) (xy 87.470535 -281.502355)
			(xy 87.415098 -281.508455) (xy 87.359364 -281.506418) (xy 87.304521 -281.496288) (xy 87.251737 -281.478281)
			(xy 87.202137 -281.45278) (xy 87.156779 -281.420329) (xy 87.11663 -281.38162) (xy 87.082544 -281.337477)
			(xy 87.055248 -281.288842) (xy 87.035325 -281.236751) (xy 87.023199 -281.182314) (xy 87.019128 -281.126692)
			(xy 41.564813 -281.126692) (xy 41.565068 -281.140662) (xy 41.564559 -281.168548) (xy 41.556439 -281.223724)
			(xy 41.540371 -281.277131) (xy 41.516699 -281.327628) (xy 41.485926 -281.374141) (xy 41.448709 -281.415678)
			(xy 41.405841 -281.451353) (xy 41.358235 -281.480407) (xy 41.306906 -281.502219) (xy 41.252949 -281.516325)
			(xy 41.197512 -281.522425) (xy 41.141778 -281.520388) (xy 41.086935 -281.510258) (xy 41.034151 -281.492251)
			(xy 40.984551 -281.46675) (xy 40.939193 -281.434299) (xy 40.899044 -281.39559) (xy 40.864958 -281.351447)
			(xy 40.837662 -281.302812) (xy 40.817739 -281.250721) (xy 40.805613 -281.196284) (xy 40.801542 -281.140662)
			(xy 27.891884 -281.140662) (xy 27.852147 -281.173731) (xy 27.804541 -281.202785) (xy 27.753212 -281.224597)
			(xy 27.699255 -281.238703) (xy 27.643818 -281.244803) (xy 27.588084 -281.242766) (xy 27.533241 -281.232636)
			(xy 27.480457 -281.214629) (xy 27.430857 -281.189128) (xy 27.385499 -281.156677) (xy 27.34535 -281.117968)
			(xy 27.311264 -281.073825) (xy 27.283968 -281.02519) (xy 27.264045 -280.973099) (xy 27.251919 -280.918662)
			(xy 27.247848 -280.86304) (xy 7.054947 -280.86304) (xy 7.037417 -280.913136) (xy 7.006472 -280.977395)
			(xy 6.968526 -281.037786) (xy 6.924057 -281.093548) (xy 6.873624 -281.143981) (xy 6.817862 -281.18845)
			(xy 6.757471 -281.226396) (xy 6.693212 -281.257341) (xy 6.625892 -281.280898) (xy 6.556357 -281.296768)
			(xy 6.485483 -281.304754) (xy 6.414161 -281.304754) (xy 6.343287 -281.296768) (xy 6.273752 -281.280898)
			(xy 6.206432 -281.257341) (xy 6.142173 -281.226396) (xy 6.081782 -281.18845) (xy 6.02602 -281.143981)
			(xy 5.975587 -281.093548) (xy 5.931118 -281.037786) (xy 5.893172 -280.977395) (xy 5.862227 -280.913136)
			(xy 5.83867 -280.845816) (xy 5.8228 -280.776281) (xy 5.814814 -280.705407) (xy 4.584962 -280.705407)
			(xy 4.576976 -280.776281) (xy 4.561106 -280.845816) (xy 4.537549 -280.913136) (xy 4.506604 -280.977395)
			(xy 4.468658 -281.037786) (xy 4.424189 -281.093548) (xy 4.373756 -281.143981) (xy 4.317994 -281.18845)
			(xy 4.257603 -281.226396) (xy 4.193344 -281.257341) (xy 4.126024 -281.280898) (xy 4.056489 -281.296768)
			(xy 3.985615 -281.304754) (xy 3.914293 -281.304754) (xy 3.843419 -281.296768) (xy 3.773884 -281.280898)
			(xy 3.706564 -281.257341) (xy 3.642305 -281.226396) (xy 3.581914 -281.18845) (xy 3.526152 -281.143981)
			(xy 3.475719 -281.093548) (xy 3.43125 -281.037786) (xy 3.393304 -280.977395) (xy 3.362359 -280.913136)
			(xy 3.338802 -280.845816) (xy 3.322932 -280.776281) (xy 3.314946 -280.705407) (xy 1.27 -280.705407)
			(xy 1.27 -280.888948) (xy 1.270437 -280.910599) (xy 1.277778 -280.953273) (xy 1.292247 -280.994085)
			(xy 1.313426 -281.031853) (xy 1.340702 -281.065484) (xy 1.373284 -281.094004) (xy 1.410229 -281.116588)
			(xy 1.450469 -281.13258) (xy 1.492837 -281.14152) (xy 1.536108 -281.143147) (xy 1.579028 -281.137414)
			(xy 1.620355 -281.124489) (xy 1.639824 -281.115008) (xy 1.671264 -281.097988) (xy 1.737191 -281.070323)
			(xy 1.805806 -281.050232) (xy 1.876242 -281.037968) (xy 1.94761 -281.033686) (xy 2.019007 -281.037441)
			(xy 2.089532 -281.049184) (xy 2.158294 -281.068769) (xy 2.224423 -281.095946) (xy 2.287084 -281.130373)
			(xy 2.345486 -281.171615) (xy 2.398891 -281.219151) (xy 2.446623 -281.272379) (xy 2.488081 -281.330629)
			(xy 2.522739 -281.393163) (xy 2.55016 -281.459191) (xy 2.569998 -281.52788) (xy 2.582002 -281.598361)
			(xy 2.58602 -281.669744) (xy 2.584013 -281.705405) (xy 7.81481 -281.705405) (xy 7.81481 -281.634083)
			(xy 7.822796 -281.563209) (xy 7.838666 -281.493674) (xy 7.862223 -281.426354) (xy 7.893168 -281.362095)
			(xy 7.931114 -281.301704) (xy 7.975583 -281.245942) (xy 8.026016 -281.195509) (xy 8.081778 -281.15104)
			(xy 8.142169 -281.113094) (xy 8.206428 -281.082149) (xy 8.273748 -281.058592) (xy 8.343283 -281.042722)
			(xy 8.414157 -281.034736) (xy 8.485479 -281.034736) (xy 8.556353 -281.042722) (xy 8.625888 -281.058592)
			(xy 8.693208 -281.082149) (xy 8.757467 -281.113094) (xy 8.817858 -281.15104) (xy 8.87362 -281.195509)
			(xy 8.924053 -281.245942) (xy 8.968522 -281.301704) (xy 9.006468 -281.362095) (xy 9.037413 -281.426354)
			(xy 9.06097 -281.493674) (xy 9.07684 -281.563209) (xy 9.084826 -281.634083) (xy 9.085326 -281.669744)
			(xy 9.084826 -281.705405) (xy 9.07684 -281.776279) (xy 9.06097 -281.845814) (xy 9.037413 -281.913134)
			(xy 9.006468 -281.977393) (xy 8.968522 -282.037784) (xy 8.924053 -282.093546) (xy 8.87362 -282.143979)
			(xy 8.817858 -282.188448) (xy 8.757467 -282.226394) (xy 8.693208 -282.257339) (xy 8.625888 -282.280896)
			(xy 8.556353 -282.296766) (xy 8.485479 -282.304752) (xy 8.414157 -282.304752) (xy 8.343283 -282.296766)
			(xy 8.273748 -282.280896) (xy 8.206428 -282.257339) (xy 8.142169 -282.226394) (xy 8.081778 -282.188448)
			(xy 8.026016 -282.143979) (xy 7.975583 -282.093546) (xy 7.931114 -282.037784) (xy 7.893168 -281.977393)
			(xy 7.862223 -281.913134) (xy 7.838666 -281.845814) (xy 7.822796 -281.776279) (xy 7.81481 -281.705405)
			(xy 2.584013 -281.705405) (xy 2.582002 -281.741127) (xy 2.569998 -281.811608) (xy 2.55016 -281.880297)
			(xy 2.522739 -281.946325) (xy 2.488081 -282.008859) (xy 2.446623 -282.067109) (xy 2.398891 -282.120337)
			(xy 2.345486 -282.167873) (xy 2.287084 -282.209115) (xy 2.224423 -282.243542) (xy 2.158294 -282.270719)
			(xy 2.089532 -282.290304) (xy 2.019007 -282.302047) (xy 1.94761 -282.305802) (xy 1.876242 -282.30152)
			(xy 1.805806 -282.289256) (xy 1.737191 -282.269165) (xy 1.671264 -282.2415) (xy 1.639824 -282.22448)
			(xy 1.620357 -282.214996) (xy 1.579031 -282.202068) (xy 1.536112 -282.196334) (xy 1.492842 -282.197961)
			(xy 1.450475 -282.2069) (xy 1.410236 -282.222894) (xy 1.373292 -282.245478) (xy 1.340712 -282.274)
			(xy 1.31344 -282.307632) (xy 1.292265 -282.345402) (xy 1.2778 -282.386215) (xy 1.270465 -282.42889)
			(xy 1.27 -282.45054) (xy 1.27 -282.705403) (xy 3.314946 -282.705403) (xy 3.314946 -282.634081) (xy 3.322932 -282.563207)
			(xy 3.338802 -282.493672) (xy 3.362359 -282.426352) (xy 3.393304 -282.362093) (xy 3.43125 -282.301702)
			(xy 3.475719 -282.24594) (xy 3.526152 -282.195507) (xy 3.581914 -282.151038) (xy 3.642305 -282.113092)
			(xy 3.706564 -282.082147) (xy 3.773884 -282.05859) (xy 3.843419 -282.04272) (xy 3.914293 -282.034734)
			(xy 3.985615 -282.034734) (xy 4.056489 -282.04272) (xy 4.126024 -282.05859) (xy 4.193344 -282.082147)
			(xy 4.257603 -282.113092) (xy 4.317994 -282.151038) (xy 4.373756 -282.195507) (xy 4.424189 -282.24594)
			(xy 4.468658 -282.301702) (xy 4.506604 -282.362093) (xy 4.537549 -282.426352) (xy 4.561106 -282.493672)
			(xy 4.576976 -282.563207) (xy 4.584962 -282.634081) (xy 4.585462 -282.669742) (xy 4.584962 -282.705403)
			(xy 4.576976 -282.776277) (xy 4.561106 -282.845812) (xy 4.537549 -282.913132) (xy 4.506604 -282.977391)
			(xy 4.468658 -283.037782) (xy 4.424189 -283.093544) (xy 4.373756 -283.143977) (xy 4.317994 -283.188446)
			(xy 4.257603 -283.226392) (xy 4.193344 -283.257337) (xy 4.126024 -283.280894) (xy 4.056489 -283.296764)
			(xy 3.985615 -283.30475) (xy 3.914293 -283.30475) (xy 3.843419 -283.296764) (xy 3.773884 -283.280894)
			(xy 3.706564 -283.257337) (xy 3.642305 -283.226392) (xy 3.581914 -283.188446) (xy 3.526152 -283.143977)
			(xy 3.475719 -283.093544) (xy 3.43125 -283.037782) (xy 3.393304 -282.977391) (xy 3.362359 -282.913132)
			(xy 3.338802 -282.845812) (xy 3.322932 -282.776277) (xy 3.314946 -282.705403) (xy 1.27 -282.705403)
			(xy 1.27 -282.888944) (xy 1.270438 -282.910594) (xy 1.277779 -282.953268) (xy 1.292249 -282.994079)
			(xy 1.313428 -283.031846) (xy 1.340704 -283.065476) (xy 1.373285 -283.093995) (xy 1.410231 -283.116578)
			(xy 1.450469 -283.132571) (xy 1.492837 -283.14151) (xy 1.536107 -283.143137) (xy 1.579026 -283.137405)
			(xy 1.620352 -283.124479) (xy 1.639824 -283.115004) (xy 1.671264 -283.097984) (xy 1.737191 -283.070319)
			(xy 1.805806 -283.050227) (xy 1.876243 -283.037963) (xy 1.947611 -283.033681) (xy 2.019008 -283.037436)
			(xy 2.089533 -283.049179) (xy 2.158295 -283.068763) (xy 2.224425 -283.095941) (xy 2.287086 -283.130368)
			(xy 2.345488 -283.17161) (xy 2.398893 -283.219146) (xy 2.446626 -283.272374) (xy 2.488083 -283.330624)
			(xy 2.522742 -283.393158) (xy 2.550163 -283.459187) (xy 2.570001 -283.527875) (xy 2.582005 -283.598357)
			(xy 2.586023 -283.66974) (xy 2.582005 -283.741123) (xy 2.570001 -283.811605) (xy 2.550163 -283.880293)
			(xy 2.522742 -283.946322) (xy 2.488083 -284.008856) (xy 2.446626 -284.067106) (xy 2.398893 -284.120334)
			(xy 2.345488 -284.16787) (xy 2.287086 -284.209112) (xy 2.224425 -284.243539) (xy 2.158295 -284.270717)
			(xy 2.089533 -284.290301) (xy 2.019008 -284.302044) (xy 1.947611 -284.305799) (xy 1.876243 -284.301517)
			(xy 1.805806 -284.289253) (xy 1.737191 -284.269161) (xy 1.671264 -284.241496) (xy 1.639824 -284.224476)
			(xy 1.620357 -284.214992) (xy 1.579031 -284.202064) (xy 1.536112 -284.196331) (xy 1.492842 -284.197957)
			(xy 1.450474 -284.206897) (xy 1.410235 -284.22289) (xy 1.373291 -284.245475) (xy 1.340711 -284.273996)
			(xy 1.313438 -284.307628) (xy 1.292263 -284.345398) (xy 1.277798 -284.386211) (xy 1.270462 -284.428886)
			(xy 1.27 -284.450536) (xy 1.27 -284.88894) (xy 1.270438 -284.91059) (xy 1.277779 -284.953264) (xy 1.292248 -284.994076)
			(xy 1.313427 -285.031844) (xy 1.340702 -285.065475) (xy 1.373284 -285.093995) (xy 1.41023 -285.116578)
			(xy 1.450469 -285.13257) (xy 1.492837 -285.14151) (xy 1.536107 -285.143137) (xy 1.579027 -285.137405)
			(xy 1.620354 -285.124479) (xy 1.639824 -285.115) (xy 1.672623 -285.097274) (xy 1.741511 -285.068755)
			(xy 1.813263 -285.048492) (xy 1.886893 -285.036765) (xy 1.96139 -285.033735) (xy 2.035729 -285.039443)
			(xy 2.10889 -285.05381) (xy 2.179867 -285.07664) (xy 2.247684 -285.107619) (xy 2.311411 -285.14632)
			(xy 2.341118 -285.168848) (xy 2.364676 -285.187695) (xy 2.408499 -285.229167) (xy 2.448199 -285.274601)
			(xy 2.466086 -285.298896) (xy 2.475226 -285.310871) (xy 2.498062 -285.330508) (xy 2.52487 -285.344233)
			(xy 2.554151 -285.35128) (xy 2.56921 -285.351728) (xy 3.170174 -285.351728) (xy 3.192127 -285.351275)
			(xy 3.235381 -285.343745) (xy 3.276695 -285.328887) (xy 3.314839 -285.307146) (xy 3.348674 -285.279167)
			(xy 3.377193 -285.245786) (xy 3.399546 -285.207998) (xy 3.415066 -285.166927) (xy 3.423291 -285.1238)
			(xy 3.423975 -285.079901) (xy 3.417099 -285.036538) (xy 3.402867 -284.995004) (xy 3.392678 -284.975554)
			(xy 3.376296 -284.944688) (xy 3.34962 -284.880098) (xy 3.330191 -284.812971) (xy 3.318245 -284.744117)
			(xy 3.313925 -284.674369) (xy 3.317284 -284.604568) (xy 3.328281 -284.535557) (xy 3.346783 -284.468169)
			(xy 3.372567 -284.403217) (xy 3.405322 -284.341487) (xy 3.444652 -284.283723) (xy 3.490082 -284.230623)
			(xy 3.541063 -284.182828) (xy 3.596981 -284.140915) (xy 3.65716 -284.105391) (xy 3.720873 -284.076683)
			(xy 3.787351 -284.055139) (xy 3.855792 -284.041019) (xy 3.925368 -284.034493) (xy 3.995241 -284.03564)
			(xy 4.029964 -284.039564) (xy 4.048252 -284.042104) (xy 4.053078 -284.042866) (xy 4.063492 -284.043628)
			(xy 4.081861 -284.044482) (xy 4.117821 -284.036871) (xy 4.150137 -284.019358) (xy 4.163568 -284.006798)
			(xy 4.252722 -283.917644) (xy 4.966208 -283.204412) (xy 5.613654 -283.204412) (xy 5.637013 -283.203158)
			(xy 5.682712 -283.193187) (xy 5.725816 -283.175026) (xy 5.764872 -283.149289) (xy 5.798562 -283.116844)
			(xy 5.825751 -283.078784) (xy 5.845521 -283.036393) (xy 5.857204 -282.991102) (xy 5.860408 -282.944439)
			(xy 5.855024 -282.897976) (xy 5.848604 -282.875482) (xy 5.837567 -282.841707) (xy 5.822204 -282.772329)
			(xy 5.814677 -282.70167) (xy 5.81508 -282.630613) (xy 5.823408 -282.560044) (xy 5.839556 -282.490845)
			(xy 5.863324 -282.423879) (xy 5.894414 -282.359983) (xy 5.932439 -282.299954) (xy 5.976923 -282.244543)
			(xy 6.027311 -282.194439) (xy 6.082974 -282.15027) (xy 6.143217 -282.112587) (xy 6.207289 -282.081859)
			(xy 6.274388 -282.058472) (xy 6.343678 -282.042716) (xy 6.414293 -282.034788) (xy 6.485351 -282.034788)
			(xy 6.555966 -282.042716) (xy 6.625256 -282.058472) (xy 6.692355 -282.081859) (xy 6.756427 -282.112587)
			(xy 6.81667 -282.15027) (xy 6.872333 -282.194439) (xy 6.922721 -282.244543) (xy 6.967205 -282.299954)
			(xy 7.00523 -282.359983) (xy 7.03632 -282.423879) (xy 7.060088 -282.490845) (xy 7.076236 -282.560044)
			(xy 7.084564 -282.630613) (xy 7.084967 -282.70167) (xy 7.07744 -282.772329) (xy 7.062077 -282.841707)
			(xy 7.05104 -282.875482) (xy 7.044654 -282.897985) (xy 7.039272 -282.944444) (xy 7.042476 -282.991104)
			(xy 7.054158 -283.036392) (xy 7.073924 -283.07878) (xy 7.101107 -283.116839) (xy 7.134792 -283.149285)
			(xy 7.173841 -283.175026) (xy 7.216939 -283.193192) (xy 7.262632 -283.203171) (xy 7.28599 -283.204412)
			(xy 7.401814 -283.204412) (xy 7.545832 -283.34843) (xy 7.561947 -283.362859) (xy 7.59812 -283.386569)
			(xy 7.637788 -283.40381) (xy 7.679802 -283.414082) (xy 7.72295 -283.417089) (xy 7.765983 -283.412744)
			(xy 7.807658 -283.401172) (xy 7.846771 -283.382709) (xy 7.882191 -283.357887) (xy 7.912895 -283.327424)
			(xy 7.925816 -283.310076) (xy 7.944467 -283.283617) (xy 7.986343 -283.234246) (xy 8.033021 -283.189388)
			(xy 8.084019 -283.14951) (xy 8.138808 -283.115023) (xy 8.167624 -283.100272) (xy 8.199441 -283.085042)
			(xy 8.26573 -283.060915) (xy 8.334283 -283.044278) (xy 8.404257 -283.035333) (xy 8.474791 -283.034192)
			(xy 8.545017 -283.040868) (xy 8.614073 -283.055279) (xy 8.681108 -283.077247) (xy 8.745298 -283.106504)
			(xy 8.805854 -283.142688) (xy 8.862031 -283.185355) (xy 8.913138 -283.23398) (xy 8.958547 -283.287964)
			(xy 8.997699 -283.346645) (xy 9.030112 -283.409301) (xy 9.049598 -283.460073) (xy 28.093141 -283.460073)
			(xy 28.093141 -283.396807) (xy 28.101399 -283.334083) (xy 28.117773 -283.272974) (xy 28.141984 -283.214524)
			(xy 28.173617 -283.159735) (xy 28.21213 -283.109543) (xy 28.256865 -283.064808) (xy 28.307057 -283.026295)
			(xy 28.361846 -282.994662) (xy 28.420296 -282.970451) (xy 28.481405 -282.954077) (xy 28.544129 -282.945819)
			(xy 28.607395 -282.945819) (xy 28.670119 -282.954077) (xy 28.731228 -282.970451) (xy 28.789678 -282.994662)
			(xy 28.844467 -283.026295) (xy 28.894659 -283.064808) (xy 28.917392 -283.08681) (xy 29.060902 -283.23032)
			(xy 29.369004 -283.23032) (xy 29.39199 -283.229782) (xy 29.437209 -283.221494) (xy 29.4802 -283.205207)
			(xy 29.51956 -283.181453) (xy 29.554005 -283.151006) (xy 29.582412 -283.11486) (xy 29.603853 -283.074194)
			(xy 29.61763 -283.030334) (xy 29.623292 -282.984712) (xy 29.620656 -282.938815) (xy 29.609807 -282.894141)
			(xy 29.600906 -282.872942) (xy 29.583621 -282.832985) (xy 29.555658 -282.750531) (xy 29.535436 -282.665846)
			(xy 29.52313 -282.579654) (xy 29.518844 -282.492694) (xy 29.522615 -282.405709) (xy 29.534411 -282.319446)
			(xy 29.554131 -282.234643) (xy 29.581606 -282.152025) (xy 29.616601 -282.072301) (xy 29.658815 -281.996154)
			(xy 29.707888 -281.924235) (xy 29.763399 -281.85716) (xy 29.824873 -281.795504) (xy 29.891783 -281.739795)
			(xy 29.963557 -281.690509) (xy 30.039579 -281.64807) (xy 30.119199 -281.61284) (xy 30.201734 -281.585121)
			(xy 30.286479 -281.56515) (xy 30.372707 -281.553099) (xy 30.45968 -281.54907) (xy 30.546653 -281.553099)
			(xy 30.632881 -281.56515) (xy 30.717626 -281.585121) (xy 30.800161 -281.61284) (xy 30.879781 -281.64807)
			(xy 30.955803 -281.690509) (xy 31.027577 -281.739795) (xy 31.094487 -281.795504) (xy 31.155961 -281.85716)
			(xy 31.211472 -281.924235) (xy 31.260545 -281.996154) (xy 31.302759 -282.072301) (xy 31.337754 -282.152025)
			(xy 31.365229 -282.234643) (xy 31.384949 -282.319446) (xy 31.396745 -282.405709) (xy 31.400516 -282.492694)
			(xy 31.398512 -282.53336) (xy 34.599874 -282.53336) (xy 34.599874 -282.44646) (xy 34.607892 -282.359931)
			(xy 34.62386 -282.274511) (xy 34.647641 -282.190929) (xy 34.679033 -282.109897) (xy 34.717767 -282.032108)
			(xy 34.763514 -281.958224) (xy 34.815883 -281.888877) (xy 34.874427 -281.824657) (xy 34.938647 -281.766113)
			(xy 35.007994 -281.713744) (xy 35.081878 -281.667997) (xy 35.159667 -281.629263) (xy 35.240699 -281.597871)
			(xy 35.324281 -281.57409) (xy 35.409701 -281.558122) (xy 35.49623 -281.550104) (xy 35.58313 -281.550104)
			(xy 35.669659 -281.558122) (xy 35.755079 -281.57409) (xy 35.838661 -281.597871) (xy 35.919693 -281.629263)
			(xy 35.997482 -281.667997) (xy 36.071366 -281.713744) (xy 36.140713 -281.766113) (xy 36.204933 -281.824657)
			(xy 36.216998 -281.837892) (xy 85.345268 -281.837892) (xy 85.349339 -281.78227) (xy 85.361465 -281.727833)
			(xy 85.381388 -281.675742) (xy 85.408684 -281.627107) (xy 85.44277 -281.582964) (xy 85.482919 -281.544255)
			(xy 85.528277 -281.511804) (xy 85.577877 -281.486303) (xy 85.630661 -281.468296) (xy 85.685504 -281.458166)
			(xy 85.741238 -281.456129) (xy 85.796675 -281.462229) (xy 85.850632 -281.476335) (xy 85.901961 -281.498147)
			(xy 85.949567 -281.527201) (xy 85.992435 -281.562876) (xy 86.029652 -281.604413) (xy 86.060425 -281.650926)
			(xy 86.084097 -281.701423) (xy 86.100165 -281.75483) (xy 86.108285 -281.810006) (xy 86.108794 -281.837892)
			(xy 86.108285 -281.865778) (xy 86.100165 -281.920954) (xy 86.084097 -281.974361) (xy 86.060425 -282.024858)
			(xy 86.029652 -282.071371) (xy 85.992435 -282.112908) (xy 85.949567 -282.148583) (xy 85.901961 -282.177637)
			(xy 85.850632 -282.199449) (xy 85.796675 -282.213555) (xy 85.741238 -282.219655) (xy 85.685504 -282.217618)
			(xy 85.630661 -282.207488) (xy 85.577877 -282.189481) (xy 85.528277 -282.16398) (xy 85.482919 -282.131529)
			(xy 85.44277 -282.09282) (xy 85.408684 -282.048677) (xy 85.381388 -282.000042) (xy 85.361465 -281.947951)
			(xy 85.349339 -281.893514) (xy 85.345268 -281.837892) (xy 36.216998 -281.837892) (xy 36.263477 -281.888877)
			(xy 36.315846 -281.958224) (xy 36.361593 -282.032108) (xy 36.400327 -282.109897) (xy 36.431719 -282.190929)
			(xy 36.4555 -282.274511) (xy 36.471468 -282.359931) (xy 36.479486 -282.44646) (xy 36.479988 -282.48991)
			(xy 36.479486 -282.53336) (xy 36.471468 -282.619889) (xy 36.4555 -282.705309) (xy 36.431719 -282.788891)
			(xy 36.400327 -282.869923) (xy 36.361593 -282.947712) (xy 36.315846 -283.021596) (xy 36.263477 -283.090943)
			(xy 36.204933 -283.155163) (xy 36.140713 -283.213707) (xy 36.071366 -283.266076) (xy 35.997482 -283.311823)
			(xy 35.919693 -283.350557) (xy 35.838661 -283.381949) (xy 35.755079 -283.40573) (xy 35.669659 -283.421698)
			(xy 35.58313 -283.429716) (xy 35.49623 -283.429716) (xy 35.409701 -283.421698) (xy 35.324281 -283.40573)
			(xy 35.240699 -283.381949) (xy 35.159667 -283.350557) (xy 35.081878 -283.311823) (xy 35.007994 -283.266076)
			(xy 34.938647 -283.213707) (xy 34.874427 -283.155163) (xy 34.815883 -283.090943) (xy 34.763514 -283.021596)
			(xy 34.717767 -282.947712) (xy 34.679033 -282.869923) (xy 34.647641 -282.788891) (xy 34.62386 -282.705309)
			(xy 34.607892 -282.619889) (xy 34.599874 -282.53336) (xy 31.398512 -282.53336) (xy 31.39623 -282.579654)
			(xy 31.383924 -282.665846) (xy 31.363702 -282.750531) (xy 31.335739 -282.832985) (xy 31.318454 -282.872942)
			(xy 31.309503 -282.894128) (xy 31.298627 -282.938812) (xy 31.295972 -282.984725) (xy 31.301624 -283.030365)
			(xy 31.315399 -283.074243) (xy 31.336846 -283.114925) (xy 31.365265 -283.151082) (xy 31.399728 -283.181534)
			(xy 31.439109 -283.205285) (xy 31.482122 -283.22156) (xy 31.527361 -283.229828) (xy 31.550356 -283.23032)
			(xy 32.213042 -283.23032) (xy 32.480977 -283.49829) (xy 41.410888 -283.49829) (xy 41.414959 -283.442668)
			(xy 41.427085 -283.388231) (xy 41.447008 -283.33614) (xy 41.474304 -283.287505) (xy 41.50839 -283.243362)
			(xy 41.548539 -283.204653) (xy 41.593897 -283.172202) (xy 41.643497 -283.146701) (xy 41.696281 -283.128694)
			(xy 41.751124 -283.118564) (xy 41.806858 -283.116527) (xy 41.862295 -283.122627) (xy 41.916252 -283.136733)
			(xy 41.967581 -283.158545) (xy 42.015187 -283.187599) (xy 42.058055 -283.223274) (xy 42.095272 -283.264811)
			(xy 42.126045 -283.311324) (xy 42.149717 -283.361821) (xy 42.165785 -283.415228) (xy 42.173905 -283.470404)
			(xy 42.174414 -283.49829) (xy 42.174363 -283.501084) (xy 72.817734 -283.501084) (xy 72.821805 -283.445462)
			(xy 72.833931 -283.391025) (xy 72.853854 -283.338934) (xy 72.88115 -283.290299) (xy 72.915236 -283.246156)
			(xy 72.955385 -283.207447) (xy 73.000743 -283.174996) (xy 73.050343 -283.149495) (xy 73.103127 -283.131488)
			(xy 73.15797 -283.121358) (xy 73.213704 -283.119321) (xy 73.269141 -283.125421) (xy 73.323098 -283.139527)
			(xy 73.374427 -283.161339) (xy 73.422033 -283.190393) (xy 73.464901 -283.226068) (xy 73.502118 -283.267605)
			(xy 73.532891 -283.314118) (xy 73.556563 -283.364615) (xy 73.572631 -283.418022) (xy 73.580751 -283.473198)
			(xy 73.58126 -283.501084) (xy 73.963274 -283.501084) (xy 73.967345 -283.445462) (xy 73.979471 -283.391025)
			(xy 73.999394 -283.338934) (xy 74.02669 -283.290299) (xy 74.060776 -283.246156) (xy 74.100925 -283.207447)
			(xy 74.146283 -283.174996) (xy 74.195883 -283.149495) (xy 74.248667 -283.131488) (xy 74.30351 -283.121358)
			(xy 74.359244 -283.119321) (xy 74.414681 -283.125421) (xy 74.468638 -283.139527) (xy 74.519967 -283.161339)
			(xy 74.567573 -283.190393) (xy 74.610441 -283.226068) (xy 74.647658 -283.267605) (xy 74.678431 -283.314118)
			(xy 74.702103 -283.364615) (xy 74.718171 -283.418022) (xy 74.726291 -283.473198) (xy 74.726531 -283.486352)
			(xy 83.925662 -283.486352) (xy 83.929733 -283.43073) (xy 83.941859 -283.376293) (xy 83.961782 -283.324202)
			(xy 83.989078 -283.275567) (xy 84.023164 -283.231424) (xy 84.063313 -283.192715) (xy 84.108671 -283.160264)
			(xy 84.158271 -283.134763) (xy 84.211055 -283.116756) (xy 84.265898 -283.106626) (xy 84.321632 -283.104589)
			(xy 84.377069 -283.110689) (xy 84.431026 -283.124795) (xy 84.482355 -283.146607) (xy 84.529961 -283.175661)
			(xy 84.572829 -283.211336) (xy 84.610046 -283.252873) (xy 84.640819 -283.299386) (xy 84.664491 -283.349883)
			(xy 84.680559 -283.40329) (xy 84.688679 -283.458466) (xy 84.689188 -283.486352) (xy 84.688679 -283.514238)
			(xy 84.680559 -283.569414) (xy 84.664491 -283.622821) (xy 84.640819 -283.673318) (xy 84.610046 -283.719831)
			(xy 84.572829 -283.761368) (xy 84.529961 -283.797043) (xy 84.482355 -283.826097) (xy 84.431026 -283.847909)
			(xy 84.377069 -283.862015) (xy 84.321632 -283.868115) (xy 84.265898 -283.866078) (xy 84.211055 -283.855948)
			(xy 84.158271 -283.837941) (xy 84.108671 -283.81244) (xy 84.063313 -283.779989) (xy 84.023164 -283.74128)
			(xy 83.989078 -283.697137) (xy 83.961782 -283.648502) (xy 83.941859 -283.596411) (xy 83.929733 -283.541974)
			(xy 83.925662 -283.486352) (xy 74.726531 -283.486352) (xy 74.7268 -283.501084) (xy 74.726291 -283.52897)
			(xy 74.718171 -283.584146) (xy 74.702103 -283.637553) (xy 74.678431 -283.68805) (xy 74.647658 -283.734563)
			(xy 74.610441 -283.7761) (xy 74.567573 -283.811775) (xy 74.519967 -283.840829) (xy 74.468638 -283.862641)
			(xy 74.414681 -283.876747) (xy 74.359244 -283.882847) (xy 74.30351 -283.88081) (xy 74.248667 -283.87068)
			(xy 74.195883 -283.852673) (xy 74.146283 -283.827172) (xy 74.100925 -283.794721) (xy 74.060776 -283.756012)
			(xy 74.02669 -283.711869) (xy 73.999394 -283.663234) (xy 73.979471 -283.611143) (xy 73.967345 -283.556706)
			(xy 73.963274 -283.501084) (xy 73.58126 -283.501084) (xy 73.580751 -283.52897) (xy 73.572631 -283.584146)
			(xy 73.556563 -283.637553) (xy 73.532891 -283.68805) (xy 73.502118 -283.734563) (xy 73.464901 -283.7761)
			(xy 73.422033 -283.811775) (xy 73.374427 -283.840829) (xy 73.323098 -283.862641) (xy 73.269141 -283.876747)
			(xy 73.213704 -283.882847) (xy 73.15797 -283.88081) (xy 73.103127 -283.87068) (xy 73.050343 -283.852673)
			(xy 73.000743 -283.827172) (xy 72.955385 -283.794721) (xy 72.915236 -283.756012) (xy 72.88115 -283.711869)
			(xy 72.853854 -283.663234) (xy 72.833931 -283.611143) (xy 72.821805 -283.556706) (xy 72.817734 -283.501084)
			(xy 42.174363 -283.501084) (xy 42.173905 -283.526176) (xy 42.165785 -283.581352) (xy 42.149717 -283.634759)
			(xy 42.126045 -283.685256) (xy 42.095272 -283.731769) (xy 42.058055 -283.773306) (xy 42.015187 -283.808981)
			(xy 41.967581 -283.838035) (xy 41.916252 -283.859847) (xy 41.862295 -283.873953) (xy 41.806858 -283.880053)
			(xy 41.751124 -283.878016) (xy 41.696281 -283.867886) (xy 41.643497 -283.849879) (xy 41.593897 -283.824378)
			(xy 41.548539 -283.791927) (xy 41.50839 -283.753218) (xy 41.474304 -283.709075) (xy 41.447008 -283.66044)
			(xy 41.427085 -283.608349) (xy 41.414959 -283.553912) (xy 41.410888 -283.49829) (xy 32.480977 -283.49829)
			(xy 34.166048 -285.18358) (xy 34.182495 -285.199418) (xy 34.220015 -285.225433) (xy 34.261579 -285.244327)
			(xy 34.305851 -285.255491) (xy 34.351404 -285.258565) (xy 34.396774 -285.253452) (xy 34.4405 -285.240316)
			(xy 34.481176 -285.219579) (xy 34.517493 -285.191909) (xy 34.548283 -285.158196) (xy 34.572553 -285.119524)
			(xy 34.589525 -285.077138) (xy 34.598651 -285.032403) (xy 34.599626 -285.00959) (xy 34.60107 -284.965856)
			(xy 34.611079 -284.878919) (xy 34.629122 -284.793289) (xy 34.655043 -284.709705) (xy 34.688618 -284.628891)
			(xy 34.729556 -284.551547) (xy 34.777503 -284.47834) (xy 34.832045 -284.409906) (xy 34.892709 -284.346834)
			(xy 34.958971 -284.289672) (xy 35.030257 -284.238914) (xy 35.105951 -284.194998) (xy 35.185397 -284.158306)
			(xy 35.26791 -284.129153) (xy 35.352773 -284.107793) (xy 35.439255 -284.09441) (xy 35.526606 -284.089121)
			(xy 35.61407 -284.09197) (xy 35.700891 -284.102933) (xy 35.786318 -284.121915) (xy 35.869612 -284.148753)
			(xy 35.950052 -284.183213) (xy 36.026942 -284.224998) (xy 36.099618 -284.273747) (xy 36.16745 -284.329037)
			(xy 36.184331 -284.345634) (xy 71.489314 -284.345634) (xy 71.493385 -284.290012) (xy 71.505511 -284.235575)
			(xy 71.525434 -284.183484) (xy 71.55273 -284.134849) (xy 71.586816 -284.090706) (xy 71.626965 -284.051997)
			(xy 71.672323 -284.019546) (xy 71.721923 -283.994045) (xy 71.774707 -283.976038) (xy 71.82955 -283.965908)
			(xy 71.885284 -283.963871) (xy 71.940721 -283.969971) (xy 71.994678 -283.984077) (xy 72.046007 -284.005889)
			(xy 72.093613 -284.034943) (xy 72.136481 -284.070618) (xy 72.173698 -284.112155) (xy 72.204471 -284.158668)
			(xy 72.228143 -284.209165) (xy 72.244211 -284.262572) (xy 72.252331 -284.317748) (xy 72.25284 -284.345634)
			(xy 72.252331 -284.37352) (xy 72.244211 -284.428696) (xy 72.228143 -284.482103) (xy 72.204471 -284.5326)
			(xy 72.173698 -284.579113) (xy 72.136481 -284.62065) (xy 72.093613 -284.656325) (xy 72.046007 -284.685379)
			(xy 71.994678 -284.707191) (xy 71.940721 -284.721297) (xy 71.885284 -284.727397) (xy 71.82955 -284.72536)
			(xy 71.774707 -284.71523) (xy 71.721923 -284.697223) (xy 71.672323 -284.671722) (xy 71.626965 -284.639271)
			(xy 71.586816 -284.600562) (xy 71.55273 -284.556419) (xy 71.525434 -284.507784) (xy 71.505511 -284.455693)
			(xy 71.493385 -284.401256) (xy 71.489314 -284.345634) (xy 36.184331 -284.345634) (xy 36.229851 -284.39039)
			(xy 36.286282 -284.457275) (xy 36.336254 -284.529115) (xy 36.379336 -284.605286) (xy 36.415154 -284.685131)
			(xy 36.443398 -284.767959) (xy 36.463825 -284.853052) (xy 36.476257 -284.939675) (xy 36.480587 -285.027079)
			(xy 36.476777 -285.114506) (xy 36.464861 -285.201202) (xy 36.454394 -285.245979) (xy 47.75199 -285.245979)
			(xy 47.75199 -285.164869) (xy 47.75994 -285.08415) (xy 47.775763 -285.004599) (xy 47.799308 -284.926983)
			(xy 47.830347 -284.852047) (xy 47.868582 -284.780515) (xy 47.913644 -284.713075) (xy 47.965099 -284.650376)
			(xy 48.022452 -284.593023) (xy 48.085151 -284.541568) (xy 48.152591 -284.496506) (xy 48.224123 -284.458271)
			(xy 48.299059 -284.427232) (xy 48.376675 -284.403687) (xy 48.456226 -284.387864) (xy 48.536945 -284.379914)
			(xy 48.618055 -284.379914) (xy 48.698774 -284.387864) (xy 48.778325 -284.403687) (xy 48.855941 -284.427232)
			(xy 48.930877 -284.458271) (xy 49.002409 -284.496506) (xy 49.069849 -284.541568) (xy 49.132548 -284.593023)
			(xy 49.189901 -284.650376) (xy 49.241356 -284.713075) (xy 49.270612 -284.75686) (xy 83.181188 -284.75686)
			(xy 83.185259 -284.701238) (xy 83.197385 -284.646801) (xy 83.217308 -284.59471) (xy 83.244604 -284.546075)
			(xy 83.27869 -284.501932) (xy 83.318839 -284.463223) (xy 83.364197 -284.430772) (xy 83.413797 -284.405271)
			(xy 83.466581 -284.387264) (xy 83.521424 -284.377134) (xy 83.577158 -284.375097) (xy 83.632595 -284.381197)
			(xy 83.686552 -284.395303) (xy 83.737881 -284.417115) (xy 83.785487 -284.446169) (xy 83.828355 -284.481844)
			(xy 83.865572 -284.523381) (xy 83.896345 -284.569894) (xy 83.920017 -284.620391) (xy 83.936085 -284.673798)
			(xy 83.944205 -284.728974) (xy 83.944714 -284.75686) (xy 83.944205 -284.784746) (xy 83.936085 -284.839922)
			(xy 83.920017 -284.893329) (xy 83.896345 -284.943826) (xy 83.865572 -284.990339) (xy 83.828355 -285.031876)
			(xy 83.785487 -285.067551) (xy 83.737881 -285.096605) (xy 83.686552 -285.118417) (xy 83.632595 -285.132523)
			(xy 83.577158 -285.138623) (xy 83.521424 -285.136586) (xy 83.466581 -285.126456) (xy 83.413797 -285.108449)
			(xy 83.364197 -285.082948) (xy 83.318839 -285.050497) (xy 83.27869 -285.011788) (xy 83.244604 -284.967645)
			(xy 83.217308 -284.91901) (xy 83.197385 -284.866919) (xy 83.185259 -284.812482) (xy 83.181188 -284.75686)
			(xy 49.270612 -284.75686) (xy 49.286418 -284.780515) (xy 49.324653 -284.852047) (xy 49.355692 -284.926983)
			(xy 49.379237 -285.004599) (xy 49.39506 -285.08415) (xy 49.40301 -285.164869) (xy 49.403508 -285.205424)
			(xy 49.40301 -285.245979) (xy 49.39506 -285.326698) (xy 49.379237 -285.406249) (xy 49.355692 -285.483865)
			(xy 49.324653 -285.558801) (xy 49.286418 -285.630333) (xy 49.241356 -285.697773) (xy 49.189901 -285.760472)
			(xy 49.132548 -285.817825) (xy 49.069849 -285.86928) (xy 49.002409 -285.914342) (xy 48.930877 -285.952577)
			(xy 48.855941 -285.983616) (xy 48.778325 -286.007161) (xy 48.698774 -286.022984) (xy 48.618055 -286.030934)
			(xy 48.536945 -286.030934) (xy 48.456226 -286.022984) (xy 48.376675 -286.007161) (xy 48.299059 -285.983616)
			(xy 48.224123 -285.952577) (xy 48.152591 -285.914342) (xy 48.085151 -285.86928) (xy 48.022452 -285.817825)
			(xy 47.965099 -285.760472) (xy 47.913644 -285.697773) (xy 47.868582 -285.630333) (xy 47.830347 -285.558801)
			(xy 47.799308 -285.483865) (xy 47.775763 -285.406249) (xy 47.75994 -285.326698) (xy 47.75199 -285.245979)
			(xy 36.454394 -285.245979) (xy 36.444942 -285.286415) (xy 36.417191 -285.36941) (xy 36.399978 -285.40964)
			(xy 36.391151 -285.430836) (xy 36.380461 -285.475486) (xy 36.377964 -285.52133) (xy 36.38374 -285.566877)
			(xy 36.397603 -285.610646) (xy 36.419101 -285.651213) (xy 36.447535 -285.68726) (xy 36.481981 -285.717615)
			(xy 36.521318 -285.741289) (xy 36.564267 -285.757514) (xy 36.609432 -285.765762) (xy 36.632388 -285.766256)
			(xy 37.486844 -285.766256) (xy 37.942012 -285.311088) (xy 41.256712 -285.311088) (xy 42.043279 -286.097472)
			(xy 82.563714 -286.097472) (xy 82.567785 -286.04185) (xy 82.579911 -285.987413) (xy 82.599834 -285.935322)
			(xy 82.62713 -285.886687) (xy 82.661216 -285.842544) (xy 82.701365 -285.803835) (xy 82.746723 -285.771384)
			(xy 82.796323 -285.745883) (xy 82.849107 -285.727876) (xy 82.90395 -285.717746) (xy 82.959684 -285.715709)
			(xy 83.015121 -285.721809) (xy 83.069078 -285.735915) (xy 83.120407 -285.757727) (xy 83.168013 -285.786781)
			(xy 83.210881 -285.822456) (xy 83.248098 -285.863993) (xy 83.278871 -285.910506) (xy 83.302543 -285.961003)
			(xy 83.318611 -286.01441) (xy 83.326731 -286.069586) (xy 83.32724 -286.097472) (xy 83.326731 -286.125358)
			(xy 83.318611 -286.180534) (xy 83.302543 -286.233941) (xy 83.278871 -286.284438) (xy 83.248098 -286.330951)
			(xy 83.210881 -286.372488) (xy 83.168013 -286.408163) (xy 83.120407 -286.437217) (xy 83.069078 -286.459029)
			(xy 83.015121 -286.473135) (xy 82.959684 -286.479235) (xy 82.90395 -286.477198) (xy 82.849107 -286.467068)
			(xy 82.796323 -286.449061) (xy 82.746723 -286.42356) (xy 82.701365 -286.391109) (xy 82.661216 -286.3524)
			(xy 82.62713 -286.308257) (xy 82.599834 -286.259622) (xy 82.579911 -286.207531) (xy 82.567785 -286.153094)
			(xy 82.563714 -286.097472) (xy 42.043279 -286.097472) (xy 42.346118 -286.40024) (xy 51.563524 -286.40024)
			(xy 51.873141 -286.709866) (xy 86.877404 -286.709866) (xy 86.881424 -286.519215) (xy 86.893478 -286.328902)
			(xy 86.913544 -286.139267) (xy 86.941587 -285.950646) (xy 86.977556 -285.763376) (xy 87.021388 -285.577788)
			(xy 87.073005 -285.394213) (xy 87.132315 -285.212977) (xy 87.199213 -285.034402) (xy 87.273579 -284.858807)
			(xy 87.355281 -284.686502) (xy 87.444175 -284.517795) (xy 87.540101 -284.352985) (xy 87.64289 -284.192366)
			(xy 87.752359 -284.036223) (xy 87.868313 -283.884834) (xy 87.990547 -283.738467) (xy 88.118841 -283.597383)
			(xy 88.252969 -283.461834) (xy 88.392693 -283.332059) (xy 88.537763 -283.208289) (xy 88.687921 -283.090746)
			(xy 88.842902 -282.979637) (xy 89.002429 -282.87516) (xy 89.166218 -282.777501) (xy 89.333978 -282.686834)
			(xy 89.505412 -282.60332) (xy 89.680214 -282.527107) (xy 89.858073 -282.458331) (xy 90.038674 -282.397113)
			(xy 90.221694 -282.343564) (xy 90.40681 -282.297778) (xy 90.593691 -282.259836) (xy 90.782006 -282.229807)
			(xy 90.971419 -282.207742) (xy 91.161593 -282.193683) (xy 91.352192 -282.187653) (xy 91.542875 -282.189663)
			(xy 91.733304 -282.19971) (xy 91.92314 -282.217776) (xy 92.112046 -282.243829) (xy 92.299685 -282.277822)
			(xy 92.485725 -282.319695) (xy 92.669834 -282.369374) (xy 92.851685 -282.42677) (xy 93.030955 -282.491781)
			(xy 93.207325 -282.564292) (xy 93.380481 -282.644173) (xy 93.550116 -282.731283) (xy 93.715928 -282.825467)
			(xy 93.877622 -282.926558) (xy 94.03491 -283.034374) (xy 94.187513 -283.148726) (xy 94.335161 -283.269409)
			(xy 94.477589 -283.39621) (xy 94.614545 -283.528901) (xy 94.745786 -283.667249) (xy 94.871078 -283.811006)
			(xy 94.990198 -283.959917) (xy 95.102934 -284.113718) (xy 95.209087 -284.272134) (xy 95.308467 -284.434885)
			(xy 95.400897 -284.60168) (xy 95.486214 -284.772224) (xy 95.564266 -284.946212) (xy 95.634913 -285.123337)
			(xy 95.698031 -285.303282) (xy 95.753507 -285.485728) (xy 95.801242 -285.670351) (xy 95.841152 -285.856821)
			(xy 95.873165 -286.044809) (xy 95.897225 -286.233979) (xy 95.913288 -286.423995) (xy 95.921327 -286.614519)
			(xy 95.92183 -286.709866) (xy 95.921327 -286.805213) (xy 95.913288 -286.995737) (xy 95.897225 -287.185753)
			(xy 95.873165 -287.374923) (xy 95.841152 -287.562911) (xy 95.801242 -287.749381) (xy 95.753507 -287.934004)
			(xy 95.698031 -288.11645) (xy 95.634913 -288.296395) (xy 95.564266 -288.47352) (xy 95.486214 -288.647508)
			(xy 95.400897 -288.818052) (xy 95.308467 -288.984847) (xy 95.209087 -289.147598) (xy 95.102934 -289.306014)
			(xy 94.990198 -289.459815) (xy 94.871078 -289.608726) (xy 94.745786 -289.752483) (xy 94.614545 -289.890831)
			(xy 94.477589 -290.023522) (xy 94.335161 -290.150323) (xy 94.187513 -290.271006) (xy 94.03491 -290.385358)
			(xy 93.877622 -290.493174) (xy 93.715928 -290.594265) (xy 93.550116 -290.688449) (xy 93.380481 -290.775559)
			(xy 93.207325 -290.85544) (xy 93.030955 -290.927951) (xy 92.851685 -290.992962) (xy 92.669834 -291.050358)
			(xy 92.485725 -291.100037) (xy 92.299685 -291.14191) (xy 92.112046 -291.175903) (xy 91.92314 -291.201956)
			(xy 91.733304 -291.220022) (xy 91.542875 -291.230069) (xy 91.352192 -291.232079) (xy 91.161593 -291.226049)
			(xy 90.971419 -291.21199) (xy 90.782006 -291.189925) (xy 90.593691 -291.159896) (xy 90.40681 -291.121954)
			(xy 90.221694 -291.076168) (xy 90.038674 -291.022619) (xy 89.858073 -290.961401) (xy 89.680214 -290.892625)
			(xy 89.505412 -290.816412) (xy 89.333978 -290.732898) (xy 89.166218 -290.642231) (xy 89.002429 -290.544572)
			(xy 88.842902 -290.440095) (xy 88.687921 -290.328986) (xy 88.537763 -290.211443) (xy 88.392693 -290.087673)
			(xy 88.252969 -289.957898) (xy 88.118841 -289.822349) (xy 87.990547 -289.681265) (xy 87.868313 -289.534898)
			(xy 87.752359 -289.383509) (xy 87.64289 -289.227366) (xy 87.540101 -289.066747) (xy 87.444175 -288.901937)
			(xy 87.355281 -288.73323) (xy 87.273579 -288.560925) (xy 87.199213 -288.38533) (xy 87.132315 -288.206755)
			(xy 87.073005 -288.025519) (xy 87.021388 -287.841944) (xy 86.977556 -287.656356) (xy 86.941587 -287.469086)
			(xy 86.913544 -287.280465) (xy 86.893478 -287.09083) (xy 86.881424 -286.900517) (xy 86.877404 -286.709866)
			(xy 51.873141 -286.709866) (xy 60.580778 -295.417748) (xy 60.592921 -295.429106) (xy 60.621714 -295.445708)
			(xy 60.653822 -295.454296) (xy 60.67044 -295.454832) (xy 78.407006 -295.454832) (xy 78.423637 -295.454231)
			(xy 78.455752 -295.445559) (xy 78.484536 -295.428885) (xy 78.496668 -295.417494) (xy 79.040228 -294.873934)
			(xy 79.062961 -294.851932) (xy 79.113153 -294.813419) (xy 79.167942 -294.781786) (xy 79.226392 -294.757575)
			(xy 79.287501 -294.741201) (xy 79.350225 -294.732943) (xy 79.413491 -294.732943) (xy 79.476215 -294.741201)
			(xy 79.537324 -294.757575) (xy 79.595774 -294.781786) (xy 79.650563 -294.813419) (xy 79.700755 -294.851932)
			(xy 79.74549 -294.896667) (xy 79.784003 -294.946859) (xy 79.815636 -295.001648) (xy 79.839847 -295.060098)
			(xy 79.856221 -295.121207) (xy 79.864479 -295.183931) (xy 79.864479 -295.215564) (xy 82.370166 -295.215564)
			(xy 82.374237 -295.159942) (xy 82.386363 -295.105505) (xy 82.406286 -295.053414) (xy 82.433582 -295.004779)
			(xy 82.467668 -294.960636) (xy 82.507817 -294.921927) (xy 82.553175 -294.889476) (xy 82.602775 -294.863975)
			(xy 82.655559 -294.845968) (xy 82.710402 -294.835838) (xy 82.766136 -294.833801) (xy 82.821573 -294.839901)
			(xy 82.87553 -294.854007) (xy 82.926859 -294.875819) (xy 82.974465 -294.904873) (xy 83.017333 -294.940548)
			(xy 83.05455 -294.982085) (xy 83.085323 -295.028598) (xy 83.108995 -295.079095) (xy 83.125063 -295.132502)
			(xy 83.133183 -295.187678) (xy 83.133692 -295.215564) (xy 83.133183 -295.24345) (xy 83.125063 -295.298626)
			(xy 83.108995 -295.352033) (xy 83.085323 -295.40253) (xy 83.05455 -295.449043) (xy 83.017333 -295.49058)
			(xy 82.974465 -295.526255) (xy 82.926859 -295.555309) (xy 82.87553 -295.577121) (xy 82.821573 -295.591227)
			(xy 82.766136 -295.597327) (xy 82.710402 -295.59529) (xy 82.655559 -295.58516) (xy 82.602775 -295.567153)
			(xy 82.553175 -295.541652) (xy 82.507817 -295.509201) (xy 82.467668 -295.470492) (xy 82.433582 -295.426349)
			(xy 82.406286 -295.377714) (xy 82.386363 -295.325623) (xy 82.374237 -295.271186) (xy 82.370166 -295.215564)
			(xy 79.864479 -295.215564) (xy 79.864479 -295.247197) (xy 79.856221 -295.309921) (xy 79.839847 -295.37103)
			(xy 79.815636 -295.42948) (xy 79.784003 -295.484269) (xy 79.74549 -295.534461) (xy 79.723488 -295.557194)
			(xy 78.838298 -296.442384) (xy 78.82684 -296.454518) (xy 78.810136 -296.483397) (xy 78.801489 -296.515619)
			(xy 78.801489 -296.548981) (xy 78.810136 -296.581203) (xy 78.82684 -296.610082) (xy 78.838298 -296.622216)
			(xy 79.766922 -297.550586) (xy 79.788924 -297.573319) (xy 79.827437 -297.623511) (xy 79.85907 -297.6783)
			(xy 79.883281 -297.73675) (xy 79.899655 -297.797859) (xy 79.907913 -297.860583) (xy 79.907913 -297.923849)
			(xy 79.899655 -297.986573) (xy 79.883281 -298.047682) (xy 79.85907 -298.106132) (xy 79.827437 -298.160921)
			(xy 79.788924 -298.211113) (xy 79.744189 -298.255848) (xy 79.693997 -298.294361) (xy 79.639208 -298.325994)
			(xy 79.580758 -298.350205) (xy 79.519649 -298.366579) (xy 79.456925 -298.374837) (xy 79.393659 -298.374837)
			(xy 79.330935 -298.366579) (xy 79.269826 -298.350205) (xy 79.211376 -298.325994) (xy 79.156587 -298.294361)
			(xy 79.106395 -298.255848) (xy 79.083662 -298.233846) (xy 78.291182 -297.441366) (xy 78.279091 -297.42992)
			(xy 78.250296 -297.413224) (xy 78.218161 -297.404551) (xy 78.20152 -297.404028) (xy 59.810142 -297.404028)
			(xy 50.832766 -288.426652) (xy 41.21404 -288.426652) (xy 40.992044 -288.204656) (xy 40.979912 -288.193195)
			(xy 40.951033 -288.176486) (xy 40.91881 -288.167835) (xy 40.885446 -288.167835) (xy 40.853223 -288.176486)
			(xy 40.824344 -288.193195) (xy 40.812212 -288.204656) (xy 40.7797 -288.237168) (xy 40.771572 -288.328354)
			(xy 40.79748 -288.3662) (xy 40.812561 -288.389004) (xy 40.836792 -288.438011) (xy 40.85378 -288.489975)
			(xy 40.863177 -288.543831) (xy 40.864791 -288.598477) (xy 40.858587 -288.652795) (xy 40.844695 -288.70567)
			(xy 40.823397 -288.756021) (xy 40.79513 -288.802817) (xy 40.760473 -288.845098) (xy 40.720136 -288.882)
			(xy 40.674945 -288.912766) (xy 40.625825 -288.936767) (xy 40.573781 -288.953511) (xy 40.519881 -288.962654)
			(xy 40.465228 -288.964011) (xy 40.410941 -288.957552) (xy 40.358131 -288.943411) (xy 40.307881 -288.921877)
			(xy 40.261219 -288.89339) (xy 40.219101 -288.858535) (xy 40.182389 -288.818025) (xy 40.151835 -288.772689)
			(xy 40.128066 -288.723457) (xy 40.111567 -288.671336) (xy 40.102677 -288.617393) (xy 40.101577 -288.562734)
			(xy 40.108291 -288.508478) (xy 40.12268 -288.455735) (xy 40.144451 -288.405587) (xy 40.173156 -288.359059)
			(xy 40.208209 -288.317105) (xy 40.248892 -288.280584) (xy 40.29437 -288.250244) (xy 40.343714 -288.226707)
			(xy 40.395912 -288.210453) (xy 40.42283 -288.205672) (xy 40.445758 -288.201566) (xy 40.489647 -288.185972)
			(xy 40.529962 -288.162647) (xy 40.565355 -288.132368) (xy 40.594642 -288.096151) (xy 40.616842 -288.055205)
			(xy 40.631214 -288.010901) (xy 40.637277 -287.96472) (xy 40.634828 -287.918208) (xy 40.623948 -287.872919)
			(xy 40.605003 -287.83037) (xy 40.578625 -287.791982) (xy 40.56253 -287.775142) (xy 39.906194 -287.11906)
			(xy 39.885116 -287.097367) (xy 39.848013 -287.049594) (xy 39.81717 -286.997561) (xy 39.79307 -286.942081)
			(xy 39.776092 -286.884024) (xy 39.7665 -286.824302) (xy 39.764446 -286.763849) (xy 39.769961 -286.703612)
			(xy 39.78296 -286.644538) (xy 39.792656 -286.615886) (xy 39.799556 -286.594893) (xy 39.806951 -286.551334)
			(xy 39.806697 -286.507152) (xy 39.798802 -286.463681) (xy 39.783505 -286.422231) (xy 39.761267 -286.384053)
			(xy 39.732758 -286.350299) (xy 39.698839 -286.321987) (xy 39.660533 -286.29997) (xy 39.618996 -286.284914)
			(xy 39.575479 -286.277271) (xy 39.553388 -286.276796) (xy 38.342316 -286.276796) (xy 37.887148 -286.731964)
			(xy 36.581588 -286.731964) (xy 36.559547 -286.732464) (xy 36.51613 -286.740089) (xy 36.47468 -286.755093)
			(xy 36.436441 -286.777023) (xy 36.40256 -286.805224) (xy 36.374053 -286.838847) (xy 36.351775 -286.876886)
			(xy 36.336396 -286.918197) (xy 36.328376 -286.961543) (xy 36.327955 -287.005623) (xy 36.335148 -287.049114)
			(xy 36.349737 -287.090712) (xy 36.3601 -287.11017) (xy 36.380944 -287.148367) (xy 36.416289 -287.227887)
			(xy 36.444137 -287.310333) (xy 36.46425 -287.394999) (xy 36.476455 -287.48116) (xy 36.480648 -287.568081)
			(xy 36.476793 -287.655018) (xy 36.464923 -287.741226) (xy 36.44514 -287.82597) (xy 36.417612 -287.908523)
			(xy 36.382576 -287.98818) (xy 36.340331 -288.06426) (xy 36.291238 -288.136112) (xy 36.235717 -288.203121)
			(xy 36.174243 -288.264715) (xy 36.107342 -288.320366) (xy 36.035585 -288.369598) (xy 35.959588 -288.411991)
			(xy 35.879999 -288.447182) (xy 35.797499 -288.47487) (xy 35.712794 -288.494818) (xy 35.626609 -288.506855)
			(xy 35.53968 -288.510879) (xy 35.452751 -288.506855) (xy 35.366566 -288.494818) (xy 35.281861 -288.47487)
			(xy 35.199361 -288.447182) (xy 35.119772 -288.411991) (xy 35.043775 -288.369598) (xy 34.972018 -288.320366)
			(xy 34.905117 -288.264715) (xy 34.843643 -288.203121) (xy 34.788122 -288.136112) (xy 34.739029 -288.06426)
			(xy 34.696784 -287.98818) (xy 34.661748 -287.908523) (xy 34.63422 -287.82597) (xy 34.614437 -287.741226)
			(xy 34.602567 -287.655018) (xy 34.598712 -287.568081) (xy 34.602905 -287.48116) (xy 34.61511 -287.394999)
			(xy 34.635223 -287.310333) (xy 34.663071 -287.227887) (xy 34.698416 -287.148367) (xy 34.71926 -287.11017)
			(xy 34.72963 -287.090709) (xy 34.744244 -287.049109) (xy 34.751456 -287.005611) (xy 34.75105 -286.96152)
			(xy 34.743038 -286.918162) (xy 34.72766 -286.876839) (xy 34.705379 -286.838791) (xy 34.676862 -286.805161)
			(xy 34.642968 -286.776959) (xy 34.604714 -286.755033) (xy 34.563249 -286.740041) (xy 34.519818 -286.732434)
			(xy 34.497772 -286.731964) (xy 34.34842 -286.731964) (xy 31.812738 -284.196536) (xy 31.503874 -284.196536)
			(xy 31.481879 -284.196965) (xy 31.43855 -284.204562) (xy 31.397176 -284.219506) (xy 31.358994 -284.241352)
			(xy 31.325144 -284.269447) (xy 31.296638 -284.302952) (xy 31.274327 -284.340864) (xy 31.258879 -284.382053)
			(xy 31.250754 -284.425286) (xy 31.250195 -284.469273) (xy 31.257219 -284.512698) (xy 31.271616 -284.554266)
			(xy 31.281878 -284.573726) (xy 31.302503 -284.611931) (xy 31.337449 -284.691415) (xy 31.364918 -284.773783)
			(xy 31.384677 -284.858333) (xy 31.396556 -284.944344) (xy 31.400454 -285.031084) (xy 31.396339 -285.117814)
			(xy 31.384246 -285.203795) (xy 31.364277 -285.288295) (xy 31.336602 -285.370594) (xy 31.301458 -285.449991)
			(xy 31.259143 -285.52581) (xy 31.210018 -285.597404) (xy 31.154502 -285.664165) (xy 31.093068 -285.725523)
			(xy 31.026238 -285.780956) (xy 30.954582 -285.829991) (xy 30.87871 -285.872211) (xy 30.79927 -285.907256)
			(xy 30.716936 -285.934828) (xy 30.632411 -285.954692) (xy 30.546415 -285.966678) (xy 30.45968 -285.970685)
			(xy 30.372945 -285.966678) (xy 30.286949 -285.954692) (xy 30.202424 -285.934828) (xy 30.12009 -285.907256)
			(xy 30.04065 -285.872211) (xy 29.964778 -285.829991) (xy 29.893122 -285.780956) (xy 29.826292 -285.725523)
			(xy 29.764858 -285.664165) (xy 29.709342 -285.597404) (xy 29.660217 -285.52581) (xy 29.617902 -285.449991)
			(xy 29.582758 -285.370594) (xy 29.555083 -285.288295) (xy 29.535114 -285.203795) (xy 29.523021 -285.117814)
			(xy 29.518906 -285.031084) (xy 29.522804 -284.944344) (xy 29.534683 -284.858333) (xy 29.554442 -284.773783)
			(xy 29.581911 -284.691415) (xy 29.616857 -284.611931) (xy 29.637482 -284.573726) (xy 29.647771 -284.554274)
			(xy 29.6622 -284.512706) (xy 29.669248 -284.469273) (xy 29.668705 -284.425275) (xy 29.660587 -284.382029)
			(xy 29.645138 -284.340829) (xy 29.622819 -284.302909) (xy 29.594298 -284.269402) (xy 29.56043 -284.241312)
			(xy 29.522227 -284.21948) (xy 29.480833 -284.204558) (xy 29.437487 -284.196994) (xy 29.415486 -284.196536)
			(xy 28.660598 -284.196536) (xy 28.234132 -283.77007) (xy 28.21213 -283.747337) (xy 28.173617 -283.697145)
			(xy 28.141984 -283.642356) (xy 28.117773 -283.583906) (xy 28.101399 -283.522797) (xy 28.093141 -283.460073)
			(xy 9.049598 -283.460073) (xy 9.055388 -283.47516) (xy 9.073217 -283.543413) (xy 9.083378 -283.61322)
			(xy 9.085747 -283.683724) (xy 9.080294 -283.754056) (xy 9.067088 -283.823351) (xy 9.057132 -283.857192)
			(xy 9.051231 -283.877957) (xy 9.04571 -283.920766) (xy 9.047503 -283.963893) (xy 9.056556 -284.006097)
			(xy 9.072611 -284.046164) (xy 9.086501 -284.068774) (xy 26.32659 -284.068774) (xy 26.330661 -284.013152)
			(xy 26.342787 -283.958715) (xy 26.36271 -283.906624) (xy 26.390006 -283.857989) (xy 26.424092 -283.813846)
			(xy 26.464241 -283.775137) (xy 26.509599 -283.742686) (xy 26.559199 -283.717185) (xy 26.611983 -283.699178)
			(xy 26.666826 -283.689048) (xy 26.72256 -283.687011) (xy 26.777997 -283.693111) (xy 26.831954 -283.707217)
			(xy 26.883283 -283.729029) (xy 26.930889 -283.758083) (xy 26.973757 -283.793758) (xy 27.010974 -283.835295)
			(xy 27.041747 -283.881808) (xy 27.065419 -283.932305) (xy 27.081487 -283.985712) (xy 27.089607 -284.040888)
			(xy 27.090116 -284.068774) (xy 27.089607 -284.09666) (xy 27.081487 -284.151836) (xy 27.065419 -284.205243)
			(xy 27.041747 -284.25574) (xy 27.010974 -284.302253) (xy 26.973757 -284.34379) (xy 26.930889 -284.379465)
			(xy 26.883283 -284.408519) (xy 26.831954 -284.430331) (xy 26.777997 -284.444437) (xy 26.72256 -284.450537)
			(xy 26.666826 -284.4485) (xy 26.611983 -284.43837) (xy 26.559199 -284.420363) (xy 26.509599 -284.394862)
			(xy 26.464241 -284.362411) (xy 26.424092 -284.323702) (xy 26.390006 -284.279559) (xy 26.36271 -284.230924)
			(xy 26.342787 -284.178833) (xy 26.330661 -284.124396) (xy 26.32659 -284.068774) (xy 9.086501 -284.068774)
			(xy 9.095205 -284.082942) (xy 9.123689 -284.115374) (xy 9.157244 -284.142526) (xy 9.194903 -284.163618)
			(xy 9.235586 -284.178043) (xy 9.278121 -284.185387) (xy 9.299702 -284.185868) (xy 9.525 -284.185868)
			(xy 10.026396 -284.687264) (xy 21.130514 -284.687264) (xy 22.426676 -285.983426) (xy 26.461718 -285.983426)
			(xy 26.465789 -285.927804) (xy 26.477915 -285.873367) (xy 26.497838 -285.821276) (xy 26.525134 -285.772641)
			(xy 26.55922 -285.728498) (xy 26.599369 -285.689789) (xy 26.644727 -285.657338) (xy 26.694327 -285.631837)
			(xy 26.747111 -285.61383) (xy 26.801954 -285.6037) (xy 26.857688 -285.601663) (xy 26.913125 -285.607763)
			(xy 26.967082 -285.621869) (xy 27.018411 -285.643681) (xy 27.066017 -285.672735) (xy 27.108885 -285.70841)
			(xy 27.146102 -285.749947) (xy 27.176875 -285.79646) (xy 27.200547 -285.846957) (xy 27.216615 -285.900364)
			(xy 27.224735 -285.95554) (xy 27.225244 -285.983426) (xy 27.224735 -286.011312) (xy 27.216615 -286.066488)
			(xy 27.200547 -286.119895) (xy 27.176875 -286.170392) (xy 27.146102 -286.216905) (xy 27.108885 -286.258442)
			(xy 27.066017 -286.294117) (xy 27.018411 -286.323171) (xy 26.967082 -286.344983) (xy 26.913125 -286.359089)
			(xy 26.857688 -286.365189) (xy 26.801954 -286.363152) (xy 26.747111 -286.353022) (xy 26.694327 -286.335015)
			(xy 26.644727 -286.309514) (xy 26.599369 -286.277063) (xy 26.55922 -286.238354) (xy 26.525134 -286.194211)
			(xy 26.497838 -286.145576) (xy 26.477915 -286.093485) (xy 26.465789 -286.039048) (xy 26.461718 -285.983426)
			(xy 22.426676 -285.983426) (xy 23.281894 -286.838644) (xy 27.168854 -286.838644) (xy 27.172925 -286.783022)
			(xy 27.185051 -286.728585) (xy 27.204974 -286.676494) (xy 27.23227 -286.627859) (xy 27.266356 -286.583716)
			(xy 27.306505 -286.545007) (xy 27.351863 -286.512556) (xy 27.401463 -286.487055) (xy 27.454247 -286.469048)
			(xy 27.50909 -286.458918) (xy 27.564824 -286.456881) (xy 27.620261 -286.462981) (xy 27.674218 -286.477087)
			(xy 27.725547 -286.498899) (xy 27.773153 -286.527953) (xy 27.816021 -286.563628) (xy 27.853238 -286.605165)
			(xy 27.884011 -286.651678) (xy 27.907683 -286.702175) (xy 27.923751 -286.755582) (xy 27.931871 -286.810758)
			(xy 27.93238 -286.838644) (xy 27.931871 -286.86653) (xy 27.923751 -286.921706) (xy 27.907683 -286.975113)
			(xy 27.884011 -287.02561) (xy 27.853238 -287.072123) (xy 27.816021 -287.11366) (xy 27.773153 -287.149335)
			(xy 27.725547 -287.178389) (xy 27.674218 -287.200201) (xy 27.620261 -287.214307) (xy 27.564824 -287.220407)
			(xy 27.50909 -287.21837) (xy 27.454247 -287.20824) (xy 27.401463 -287.190233) (xy 27.351863 -287.164732)
			(xy 27.306505 -287.132281) (xy 27.266356 -287.093572) (xy 27.23227 -287.049429) (xy 27.204974 -287.000794)
			(xy 27.185051 -286.948703) (xy 27.172925 -286.894266) (xy 27.168854 -286.838644) (xy 23.281894 -286.838644)
			(xy 24.05661 -287.61336) (xy 29.519874 -287.61336) (xy 29.519874 -287.52646) (xy 29.527892 -287.439931)
			(xy 29.54386 -287.354511) (xy 29.567641 -287.270929) (xy 29.599033 -287.189897) (xy 29.637767 -287.112108)
			(xy 29.683514 -287.038224) (xy 29.735883 -286.968877) (xy 29.794427 -286.904657) (xy 29.858647 -286.846113)
			(xy 29.927994 -286.793744) (xy 30.001878 -286.747997) (xy 30.079667 -286.709263) (xy 30.160699 -286.677871)
			(xy 30.244281 -286.65409) (xy 30.329701 -286.638122) (xy 30.41623 -286.630104) (xy 30.50313 -286.630104)
			(xy 30.589659 -286.638122) (xy 30.675079 -286.65409) (xy 30.758661 -286.677871) (xy 30.839693 -286.709263)
			(xy 30.917482 -286.747997) (xy 30.991366 -286.793744) (xy 31.060713 -286.846113) (xy 31.124933 -286.904657)
			(xy 31.183477 -286.968877) (xy 31.235846 -287.038224) (xy 31.281593 -287.112108) (xy 31.320327 -287.189897)
			(xy 31.351719 -287.270929) (xy 31.3755 -287.354511) (xy 31.391468 -287.439931) (xy 31.399486 -287.52646)
			(xy 31.399988 -287.56991) (xy 31.399486 -287.61336) (xy 31.391468 -287.699889) (xy 31.3755 -287.785309)
			(xy 31.351719 -287.868891) (xy 31.320327 -287.949923) (xy 31.281593 -288.027712) (xy 31.235846 -288.101596)
			(xy 31.183477 -288.170943) (xy 31.124933 -288.235163) (xy 31.060713 -288.293707) (xy 30.991366 -288.346076)
			(xy 30.917482 -288.391823) (xy 30.839693 -288.430557) (xy 30.758661 -288.461949) (xy 30.675079 -288.48573)
			(xy 30.589659 -288.501698) (xy 30.50313 -288.509716) (xy 30.41623 -288.509716) (xy 30.329701 -288.501698)
			(xy 30.244281 -288.48573) (xy 30.160699 -288.461949) (xy 30.079667 -288.430557) (xy 30.001878 -288.391823)
			(xy 29.927994 -288.346076) (xy 29.858647 -288.293707) (xy 29.794427 -288.235163) (xy 29.735883 -288.170943)
			(xy 29.683514 -288.101596) (xy 29.637767 -288.027712) (xy 29.599033 -287.949923) (xy 29.567641 -287.868891)
			(xy 29.54386 -287.785309) (xy 29.527892 -287.699889) (xy 29.519874 -287.61336) (xy 24.05661 -287.61336)
			(xy 26.59661 -290.15336) (xy 29.519874 -290.15336) (xy 29.519874 -290.06646) (xy 29.527892 -289.979931)
			(xy 29.54386 -289.894511) (xy 29.567641 -289.810929) (xy 29.599033 -289.729897) (xy 29.637767 -289.652108)
			(xy 29.683514 -289.578224) (xy 29.735883 -289.508877) (xy 29.794427 -289.444657) (xy 29.858647 -289.386113)
			(xy 29.927994 -289.333744) (xy 30.001878 -289.287997) (xy 30.079667 -289.249263) (xy 30.160699 -289.217871)
			(xy 30.244281 -289.19409) (xy 30.329701 -289.178122) (xy 30.41623 -289.170104) (xy 30.50313 -289.170104)
			(xy 30.589659 -289.178122) (xy 30.675079 -289.19409) (xy 30.758661 -289.217871) (xy 30.839693 -289.249263)
			(xy 30.917482 -289.287997) (xy 30.991366 -289.333744) (xy 31.060713 -289.386113) (xy 31.124933 -289.444657)
			(xy 31.183477 -289.508877) (xy 31.235846 -289.578224) (xy 31.281593 -289.652108) (xy 31.320327 -289.729897)
			(xy 31.351719 -289.810929) (xy 31.3755 -289.894511) (xy 31.391468 -289.979931) (xy 31.399486 -290.06646)
			(xy 31.399988 -290.10991) (xy 31.399486 -290.15336) (xy 34.599874 -290.15336) (xy 34.599874 -290.06646)
			(xy 34.607892 -289.979931) (xy 34.62386 -289.894511) (xy 34.647641 -289.810929) (xy 34.679033 -289.729897)
			(xy 34.717767 -289.652108) (xy 34.763514 -289.578224) (xy 34.815883 -289.508877) (xy 34.874427 -289.444657)
			(xy 34.938647 -289.386113) (xy 35.007994 -289.333744) (xy 35.081878 -289.287997) (xy 35.159667 -289.249263)
			(xy 35.240699 -289.217871) (xy 35.324281 -289.19409) (xy 35.409701 -289.178122) (xy 35.49623 -289.170104)
			(xy 35.58313 -289.170104) (xy 35.669659 -289.178122) (xy 35.755079 -289.19409) (xy 35.838661 -289.217871)
			(xy 35.919693 -289.249263) (xy 35.997482 -289.287997) (xy 36.071366 -289.333744) (xy 36.140713 -289.386113)
			(xy 36.204933 -289.444657) (xy 36.263477 -289.508877) (xy 36.315846 -289.578224) (xy 36.361593 -289.652108)
			(xy 36.400327 -289.729897) (xy 36.431719 -289.810929) (xy 36.4555 -289.894511) (xy 36.471468 -289.979931)
			(xy 36.479486 -290.06646) (xy 36.479988 -290.10991) (xy 36.479486 -290.15336) (xy 36.471468 -290.239889)
			(xy 36.4555 -290.325309) (xy 36.431719 -290.408891) (xy 36.400327 -290.489923) (xy 36.361593 -290.567712)
			(xy 36.315846 -290.641596) (xy 36.263477 -290.710943) (xy 36.204933 -290.775163) (xy 36.140713 -290.833707)
			(xy 36.071366 -290.886076) (xy 35.997482 -290.931823) (xy 35.919693 -290.970557) (xy 35.838661 -291.001949)
			(xy 35.755079 -291.02573) (xy 35.669659 -291.041698) (xy 35.58313 -291.049716) (xy 35.49623 -291.049716)
			(xy 35.409701 -291.041698) (xy 35.324281 -291.02573) (xy 35.240699 -291.001949) (xy 35.159667 -290.970557)
			(xy 35.081878 -290.931823) (xy 35.007994 -290.886076) (xy 34.938647 -290.833707) (xy 34.874427 -290.775163)
			(xy 34.815883 -290.710943) (xy 34.763514 -290.641596) (xy 34.717767 -290.567712) (xy 34.679033 -290.489923)
			(xy 34.647641 -290.408891) (xy 34.62386 -290.325309) (xy 34.607892 -290.239889) (xy 34.599874 -290.15336)
			(xy 31.399486 -290.15336) (xy 31.391468 -290.239889) (xy 31.3755 -290.325309) (xy 31.351719 -290.408891)
			(xy 31.320327 -290.489923) (xy 31.281593 -290.567712) (xy 31.235846 -290.641596) (xy 31.183477 -290.710943)
			(xy 31.124933 -290.775163) (xy 31.060713 -290.833707) (xy 30.991366 -290.886076) (xy 30.917482 -290.931823)
			(xy 30.839693 -290.970557) (xy 30.758661 -291.001949) (xy 30.675079 -291.02573) (xy 30.589659 -291.041698)
			(xy 30.50313 -291.049716) (xy 30.41623 -291.049716) (xy 30.329701 -291.041698) (xy 30.244281 -291.02573)
			(xy 30.160699 -291.001949) (xy 30.079667 -290.970557) (xy 30.001878 -290.931823) (xy 29.927994 -290.886076)
			(xy 29.858647 -290.833707) (xy 29.794427 -290.775163) (xy 29.735883 -290.710943) (xy 29.683514 -290.641596)
			(xy 29.637767 -290.567712) (xy 29.599033 -290.489923) (xy 29.567641 -290.408891) (xy 29.54386 -290.325309)
			(xy 29.527892 -290.239889) (xy 29.519874 -290.15336) (xy 26.59661 -290.15336) (xy 28.912312 -292.469062)
			(xy 28.912312 -292.69336) (xy 29.519874 -292.69336) (xy 29.519874 -292.60646) (xy 29.527892 -292.519931)
			(xy 29.54386 -292.434511) (xy 29.567641 -292.350929) (xy 29.599033 -292.269897) (xy 29.637767 -292.192108)
			(xy 29.683514 -292.118224) (xy 29.735883 -292.048877) (xy 29.794427 -291.984657) (xy 29.858647 -291.926113)
			(xy 29.927994 -291.873744) (xy 30.001878 -291.827997) (xy 30.079667 -291.789263) (xy 30.160699 -291.757871)
			(xy 30.244281 -291.73409) (xy 30.329701 -291.718122) (xy 30.41623 -291.710104) (xy 30.50313 -291.710104)
			(xy 30.589659 -291.718122) (xy 30.675079 -291.73409) (xy 30.758661 -291.757871) (xy 30.839693 -291.789263)
			(xy 30.917482 -291.827997) (xy 30.991366 -291.873744) (xy 31.060713 -291.926113) (xy 31.124933 -291.984657)
			(xy 31.183477 -292.048877) (xy 31.235846 -292.118224) (xy 31.281593 -292.192108) (xy 31.320327 -292.269897)
			(xy 31.351719 -292.350929) (xy 31.3755 -292.434511) (xy 31.391468 -292.519931) (xy 31.399486 -292.60646)
			(xy 31.399988 -292.64991) (xy 31.399486 -292.69336) (xy 34.599874 -292.69336) (xy 34.599874 -292.60646)
			(xy 34.607892 -292.519931) (xy 34.62386 -292.434511) (xy 34.647641 -292.350929) (xy 34.679033 -292.269897)
			(xy 34.717767 -292.192108) (xy 34.763514 -292.118224) (xy 34.815883 -292.048877) (xy 34.874427 -291.984657)
			(xy 34.938647 -291.926113) (xy 35.007994 -291.873744) (xy 35.081878 -291.827997) (xy 35.159667 -291.789263)
			(xy 35.240699 -291.757871) (xy 35.324281 -291.73409) (xy 35.409701 -291.718122) (xy 35.49623 -291.710104)
			(xy 35.58313 -291.710104) (xy 35.669659 -291.718122) (xy 35.755079 -291.73409) (xy 35.838661 -291.757871)
			(xy 35.919693 -291.789263) (xy 35.997482 -291.827997) (xy 36.071366 -291.873744) (xy 36.140713 -291.926113)
			(xy 36.204933 -291.984657) (xy 36.263477 -292.048877) (xy 36.315846 -292.118224) (xy 36.361593 -292.192108)
			(xy 36.400327 -292.269897) (xy 36.431719 -292.350929) (xy 36.4555 -292.434511) (xy 36.471468 -292.519931)
			(xy 36.479486 -292.60646) (xy 36.479988 -292.64991) (xy 36.479486 -292.69336) (xy 36.471468 -292.779889)
			(xy 36.4555 -292.865309) (xy 36.431719 -292.948891) (xy 36.400327 -293.029923) (xy 36.361593 -293.107712)
			(xy 36.315846 -293.181596) (xy 36.263477 -293.250943) (xy 36.204933 -293.315163) (xy 36.140713 -293.373707)
			(xy 36.071366 -293.426076) (xy 35.997482 -293.471823) (xy 35.919693 -293.510557) (xy 35.838661 -293.541949)
			(xy 35.755079 -293.56573) (xy 35.669659 -293.581698) (xy 35.58313 -293.589716) (xy 35.49623 -293.589716)
			(xy 35.409701 -293.581698) (xy 35.324281 -293.56573) (xy 35.240699 -293.541949) (xy 35.159667 -293.510557)
			(xy 35.081878 -293.471823) (xy 35.007994 -293.426076) (xy 34.938647 -293.373707) (xy 34.874427 -293.315163)
			(xy 34.815883 -293.250943) (xy 34.763514 -293.181596) (xy 34.717767 -293.107712) (xy 34.679033 -293.029923)
			(xy 34.647641 -292.948891) (xy 34.62386 -292.865309) (xy 34.607892 -292.779889) (xy 34.599874 -292.69336)
			(xy 31.399486 -292.69336) (xy 31.391468 -292.779889) (xy 31.3755 -292.865309) (xy 31.351719 -292.948891)
			(xy 31.320327 -293.029923) (xy 31.281593 -293.107712) (xy 31.235846 -293.181596) (xy 31.183477 -293.250943)
			(xy 31.124933 -293.315163) (xy 31.060713 -293.373707) (xy 30.991366 -293.426076) (xy 30.917482 -293.471823)
			(xy 30.839693 -293.510557) (xy 30.758661 -293.541949) (xy 30.675079 -293.56573) (xy 30.589659 -293.581698)
			(xy 30.50313 -293.589716) (xy 30.41623 -293.589716) (xy 30.329701 -293.581698) (xy 30.244281 -293.56573)
			(xy 30.160699 -293.541949) (xy 30.079667 -293.510557) (xy 30.001878 -293.471823) (xy 29.927994 -293.426076)
			(xy 29.858647 -293.373707) (xy 29.794427 -293.315163) (xy 29.735883 -293.250943) (xy 29.683514 -293.181596)
			(xy 29.637767 -293.107712) (xy 29.599033 -293.029923) (xy 29.567641 -292.948891) (xy 29.54386 -292.865309)
			(xy 29.527892 -292.779889) (xy 29.519874 -292.69336) (xy 28.912312 -292.69336) (xy 28.912312 -295.23336)
			(xy 29.519874 -295.23336) (xy 29.519874 -295.14646) (xy 29.527892 -295.059931) (xy 29.54386 -294.974511)
			(xy 29.567641 -294.890929) (xy 29.599033 -294.809897) (xy 29.637767 -294.732108) (xy 29.683514 -294.658224)
			(xy 29.735883 -294.588877) (xy 29.794427 -294.524657) (xy 29.858647 -294.466113) (xy 29.927994 -294.413744)
			(xy 30.001878 -294.367997) (xy 30.079667 -294.329263) (xy 30.160699 -294.297871) (xy 30.244281 -294.27409)
			(xy 30.329701 -294.258122) (xy 30.41623 -294.250104) (xy 30.50313 -294.250104) (xy 30.589659 -294.258122)
			(xy 30.675079 -294.27409) (xy 30.758661 -294.297871) (xy 30.839693 -294.329263) (xy 30.917482 -294.367997)
			(xy 30.991366 -294.413744) (xy 31.060713 -294.466113) (xy 31.124933 -294.524657) (xy 31.183477 -294.588877)
			(xy 31.235846 -294.658224) (xy 31.281593 -294.732108) (xy 31.320327 -294.809897) (xy 31.351719 -294.890929)
			(xy 31.3755 -294.974511) (xy 31.391468 -295.059931) (xy 31.399486 -295.14646) (xy 31.399988 -295.18991)
			(xy 31.399486 -295.23336) (xy 34.599874 -295.23336) (xy 34.599874 -295.14646) (xy 34.607892 -295.059931)
			(xy 34.62386 -294.974511) (xy 34.647641 -294.890929) (xy 34.679033 -294.809897) (xy 34.717767 -294.732108)
			(xy 34.763514 -294.658224) (xy 34.815883 -294.588877) (xy 34.874427 -294.524657) (xy 34.938647 -294.466113)
			(xy 35.007994 -294.413744) (xy 35.081878 -294.367997) (xy 35.159667 -294.329263) (xy 35.240699 -294.297871)
			(xy 35.324281 -294.27409) (xy 35.409701 -294.258122) (xy 35.49623 -294.250104) (xy 35.58313 -294.250104)
			(xy 35.669659 -294.258122) (xy 35.755079 -294.27409) (xy 35.838661 -294.297871) (xy 35.919693 -294.329263)
			(xy 35.997482 -294.367997) (xy 36.071366 -294.413744) (xy 36.140713 -294.466113) (xy 36.204933 -294.524657)
			(xy 36.263477 -294.588877) (xy 36.315846 -294.658224) (xy 36.361593 -294.732108) (xy 36.400327 -294.809897)
			(xy 36.431719 -294.890929) (xy 36.4555 -294.974511) (xy 36.471468 -295.059931) (xy 36.479486 -295.14646)
			(xy 36.479988 -295.18991) (xy 36.479486 -295.23336) (xy 36.471468 -295.319889) (xy 36.4555 -295.405309)
			(xy 36.431719 -295.488891) (xy 36.400327 -295.569923) (xy 36.361593 -295.647712) (xy 36.315846 -295.721596)
			(xy 36.263477 -295.790943) (xy 36.204933 -295.855163) (xy 36.140713 -295.913707) (xy 36.071366 -295.966076)
			(xy 35.997482 -296.011823) (xy 35.919693 -296.050557) (xy 35.838661 -296.081949) (xy 35.755079 -296.10573)
			(xy 35.669659 -296.121698) (xy 35.58313 -296.129716) (xy 35.49623 -296.129716) (xy 35.409701 -296.121698)
			(xy 35.324281 -296.10573) (xy 35.240699 -296.081949) (xy 35.159667 -296.050557) (xy 35.081878 -296.011823)
			(xy 35.007994 -295.966076) (xy 34.938647 -295.913707) (xy 34.874427 -295.855163) (xy 34.815883 -295.790943)
			(xy 34.763514 -295.721596) (xy 34.717767 -295.647712) (xy 34.679033 -295.569923) (xy 34.647641 -295.488891)
			(xy 34.62386 -295.405309) (xy 34.607892 -295.319889) (xy 34.599874 -295.23336) (xy 31.399486 -295.23336)
			(xy 31.391468 -295.319889) (xy 31.3755 -295.405309) (xy 31.351719 -295.488891) (xy 31.320327 -295.569923)
			(xy 31.281593 -295.647712) (xy 31.235846 -295.721596) (xy 31.183477 -295.790943) (xy 31.124933 -295.855163)
			(xy 31.060713 -295.913707) (xy 30.991366 -295.966076) (xy 30.917482 -296.011823) (xy 30.839693 -296.050557)
			(xy 30.758661 -296.081949) (xy 30.675079 -296.10573) (xy 30.589659 -296.121698) (xy 30.50313 -296.129716)
			(xy 30.41623 -296.129716) (xy 30.329701 -296.121698) (xy 30.244281 -296.10573) (xy 30.160699 -296.081949)
			(xy 30.079667 -296.050557) (xy 30.001878 -296.011823) (xy 29.927994 -295.966076) (xy 29.858647 -295.913707)
			(xy 29.794427 -295.855163) (xy 29.735883 -295.790943) (xy 29.683514 -295.721596) (xy 29.637767 -295.647712)
			(xy 29.599033 -295.569923) (xy 29.567641 -295.488891) (xy 29.54386 -295.405309) (xy 29.527892 -295.319889)
			(xy 29.519874 -295.23336) (xy 28.912312 -295.23336) (xy 28.912312 -297.77336) (xy 29.519874 -297.77336)
			(xy 29.519874 -297.68646) (xy 29.527892 -297.599931) (xy 29.54386 -297.514511) (xy 29.567641 -297.430929)
			(xy 29.599033 -297.349897) (xy 29.637767 -297.272108) (xy 29.683514 -297.198224) (xy 29.735883 -297.128877)
			(xy 29.794427 -297.064657) (xy 29.858647 -297.006113) (xy 29.927994 -296.953744) (xy 30.001878 -296.907997)
			(xy 30.079667 -296.869263) (xy 30.160699 -296.837871) (xy 30.244281 -296.81409) (xy 30.329701 -296.798122)
			(xy 30.41623 -296.790104) (xy 30.50313 -296.790104) (xy 30.589659 -296.798122) (xy 30.675079 -296.81409)
			(xy 30.758661 -296.837871) (xy 30.839693 -296.869263) (xy 30.917482 -296.907997) (xy 30.991366 -296.953744)
			(xy 31.060713 -297.006113) (xy 31.124933 -297.064657) (xy 31.183477 -297.128877) (xy 31.235846 -297.198224)
			(xy 31.281593 -297.272108) (xy 31.320327 -297.349897) (xy 31.351719 -297.430929) (xy 31.3755 -297.514511)
			(xy 31.391468 -297.599931) (xy 31.399486 -297.68646) (xy 31.399988 -297.72991) (xy 31.399486 -297.77336)
			(xy 34.599874 -297.77336) (xy 34.599874 -297.68646) (xy 34.607892 -297.599931) (xy 34.62386 -297.514511)
			(xy 34.647641 -297.430929) (xy 34.679033 -297.349897) (xy 34.717767 -297.272108) (xy 34.763514 -297.198224)
			(xy 34.815883 -297.128877) (xy 34.874427 -297.064657) (xy 34.938647 -297.006113) (xy 35.007994 -296.953744)
			(xy 35.081878 -296.907997) (xy 35.159667 -296.869263) (xy 35.240699 -296.837871) (xy 35.324281 -296.81409)
			(xy 35.409701 -296.798122) (xy 35.49623 -296.790104) (xy 35.58313 -296.790104) (xy 35.669659 -296.798122)
			(xy 35.755079 -296.81409) (xy 35.838661 -296.837871) (xy 35.919693 -296.869263) (xy 35.997482 -296.907997)
			(xy 36.071366 -296.953744) (xy 36.094295 -296.971059) (xy 38.258488 -296.971059) (xy 38.258488 -296.899737)
			(xy 38.266474 -296.828863) (xy 38.282344 -296.759328) (xy 38.305901 -296.692008) (xy 38.336846 -296.627749)
			(xy 38.374792 -296.567358) (xy 38.419261 -296.511596) (xy 38.469694 -296.461163) (xy 38.525456 -296.416694)
			(xy 38.585847 -296.378748) (xy 38.650106 -296.347803) (xy 38.717426 -296.324246) (xy 38.786961 -296.308376)
			(xy 38.857835 -296.30039) (xy 38.929157 -296.30039) (xy 39.000031 -296.308376) (xy 39.069566 -296.324246)
			(xy 39.136886 -296.347803) (xy 39.201145 -296.378748) (xy 39.261536 -296.416694) (xy 39.317298 -296.461163)
			(xy 39.367731 -296.511596) (xy 39.4122 -296.567358) (xy 39.450146 -296.627749) (xy 39.481091 -296.692008)
			(xy 39.504648 -296.759328) (xy 39.520518 -296.828863) (xy 39.528504 -296.899737) (xy 39.529004 -296.935398)
			(xy 39.528504 -296.971059) (xy 40.1452 -296.971059) (xy 40.1452 -296.899737) (xy 40.153186 -296.828863)
			(xy 40.169056 -296.759328) (xy 40.192613 -296.692008) (xy 40.223558 -296.627749) (xy 40.261504 -296.567358)
			(xy 40.305973 -296.511596) (xy 40.356406 -296.461163) (xy 40.412168 -296.416694) (xy 40.472559 -296.378748)
			(xy 40.536818 -296.347803) (xy 40.604138 -296.324246) (xy 40.673673 -296.308376) (xy 40.744547 -296.30039)
			(xy 40.815869 -296.30039) (xy 40.886743 -296.308376) (xy 40.956278 -296.324246) (xy 41.023598 -296.347803)
			(xy 41.087857 -296.378748) (xy 41.148248 -296.416694) (xy 41.20401 -296.461163) (xy 41.254443 -296.511596)
			(xy 41.298912 -296.567358) (xy 41.336858 -296.627749) (xy 41.367803 -296.692008) (xy 41.39136 -296.759328)
			(xy 41.40723 -296.828863) (xy 41.415216 -296.899737) (xy 41.415716 -296.935398) (xy 41.415216 -296.971059)
			(xy 41.40723 -297.041933) (xy 41.39136 -297.111468) (xy 41.367803 -297.178788) (xy 41.336858 -297.243047)
			(xy 41.298912 -297.303438) (xy 41.254443 -297.3592) (xy 41.20401 -297.409633) (xy 41.148248 -297.454102)
			(xy 41.087857 -297.492048) (xy 41.023598 -297.522993) (xy 40.956278 -297.54655) (xy 40.886743 -297.56242)
			(xy 40.815869 -297.570406) (xy 40.744547 -297.570406) (xy 40.673673 -297.56242) (xy 40.604138 -297.54655)
			(xy 40.536818 -297.522993) (xy 40.472559 -297.492048) (xy 40.412168 -297.454102) (xy 40.356406 -297.409633)
			(xy 40.305973 -297.3592) (xy 40.261504 -297.303438) (xy 40.223558 -297.243047) (xy 40.192613 -297.178788)
			(xy 40.169056 -297.111468) (xy 40.153186 -297.041933) (xy 40.1452 -296.971059) (xy 39.528504 -296.971059)
			(xy 39.520518 -297.041933) (xy 39.504648 -297.111468) (xy 39.481091 -297.178788) (xy 39.450146 -297.243047)
			(xy 39.4122 -297.303438) (xy 39.367731 -297.3592) (xy 39.317298 -297.409633) (xy 39.261536 -297.454102)
			(xy 39.201145 -297.492048) (xy 39.136886 -297.522993) (xy 39.069566 -297.54655) (xy 39.000031 -297.56242)
			(xy 38.929157 -297.570406) (xy 38.857835 -297.570406) (xy 38.786961 -297.56242) (xy 38.717426 -297.54655)
			(xy 38.650106 -297.522993) (xy 38.585847 -297.492048) (xy 38.525456 -297.454102) (xy 38.469694 -297.409633)
			(xy 38.419261 -297.3592) (xy 38.374792 -297.303438) (xy 38.336846 -297.243047) (xy 38.305901 -297.178788)
			(xy 38.282344 -297.111468) (xy 38.266474 -297.041933) (xy 38.258488 -296.971059) (xy 36.094295 -296.971059)
			(xy 36.140713 -297.006113) (xy 36.204933 -297.064657) (xy 36.263477 -297.128877) (xy 36.315846 -297.198224)
			(xy 36.361593 -297.272108) (xy 36.400327 -297.349897) (xy 36.431719 -297.430929) (xy 36.4555 -297.514511)
			(xy 36.471468 -297.599931) (xy 36.479486 -297.68646) (xy 36.479988 -297.72991) (xy 36.479486 -297.77336)
			(xy 36.471468 -297.859889) (xy 36.4555 -297.945309) (xy 36.431719 -298.028891) (xy 36.400327 -298.109923)
			(xy 36.361593 -298.187712) (xy 36.315846 -298.261596) (xy 36.263477 -298.330943) (xy 36.204933 -298.395163)
			(xy 36.140713 -298.453707) (xy 36.071366 -298.506076) (xy 35.997482 -298.551823) (xy 35.919693 -298.590557)
			(xy 35.838661 -298.621949) (xy 35.755079 -298.64573) (xy 35.669659 -298.661698) (xy 35.58313 -298.669716)
			(xy 35.49623 -298.669716) (xy 35.409701 -298.661698) (xy 35.324281 -298.64573) (xy 35.240699 -298.621949)
			(xy 35.159667 -298.590557) (xy 35.081878 -298.551823) (xy 35.007994 -298.506076) (xy 34.938647 -298.453707)
			(xy 34.874427 -298.395163) (xy 34.815883 -298.330943) (xy 34.763514 -298.261596) (xy 34.717767 -298.187712)
			(xy 34.679033 -298.109923) (xy 34.647641 -298.028891) (xy 34.62386 -297.945309) (xy 34.607892 -297.859889)
			(xy 34.599874 -297.77336) (xy 31.399486 -297.77336) (xy 31.391468 -297.859889) (xy 31.3755 -297.945309)
			(xy 31.351719 -298.028891) (xy 31.320327 -298.109923) (xy 31.281593 -298.187712) (xy 31.235846 -298.261596)
			(xy 31.183477 -298.330943) (xy 31.124933 -298.395163) (xy 31.060713 -298.453707) (xy 30.991366 -298.506076)
			(xy 30.917482 -298.551823) (xy 30.839693 -298.590557) (xy 30.758661 -298.621949) (xy 30.675079 -298.64573)
			(xy 30.589659 -298.661698) (xy 30.50313 -298.669716) (xy 30.41623 -298.669716) (xy 30.329701 -298.661698)
			(xy 30.244281 -298.64573) (xy 30.160699 -298.621949) (xy 30.079667 -298.590557) (xy 30.001878 -298.551823)
			(xy 29.927994 -298.506076) (xy 29.858647 -298.453707) (xy 29.794427 -298.395163) (xy 29.735883 -298.330943)
			(xy 29.683514 -298.261596) (xy 29.637767 -298.187712) (xy 29.599033 -298.109923) (xy 29.567641 -298.028891)
			(xy 29.54386 -297.945309) (xy 29.527892 -297.859889) (xy 29.519874 -297.77336) (xy 28.912312 -297.77336)
			(xy 28.912312 -298.804685) (xy 38.258488 -298.804685) (xy 38.258488 -298.733363) (xy 38.266474 -298.662489)
			(xy 38.282344 -298.592954) (xy 38.305901 -298.525634) (xy 38.336846 -298.461375) (xy 38.374792 -298.400984)
			(xy 38.419261 -298.345222) (xy 38.469694 -298.294789) (xy 38.525456 -298.25032) (xy 38.585847 -298.212374)
			(xy 38.650106 -298.181429) (xy 38.717426 -298.157872) (xy 38.786961 -298.142002) (xy 38.857835 -298.134016)
			(xy 38.929157 -298.134016) (xy 39.000031 -298.142002) (xy 39.069566 -298.157872) (xy 39.136886 -298.181429)
			(xy 39.201145 -298.212374) (xy 39.261536 -298.25032) (xy 39.317298 -298.294789) (xy 39.367731 -298.345222)
			(xy 39.4122 -298.400984) (xy 39.450146 -298.461375) (xy 39.481091 -298.525634) (xy 39.504648 -298.592954)
			(xy 39.520518 -298.662489) (xy 39.528504 -298.733363) (xy 39.529004 -298.769024) (xy 39.528504 -298.804685)
			(xy 40.1452 -298.804685) (xy 40.1452 -298.733363) (xy 40.153186 -298.662489) (xy 40.169056 -298.592954)
			(xy 40.192613 -298.525634) (xy 40.223558 -298.461375) (xy 40.261504 -298.400984) (xy 40.305973 -298.345222)
			(xy 40.356406 -298.294789) (xy 40.412168 -298.25032) (xy 40.472559 -298.212374) (xy 40.536818 -298.181429)
			(xy 40.604138 -298.157872) (xy 40.673673 -298.142002) (xy 40.744547 -298.134016) (xy 40.815869 -298.134016)
			(xy 40.886743 -298.142002) (xy 40.956278 -298.157872) (xy 41.023598 -298.181429) (xy 41.087857 -298.212374)
			(xy 41.148248 -298.25032) (xy 41.20401 -298.294789) (xy 41.254443 -298.345222) (xy 41.298912 -298.400984)
			(xy 41.336858 -298.461375) (xy 41.367803 -298.525634) (xy 41.39136 -298.592954) (xy 41.40723 -298.662489)
			(xy 41.415216 -298.733363) (xy 41.415716 -298.769024) (xy 41.415216 -298.804685) (xy 42.386242 -298.804685)
			(xy 42.386242 -298.733363) (xy 42.394228 -298.662489) (xy 42.410098 -298.592954) (xy 42.433655 -298.525634)
			(xy 42.4646 -298.461375) (xy 42.502546 -298.400984) (xy 42.547015 -298.345222) (xy 42.597448 -298.294789)
			(xy 42.65321 -298.25032) (xy 42.713601 -298.212374) (xy 42.77786 -298.181429) (xy 42.84518 -298.157872)
			(xy 42.914715 -298.142002) (xy 42.985589 -298.134016) (xy 43.056911 -298.134016) (xy 43.127785 -298.142002)
			(xy 43.19732 -298.157872) (xy 43.26464 -298.181429) (xy 43.328899 -298.212374) (xy 43.38929 -298.25032)
			(xy 43.445052 -298.294789) (xy 43.495485 -298.345222) (xy 43.539954 -298.400984) (xy 43.5779 -298.461375)
			(xy 43.608845 -298.525634) (xy 43.632402 -298.592954) (xy 43.648272 -298.662489) (xy 43.656258 -298.733363)
			(xy 43.656758 -298.769024) (xy 43.656258 -298.804685) (xy 44.290226 -298.804685) (xy 44.290226 -298.733363)
			(xy 44.298212 -298.662489) (xy 44.314082 -298.592954) (xy 44.337639 -298.525634) (xy 44.368584 -298.461375)
			(xy 44.40653 -298.400984) (xy 44.450999 -298.345222) (xy 44.501432 -298.294789) (xy 44.557194 -298.25032)
			(xy 44.617585 -298.212374) (xy 44.681844 -298.181429) (xy 44.749164 -298.157872) (xy 44.818699 -298.142002)
			(xy 44.889573 -298.134016) (xy 44.960895 -298.134016) (xy 45.031769 -298.142002) (xy 45.101304 -298.157872)
			(xy 45.168624 -298.181429) (xy 45.232883 -298.212374) (xy 45.293274 -298.25032) (xy 45.349036 -298.294789)
			(xy 45.399469 -298.345222) (xy 45.443938 -298.400984) (xy 45.481884 -298.461375) (xy 45.512829 -298.525634)
			(xy 45.536386 -298.592954) (xy 45.552256 -298.662489) (xy 45.560242 -298.733363) (xy 45.560742 -298.769024)
			(xy 45.560242 -298.804685) (xy 45.552256 -298.875559) (xy 45.536386 -298.945094) (xy 45.512829 -299.012414)
			(xy 45.481884 -299.076673) (xy 45.443938 -299.137064) (xy 45.399469 -299.192826) (xy 45.349036 -299.243259)
			(xy 45.293274 -299.287728) (xy 45.232883 -299.325674) (xy 45.168624 -299.356619) (xy 45.101304 -299.380176)
			(xy 45.031769 -299.396046) (xy 44.960895 -299.404032) (xy 44.889573 -299.404032) (xy 44.818699 -299.396046)
			(xy 44.749164 -299.380176) (xy 44.681844 -299.356619) (xy 44.617585 -299.325674) (xy 44.557194 -299.287728)
			(xy 44.501432 -299.243259) (xy 44.450999 -299.192826) (xy 44.40653 -299.137064) (xy 44.368584 -299.076673)
			(xy 44.337639 -299.012414) (xy 44.314082 -298.945094) (xy 44.298212 -298.875559) (xy 44.290226 -298.804685)
			(xy 43.656258 -298.804685) (xy 43.648272 -298.875559) (xy 43.632402 -298.945094) (xy 43.608845 -299.012414)
			(xy 43.5779 -299.076673) (xy 43.539954 -299.137064) (xy 43.495485 -299.192826) (xy 43.445052 -299.243259)
			(xy 43.38929 -299.287728) (xy 43.328899 -299.325674) (xy 43.26464 -299.356619) (xy 43.19732 -299.380176)
			(xy 43.127785 -299.396046) (xy 43.056911 -299.404032) (xy 42.985589 -299.404032) (xy 42.914715 -299.396046)
			(xy 42.84518 -299.380176) (xy 42.77786 -299.356619) (xy 42.713601 -299.325674) (xy 42.65321 -299.287728)
			(xy 42.597448 -299.243259) (xy 42.547015 -299.192826) (xy 42.502546 -299.137064) (xy 42.4646 -299.076673)
			(xy 42.433655 -299.012414) (xy 42.410098 -298.945094) (xy 42.394228 -298.875559) (xy 42.386242 -298.804685)
			(xy 41.415216 -298.804685) (xy 41.40723 -298.875559) (xy 41.39136 -298.945094) (xy 41.367803 -299.012414)
			(xy 41.336858 -299.076673) (xy 41.298912 -299.137064) (xy 41.254443 -299.192826) (xy 41.20401 -299.243259)
			(xy 41.148248 -299.287728) (xy 41.087857 -299.325674) (xy 41.023598 -299.356619) (xy 40.956278 -299.380176)
			(xy 40.886743 -299.396046) (xy 40.815869 -299.404032) (xy 40.744547 -299.404032) (xy 40.673673 -299.396046)
			(xy 40.604138 -299.380176) (xy 40.536818 -299.356619) (xy 40.472559 -299.325674) (xy 40.412168 -299.287728)
			(xy 40.356406 -299.243259) (xy 40.305973 -299.192826) (xy 40.261504 -299.137064) (xy 40.223558 -299.076673)
			(xy 40.192613 -299.012414) (xy 40.169056 -298.945094) (xy 40.153186 -298.875559) (xy 40.1452 -298.804685)
			(xy 39.528504 -298.804685) (xy 39.520518 -298.875559) (xy 39.504648 -298.945094) (xy 39.481091 -299.012414)
			(xy 39.450146 -299.076673) (xy 39.4122 -299.137064) (xy 39.367731 -299.192826) (xy 39.317298 -299.243259)
			(xy 39.261536 -299.287728) (xy 39.201145 -299.325674) (xy 39.136886 -299.356619) (xy 39.069566 -299.380176)
			(xy 39.000031 -299.396046) (xy 38.929157 -299.404032) (xy 38.857835 -299.404032) (xy 38.786961 -299.396046)
			(xy 38.717426 -299.380176) (xy 38.650106 -299.356619) (xy 38.585847 -299.325674) (xy 38.525456 -299.287728)
			(xy 38.469694 -299.243259) (xy 38.419261 -299.192826) (xy 38.374792 -299.137064) (xy 38.336846 -299.076673)
			(xy 38.305901 -299.012414) (xy 38.282344 -298.945094) (xy 38.266474 -298.875559) (xy 38.258488 -298.804685)
			(xy 28.912312 -298.804685) (xy 28.912312 -300.31336) (xy 29.519874 -300.31336) (xy 29.519874 -300.22646)
			(xy 29.527892 -300.139931) (xy 29.54386 -300.054511) (xy 29.567641 -299.970929) (xy 29.599033 -299.889897)
			(xy 29.637767 -299.812108) (xy 29.683514 -299.738224) (xy 29.735883 -299.668877) (xy 29.794427 -299.604657)
			(xy 29.858647 -299.546113) (xy 29.927994 -299.493744) (xy 30.001878 -299.447997) (xy 30.079667 -299.409263)
			(xy 30.160699 -299.377871) (xy 30.244281 -299.35409) (xy 30.329701 -299.338122) (xy 30.41623 -299.330104)
			(xy 30.50313 -299.330104) (xy 30.589659 -299.338122) (xy 30.675079 -299.35409) (xy 30.758661 -299.377871)
			(xy 30.839693 -299.409263) (xy 30.917482 -299.447997) (xy 30.991366 -299.493744) (xy 31.060713 -299.546113)
			(xy 31.124933 -299.604657) (xy 31.183477 -299.668877) (xy 31.235846 -299.738224) (xy 31.281593 -299.812108)
			(xy 31.320327 -299.889897) (xy 31.351719 -299.970929) (xy 31.3755 -300.054511) (xy 31.391468 -300.139931)
			(xy 31.399486 -300.22646) (xy 31.399988 -300.26991) (xy 31.399486 -300.31336) (xy 34.599874 -300.31336)
			(xy 34.599874 -300.22646) (xy 34.607892 -300.139931) (xy 34.62386 -300.054511) (xy 34.647641 -299.970929)
			(xy 34.679033 -299.889897) (xy 34.717767 -299.812108) (xy 34.763514 -299.738224) (xy 34.815883 -299.668877)
			(xy 34.874427 -299.604657) (xy 34.938647 -299.546113) (xy 35.007994 -299.493744) (xy 35.081878 -299.447997)
			(xy 35.159667 -299.409263) (xy 35.240699 -299.377871) (xy 35.324281 -299.35409) (xy 35.409701 -299.338122)
			(xy 35.49623 -299.330104) (xy 35.58313 -299.330104) (xy 35.669659 -299.338122) (xy 35.755079 -299.35409)
			(xy 35.838661 -299.377871) (xy 35.919693 -299.409263) (xy 35.997482 -299.447997) (xy 36.071366 -299.493744)
			(xy 36.140713 -299.546113) (xy 36.204933 -299.604657) (xy 36.263477 -299.668877) (xy 36.271585 -299.679614)
			(xy 97.869246 -299.679614) (xy 97.873317 -299.623992) (xy 97.885443 -299.569555) (xy 97.905366 -299.517464)
			(xy 97.932662 -299.468829) (xy 97.966748 -299.424686) (xy 98.006897 -299.385977) (xy 98.052255 -299.353526)
			(xy 98.101855 -299.328025) (xy 98.154639 -299.310018) (xy 98.209482 -299.299888) (xy 98.265216 -299.297851)
			(xy 98.320653 -299.303951) (xy 98.37461 -299.318057) (xy 98.425939 -299.339869) (xy 98.473545 -299.368923)
			(xy 98.516413 -299.404598) (xy 98.55363 -299.446135) (xy 98.584403 -299.492648) (xy 98.608075 -299.543145)
			(xy 98.624143 -299.596552) (xy 98.632263 -299.651728) (xy 98.632772 -299.679614) (xy 98.632263 -299.7075)
			(xy 98.624143 -299.762676) (xy 98.608075 -299.816083) (xy 98.584403 -299.86658) (xy 98.55363 -299.913093)
			(xy 98.516413 -299.95463) (xy 98.473545 -299.990305) (xy 98.425939 -300.019359) (xy 98.37461 -300.041171)
			(xy 98.320653 -300.055277) (xy 98.265216 -300.061377) (xy 98.209482 -300.05934) (xy 98.154639 -300.04921)
			(xy 98.101855 -300.031203) (xy 98.052255 -300.005702) (xy 98.006897 -299.973251) (xy 97.966748 -299.934542)
			(xy 97.932662 -299.890399) (xy 97.905366 -299.841764) (xy 97.885443 -299.789673) (xy 97.873317 -299.735236)
			(xy 97.869246 -299.679614) (xy 36.271585 -299.679614) (xy 36.315846 -299.738224) (xy 36.361593 -299.812108)
			(xy 36.400327 -299.889897) (xy 36.431719 -299.970929) (xy 36.4555 -300.054511) (xy 36.471468 -300.139931)
			(xy 36.479486 -300.22646) (xy 36.479988 -300.26991) (xy 36.479486 -300.31336) (xy 36.471468 -300.399889)
			(xy 36.4555 -300.485309) (xy 36.431719 -300.568891) (xy 36.400327 -300.649923) (xy 36.372593 -300.705621)
			(xy 38.258488 -300.705621) (xy 38.258488 -300.634299) (xy 38.266474 -300.563425) (xy 38.282344 -300.49389)
			(xy 38.305901 -300.42657) (xy 38.336846 -300.362311) (xy 38.374792 -300.30192) (xy 38.419261 -300.246158)
			(xy 38.469694 -300.195725) (xy 38.525456 -300.151256) (xy 38.585847 -300.11331) (xy 38.650106 -300.082365)
			(xy 38.717426 -300.058808) (xy 38.786961 -300.042938) (xy 38.857835 -300.034952) (xy 38.929157 -300.034952)
			(xy 39.000031 -300.042938) (xy 39.069566 -300.058808) (xy 39.136886 -300.082365) (xy 39.201145 -300.11331)
			(xy 39.261536 -300.151256) (xy 39.317298 -300.195725) (xy 39.367731 -300.246158) (xy 39.4122 -300.30192)
			(xy 39.450146 -300.362311) (xy 39.481091 -300.42657) (xy 39.504648 -300.49389) (xy 39.520518 -300.563425)
			(xy 39.528504 -300.634299) (xy 39.529004 -300.66996) (xy 39.528504 -300.705621) (xy 40.1452 -300.705621)
			(xy 40.1452 -300.634299) (xy 40.153186 -300.563425) (xy 40.169056 -300.49389) (xy 40.192613 -300.42657)
			(xy 40.223558 -300.362311) (xy 40.261504 -300.30192) (xy 40.305973 -300.246158) (xy 40.356406 -300.195725)
			(xy 40.412168 -300.151256) (xy 40.472559 -300.11331) (xy 40.536818 -300.082365) (xy 40.604138 -300.058808)
			(xy 40.673673 -300.042938) (xy 40.744547 -300.034952) (xy 40.815869 -300.034952) (xy 40.886743 -300.042938)
			(xy 40.956278 -300.058808) (xy 41.023598 -300.082365) (xy 41.087857 -300.11331) (xy 41.148248 -300.151256)
			(xy 41.20401 -300.195725) (xy 41.254443 -300.246158) (xy 41.298912 -300.30192) (xy 41.336858 -300.362311)
			(xy 41.367803 -300.42657) (xy 41.39136 -300.49389) (xy 41.40723 -300.563425) (xy 41.415216 -300.634299)
			(xy 41.415716 -300.66996) (xy 41.415216 -300.705621) (xy 42.386242 -300.705621) (xy 42.386242 -300.634299)
			(xy 42.394228 -300.563425) (xy 42.410098 -300.49389) (xy 42.433655 -300.42657) (xy 42.4646 -300.362311)
			(xy 42.502546 -300.30192) (xy 42.547015 -300.246158) (xy 42.597448 -300.195725) (xy 42.65321 -300.151256)
			(xy 42.713601 -300.11331) (xy 42.77786 -300.082365) (xy 42.84518 -300.058808) (xy 42.914715 -300.042938)
			(xy 42.985589 -300.034952) (xy 43.056911 -300.034952) (xy 43.127785 -300.042938) (xy 43.19732 -300.058808)
			(xy 43.26464 -300.082365) (xy 43.328899 -300.11331) (xy 43.38929 -300.151256) (xy 43.445052 -300.195725)
			(xy 43.495485 -300.246158) (xy 43.539954 -300.30192) (xy 43.5779 -300.362311) (xy 43.608845 -300.42657)
			(xy 43.632402 -300.49389) (xy 43.648272 -300.563425) (xy 43.656258 -300.634299) (xy 43.656758 -300.66996)
			(xy 43.656258 -300.705621) (xy 44.290226 -300.705621) (xy 44.290226 -300.634299) (xy 44.298212 -300.563425)
			(xy 44.314082 -300.49389) (xy 44.337639 -300.42657) (xy 44.368584 -300.362311) (xy 44.40653 -300.30192)
			(xy 44.450999 -300.246158) (xy 44.501432 -300.195725) (xy 44.557194 -300.151256) (xy 44.617585 -300.11331)
			(xy 44.681844 -300.082365) (xy 44.749164 -300.058808) (xy 44.818699 -300.042938) (xy 44.889573 -300.034952)
			(xy 44.960895 -300.034952) (xy 45.031769 -300.042938) (xy 45.101304 -300.058808) (xy 45.168624 -300.082365)
			(xy 45.232883 -300.11331) (xy 45.293274 -300.151256) (xy 45.349036 -300.195725) (xy 45.399469 -300.246158)
			(xy 45.443938 -300.30192) (xy 45.481884 -300.362311) (xy 45.512829 -300.42657) (xy 45.536386 -300.49389)
			(xy 45.552256 -300.563425) (xy 45.560242 -300.634299) (xy 45.560742 -300.66996) (xy 45.560242 -300.705621)
			(xy 45.552927 -300.770544) (xy 96.970086 -300.770544) (xy 96.974157 -300.714922) (xy 96.986283 -300.660485)
			(xy 97.006206 -300.608394) (xy 97.033502 -300.559759) (xy 97.067588 -300.515616) (xy 97.107737 -300.476907)
			(xy 97.153095 -300.444456) (xy 97.202695 -300.418955) (xy 97.255479 -300.400948) (xy 97.310322 -300.390818)
			(xy 97.366056 -300.388781) (xy 97.421493 -300.394881) (xy 97.47545 -300.408987) (xy 97.526779 -300.430799)
			(xy 97.574385 -300.459853) (xy 97.617253 -300.495528) (xy 97.65447 -300.537065) (xy 97.685243 -300.583578)
			(xy 97.708915 -300.634075) (xy 97.724983 -300.687482) (xy 97.733103 -300.742658) (xy 97.733612 -300.770544)
			(xy 97.733103 -300.79843) (xy 97.724983 -300.853606) (xy 97.708915 -300.907013) (xy 97.685243 -300.95751)
			(xy 97.65447 -301.004023) (xy 97.617253 -301.04556) (xy 97.574385 -301.081235) (xy 97.526779 -301.110289)
			(xy 97.47545 -301.132101) (xy 97.421493 -301.146207) (xy 97.366056 -301.152307) (xy 97.310322 -301.15027)
			(xy 97.255479 -301.14014) (xy 97.202695 -301.122133) (xy 97.153095 -301.096632) (xy 97.107737 -301.064181)
			(xy 97.067588 -301.025472) (xy 97.033502 -300.981329) (xy 97.006206 -300.932694) (xy 96.986283 -300.880603)
			(xy 96.974157 -300.826166) (xy 96.970086 -300.770544) (xy 45.552927 -300.770544) (xy 45.552256 -300.776495)
			(xy 45.536386 -300.84603) (xy 45.512829 -300.91335) (xy 45.481884 -300.977609) (xy 45.443938 -301.038)
			(xy 45.399469 -301.093762) (xy 45.349036 -301.144195) (xy 45.293274 -301.188664) (xy 45.232883 -301.22661)
			(xy 45.168624 -301.257555) (xy 45.101304 -301.281112) (xy 45.031769 -301.296982) (xy 44.960895 -301.304968)
			(xy 44.889573 -301.304968) (xy 44.818699 -301.296982) (xy 44.749164 -301.281112) (xy 44.681844 -301.257555)
			(xy 44.617585 -301.22661) (xy 44.557194 -301.188664) (xy 44.501432 -301.144195) (xy 44.450999 -301.093762)
			(xy 44.40653 -301.038) (xy 44.368584 -300.977609) (xy 44.337639 -300.91335) (xy 44.314082 -300.84603)
			(xy 44.298212 -300.776495) (xy 44.290226 -300.705621) (xy 43.656258 -300.705621) (xy 43.648272 -300.776495)
			(xy 43.632402 -300.84603) (xy 43.608845 -300.91335) (xy 43.5779 -300.977609) (xy 43.539954 -301.038)
			(xy 43.495485 -301.093762) (xy 43.445052 -301.144195) (xy 43.38929 -301.188664) (xy 43.328899 -301.22661)
			(xy 43.26464 -301.257555) (xy 43.19732 -301.281112) (xy 43.127785 -301.296982) (xy 43.056911 -301.304968)
			(xy 42.985589 -301.304968) (xy 42.914715 -301.296982) (xy 42.84518 -301.281112) (xy 42.77786 -301.257555)
			(xy 42.713601 -301.22661) (xy 42.65321 -301.188664) (xy 42.597448 -301.144195) (xy 42.547015 -301.093762)
			(xy 42.502546 -301.038) (xy 42.4646 -300.977609) (xy 42.433655 -300.91335) (xy 42.410098 -300.84603)
			(xy 42.394228 -300.776495) (xy 42.386242 -300.705621) (xy 41.415216 -300.705621) (xy 41.40723 -300.776495)
			(xy 41.39136 -300.84603) (xy 41.367803 -300.91335) (xy 41.336858 -300.977609) (xy 41.298912 -301.038)
			(xy 41.254443 -301.093762) (xy 41.20401 -301.144195) (xy 41.148248 -301.188664) (xy 41.087857 -301.22661)
			(xy 41.023598 -301.257555) (xy 40.956278 -301.281112) (xy 40.886743 -301.296982) (xy 40.815869 -301.304968)
			(xy 40.744547 -301.304968) (xy 40.673673 -301.296982) (xy 40.604138 -301.281112) (xy 40.536818 -301.257555)
			(xy 40.472559 -301.22661) (xy 40.412168 -301.188664) (xy 40.356406 -301.144195) (xy 40.305973 -301.093762)
			(xy 40.261504 -301.038) (xy 40.223558 -300.977609) (xy 40.192613 -300.91335) (xy 40.169056 -300.84603)
			(xy 40.153186 -300.776495) (xy 40.1452 -300.705621) (xy 39.528504 -300.705621) (xy 39.520518 -300.776495)
			(xy 39.504648 -300.84603) (xy 39.481091 -300.91335) (xy 39.450146 -300.977609) (xy 39.4122 -301.038)
			(xy 39.367731 -301.093762) (xy 39.317298 -301.144195) (xy 39.261536 -301.188664) (xy 39.201145 -301.22661)
			(xy 39.136886 -301.257555) (xy 39.069566 -301.281112) (xy 39.000031 -301.296982) (xy 38.929157 -301.304968)
			(xy 38.857835 -301.304968) (xy 38.786961 -301.296982) (xy 38.717426 -301.281112) (xy 38.650106 -301.257555)
			(xy 38.585847 -301.22661) (xy 38.525456 -301.188664) (xy 38.469694 -301.144195) (xy 38.419261 -301.093762)
			(xy 38.374792 -301.038) (xy 38.336846 -300.977609) (xy 38.305901 -300.91335) (xy 38.282344 -300.84603)
			(xy 38.266474 -300.776495) (xy 38.258488 -300.705621) (xy 36.372593 -300.705621) (xy 36.361593 -300.727712)
			(xy 36.315846 -300.801596) (xy 36.263477 -300.870943) (xy 36.204933 -300.935163) (xy 36.140713 -300.993707)
			(xy 36.071366 -301.046076) (xy 35.997482 -301.091823) (xy 35.919693 -301.130557) (xy 35.838661 -301.161949)
			(xy 35.755079 -301.18573) (xy 35.669659 -301.201698) (xy 35.58313 -301.209716) (xy 35.49623 -301.209716)
			(xy 35.409701 -301.201698) (xy 35.324281 -301.18573) (xy 35.240699 -301.161949) (xy 35.159667 -301.130557)
			(xy 35.081878 -301.091823) (xy 35.007994 -301.046076) (xy 34.938647 -300.993707) (xy 34.874427 -300.935163)
			(xy 34.815883 -300.870943) (xy 34.763514 -300.801596) (xy 34.717767 -300.727712) (xy 34.679033 -300.649923)
			(xy 34.647641 -300.568891) (xy 34.62386 -300.485309) (xy 34.607892 -300.399889) (xy 34.599874 -300.31336)
			(xy 31.399486 -300.31336) (xy 31.391468 -300.399889) (xy 31.3755 -300.485309) (xy 31.351719 -300.568891)
			(xy 31.320327 -300.649923) (xy 31.281593 -300.727712) (xy 31.235846 -300.801596) (xy 31.183477 -300.870943)
			(xy 31.124933 -300.935163) (xy 31.060713 -300.993707) (xy 30.991366 -301.046076) (xy 30.917482 -301.091823)
			(xy 30.839693 -301.130557) (xy 30.758661 -301.161949) (xy 30.675079 -301.18573) (xy 30.589659 -301.201698)
			(xy 30.50313 -301.209716) (xy 30.41623 -301.209716) (xy 30.329701 -301.201698) (xy 30.244281 -301.18573)
			(xy 30.160699 -301.161949) (xy 30.079667 -301.130557) (xy 30.001878 -301.091823) (xy 29.927994 -301.046076)
			(xy 29.858647 -300.993707) (xy 29.794427 -300.935163) (xy 29.735883 -300.870943) (xy 29.683514 -300.801596)
			(xy 29.637767 -300.727712) (xy 29.599033 -300.649923) (xy 29.567641 -300.568891) (xy 29.54386 -300.485309)
			(xy 29.527892 -300.399889) (xy 29.519874 -300.31336) (xy 28.912312 -300.31336) (xy 28.912312 -302.85336)
			(xy 29.519874 -302.85336) (xy 29.519874 -302.76646) (xy 29.527892 -302.679931) (xy 29.54386 -302.594511)
			(xy 29.567641 -302.510929) (xy 29.599033 -302.429897) (xy 29.637767 -302.352108) (xy 29.683514 -302.278224)
			(xy 29.735883 -302.208877) (xy 29.794427 -302.144657) (xy 29.858647 -302.086113) (xy 29.927994 -302.033744)
			(xy 30.001878 -301.987997) (xy 30.079667 -301.949263) (xy 30.160699 -301.917871) (xy 30.244281 -301.89409)
			(xy 30.329701 -301.878122) (xy 30.41623 -301.870104) (xy 30.50313 -301.870104) (xy 30.589659 -301.878122)
			(xy 30.675079 -301.89409) (xy 30.758661 -301.917871) (xy 30.839693 -301.949263) (xy 30.917482 -301.987997)
			(xy 30.991366 -302.033744) (xy 31.060713 -302.086113) (xy 31.124933 -302.144657) (xy 31.183477 -302.208877)
			(xy 31.235846 -302.278224) (xy 31.281593 -302.352108) (xy 31.320327 -302.429897) (xy 31.351719 -302.510929)
			(xy 31.3755 -302.594511) (xy 31.391468 -302.679931) (xy 31.399486 -302.76646) (xy 31.399988 -302.80991)
			(xy 31.399486 -302.85336) (xy 34.599874 -302.85336) (xy 34.599874 -302.76646) (xy 34.607892 -302.679931)
			(xy 34.62386 -302.594511) (xy 34.647641 -302.510929) (xy 34.679033 -302.429897) (xy 34.717767 -302.352108)
			(xy 34.763514 -302.278224) (xy 34.815883 -302.208877) (xy 34.874427 -302.144657) (xy 34.938647 -302.086113)
			(xy 35.007994 -302.033744) (xy 35.081878 -301.987997) (xy 35.159667 -301.949263) (xy 35.240699 -301.917871)
			(xy 35.324281 -301.89409) (xy 35.409701 -301.878122) (xy 35.49623 -301.870104) (xy 35.58313 -301.870104)
			(xy 35.669659 -301.878122) (xy 35.755079 -301.89409) (xy 35.838661 -301.917871) (xy 35.919693 -301.949263)
			(xy 35.997482 -301.987997) (xy 36.071366 -302.033744) (xy 36.140713 -302.086113) (xy 36.204933 -302.144657)
			(xy 36.263477 -302.208877) (xy 36.315846 -302.278224) (xy 36.361593 -302.352108) (xy 36.375855 -302.380751)
			(xy 38.258488 -302.380751) (xy 38.258488 -302.309429) (xy 38.266474 -302.238555) (xy 38.282344 -302.16902)
			(xy 38.305901 -302.1017) (xy 38.336846 -302.037441) (xy 38.374792 -301.97705) (xy 38.419261 -301.921288)
			(xy 38.469694 -301.870855) (xy 38.525456 -301.826386) (xy 38.585847 -301.78844) (xy 38.650106 -301.757495)
			(xy 38.717426 -301.733938) (xy 38.786961 -301.718068) (xy 38.857835 -301.710082) (xy 38.929157 -301.710082)
			(xy 39.000031 -301.718068) (xy 39.069566 -301.733938) (xy 39.136886 -301.757495) (xy 39.201145 -301.78844)
			(xy 39.261536 -301.826386) (xy 39.317298 -301.870855) (xy 39.367731 -301.921288) (xy 39.4122 -301.97705)
			(xy 39.450146 -302.037441) (xy 39.481091 -302.1017) (xy 39.504648 -302.16902) (xy 39.520518 -302.238555)
			(xy 39.528504 -302.309429) (xy 39.529004 -302.34509) (xy 39.528504 -302.380751) (xy 40.1452 -302.380751)
			(xy 40.1452 -302.309429) (xy 40.153186 -302.238555) (xy 40.169056 -302.16902) (xy 40.192613 -302.1017)
			(xy 40.223558 -302.037441) (xy 40.261504 -301.97705) (xy 40.305973 -301.921288) (xy 40.356406 -301.870855)
			(xy 40.412168 -301.826386) (xy 40.472559 -301.78844) (xy 40.536818 -301.757495) (xy 40.604138 -301.733938)
			(xy 40.673673 -301.718068) (xy 40.744547 -301.710082) (xy 40.815869 -301.710082) (xy 40.886743 -301.718068)
			(xy 40.956278 -301.733938) (xy 41.023598 -301.757495) (xy 41.087857 -301.78844) (xy 41.148248 -301.826386)
			(xy 41.20401 -301.870855) (xy 41.254443 -301.921288) (xy 41.298912 -301.97705) (xy 41.336858 -302.037441)
			(xy 41.367803 -302.1017) (xy 41.39136 -302.16902) (xy 41.40723 -302.238555) (xy 41.415216 -302.309429)
			(xy 41.415716 -302.34509) (xy 41.415216 -302.380751) (xy 42.386242 -302.380751) (xy 42.386242 -302.309429)
			(xy 42.394228 -302.238555) (xy 42.410098 -302.16902) (xy 42.433655 -302.1017) (xy 42.4646 -302.037441)
			(xy 42.502546 -301.97705) (xy 42.547015 -301.921288) (xy 42.597448 -301.870855) (xy 42.65321 -301.826386)
			(xy 42.713601 -301.78844) (xy 42.77786 -301.757495) (xy 42.84518 -301.733938) (xy 42.914715 -301.718068)
			(xy 42.985589 -301.710082) (xy 43.056911 -301.710082) (xy 43.127785 -301.718068) (xy 43.19732 -301.733938)
			(xy 43.26464 -301.757495) (xy 43.328899 -301.78844) (xy 43.38929 -301.826386) (xy 43.445052 -301.870855)
			(xy 43.495485 -301.921288) (xy 43.539954 -301.97705) (xy 43.5779 -302.037441) (xy 43.608845 -302.1017)
			(xy 43.632402 -302.16902) (xy 43.648272 -302.238555) (xy 43.656258 -302.309429) (xy 43.656758 -302.34509)
			(xy 43.656258 -302.380751) (xy 44.290226 -302.380751) (xy 44.290226 -302.309429) (xy 44.298212 -302.238555)
			(xy 44.314082 -302.16902) (xy 44.337639 -302.1017) (xy 44.368584 -302.037441) (xy 44.40653 -301.97705)
			(xy 44.450999 -301.921288) (xy 44.501432 -301.870855) (xy 44.557194 -301.826386) (xy 44.617585 -301.78844)
			(xy 44.681844 -301.757495) (xy 44.749164 -301.733938) (xy 44.818699 -301.718068) (xy 44.889573 -301.710082)
			(xy 44.960895 -301.710082) (xy 45.031769 -301.718068) (xy 45.101304 -301.733938) (xy 45.168624 -301.757495)
			(xy 45.232883 -301.78844) (xy 45.293274 -301.826386) (xy 45.349036 -301.870855) (xy 45.399469 -301.921288)
			(xy 45.443938 -301.97705) (xy 45.481884 -302.037441) (xy 45.512829 -302.1017) (xy 45.536386 -302.16902)
			(xy 45.544281 -302.203612) (xy 95.969072 -302.203612) (xy 95.973143 -302.14799) (xy 95.985269 -302.093553)
			(xy 96.005192 -302.041462) (xy 96.032488 -301.992827) (xy 96.066574 -301.948684) (xy 96.106723 -301.909975)
			(xy 96.152081 -301.877524) (xy 96.201681 -301.852023) (xy 96.254465 -301.834016) (xy 96.309308 -301.823886)
			(xy 96.365042 -301.821849) (xy 96.420479 -301.827949) (xy 96.474436 -301.842055) (xy 96.525765 -301.863867)
			(xy 96.573371 -301.892921) (xy 96.616239 -301.928596) (xy 96.653456 -301.970133) (xy 96.684229 -302.016646)
			(xy 96.707901 -302.067143) (xy 96.723969 -302.12055) (xy 96.732089 -302.175726) (xy 96.732598 -302.203612)
			(xy 96.732089 -302.231498) (xy 96.723969 -302.286674) (xy 96.707901 -302.340081) (xy 96.684229 -302.390578)
			(xy 96.653456 -302.437091) (xy 96.616239 -302.478628) (xy 96.573371 -302.514303) (xy 96.525765 -302.543357)
			(xy 96.474436 -302.565169) (xy 96.420479 -302.579275) (xy 96.365042 -302.585375) (xy 96.309308 -302.583338)
			(xy 96.254465 -302.573208) (xy 96.201681 -302.555201) (xy 96.152081 -302.5297) (xy 96.106723 -302.497249)
			(xy 96.066574 -302.45854) (xy 96.032488 -302.414397) (xy 96.005192 -302.365762) (xy 95.985269 -302.313671)
			(xy 95.973143 -302.259234) (xy 95.969072 -302.203612) (xy 45.544281 -302.203612) (xy 45.552256 -302.238555)
			(xy 45.560242 -302.309429) (xy 45.560742 -302.34509) (xy 45.560242 -302.380751) (xy 45.552256 -302.451625)
			(xy 45.536386 -302.52116) (xy 45.512829 -302.58848) (xy 45.481884 -302.652739) (xy 45.443938 -302.71313)
			(xy 45.399469 -302.768892) (xy 45.349036 -302.819325) (xy 45.293274 -302.863794) (xy 45.232883 -302.90174)
			(xy 45.168624 -302.932685) (xy 45.101304 -302.956242) (xy 45.031769 -302.972112) (xy 44.960895 -302.980098)
			(xy 44.889573 -302.980098) (xy 44.818699 -302.972112) (xy 44.749164 -302.956242) (xy 44.681844 -302.932685)
			(xy 44.617585 -302.90174) (xy 44.557194 -302.863794) (xy 44.501432 -302.819325) (xy 44.450999 -302.768892)
			(xy 44.40653 -302.71313) (xy 44.368584 -302.652739) (xy 44.337639 -302.58848) (xy 44.314082 -302.52116)
			(xy 44.298212 -302.451625) (xy 44.290226 -302.380751) (xy 43.656258 -302.380751) (xy 43.648272 -302.451625)
			(xy 43.632402 -302.52116) (xy 43.608845 -302.58848) (xy 43.5779 -302.652739) (xy 43.539954 -302.71313)
			(xy 43.495485 -302.768892) (xy 43.445052 -302.819325) (xy 43.38929 -302.863794) (xy 43.328899 -302.90174)
			(xy 43.26464 -302.932685) (xy 43.19732 -302.956242) (xy 43.127785 -302.972112) (xy 43.056911 -302.980098)
			(xy 42.985589 -302.980098) (xy 42.914715 -302.972112) (xy 42.84518 -302.956242) (xy 42.77786 -302.932685)
			(xy 42.713601 -302.90174) (xy 42.65321 -302.863794) (xy 42.597448 -302.819325) (xy 42.547015 -302.768892)
			(xy 42.502546 -302.71313) (xy 42.4646 -302.652739) (xy 42.433655 -302.58848) (xy 42.410098 -302.52116)
			(xy 42.394228 -302.451625) (xy 42.386242 -302.380751) (xy 41.415216 -302.380751) (xy 41.40723 -302.451625)
			(xy 41.39136 -302.52116) (xy 41.367803 -302.58848) (xy 41.336858 -302.652739) (xy 41.298912 -302.71313)
			(xy 41.254443 -302.768892) (xy 41.20401 -302.819325) (xy 41.148248 -302.863794) (xy 41.087857 -302.90174)
			(xy 41.023598 -302.932685) (xy 40.956278 -302.956242) (xy 40.886743 -302.972112) (xy 40.815869 -302.980098)
			(xy 40.744547 -302.980098) (xy 40.673673 -302.972112) (xy 40.604138 -302.956242) (xy 40.536818 -302.932685)
			(xy 40.472559 -302.90174) (xy 40.412168 -302.863794) (xy 40.356406 -302.819325) (xy 40.305973 -302.768892)
			(xy 40.261504 -302.71313) (xy 40.223558 -302.652739) (xy 40.192613 -302.58848) (xy 40.169056 -302.52116)
			(xy 40.153186 -302.451625) (xy 40.1452 -302.380751) (xy 39.528504 -302.380751) (xy 39.520518 -302.451625)
			(xy 39.504648 -302.52116) (xy 39.481091 -302.58848) (xy 39.450146 -302.652739) (xy 39.4122 -302.71313)
			(xy 39.367731 -302.768892) (xy 39.317298 -302.819325) (xy 39.261536 -302.863794) (xy 39.201145 -302.90174)
			(xy 39.136886 -302.932685) (xy 39.069566 -302.956242) (xy 39.000031 -302.972112) (xy 38.929157 -302.980098)
			(xy 38.857835 -302.980098) (xy 38.786961 -302.972112) (xy 38.717426 -302.956242) (xy 38.650106 -302.932685)
			(xy 38.585847 -302.90174) (xy 38.525456 -302.863794) (xy 38.469694 -302.819325) (xy 38.419261 -302.768892)
			(xy 38.374792 -302.71313) (xy 38.336846 -302.652739) (xy 38.305901 -302.58848) (xy 38.282344 -302.52116)
			(xy 38.266474 -302.451625) (xy 38.258488 -302.380751) (xy 36.375855 -302.380751) (xy 36.400327 -302.429897)
			(xy 36.431719 -302.510929) (xy 36.4555 -302.594511) (xy 36.471468 -302.679931) (xy 36.479486 -302.76646)
			(xy 36.479988 -302.80991) (xy 36.479486 -302.85336) (xy 36.471468 -302.939889) (xy 36.4555 -303.025309)
			(xy 36.431719 -303.108891) (xy 36.400327 -303.189923) (xy 36.361593 -303.267712) (xy 36.315846 -303.341596)
			(xy 36.263477 -303.410943) (xy 36.204933 -303.475163) (xy 36.145058 -303.529746) (xy 95.24187 -303.529746)
			(xy 95.245941 -303.474124) (xy 95.258067 -303.419687) (xy 95.27799 -303.367596) (xy 95.305286 -303.318961)
			(xy 95.339372 -303.274818) (xy 95.379521 -303.236109) (xy 95.424879 -303.203658) (xy 95.474479 -303.178157)
			(xy 95.527263 -303.16015) (xy 95.582106 -303.15002) (xy 95.63784 -303.147983) (xy 95.693277 -303.154083)
			(xy 95.747234 -303.168189) (xy 95.798563 -303.190001) (xy 95.846169 -303.219055) (xy 95.889037 -303.25473)
			(xy 95.926254 -303.296267) (xy 95.957027 -303.34278) (xy 95.980699 -303.393277) (xy 95.996767 -303.446684)
			(xy 96.004887 -303.50186) (xy 96.005396 -303.529746) (xy 96.004887 -303.557632) (xy 95.996767 -303.612808)
			(xy 95.980699 -303.666215) (xy 95.957027 -303.716712) (xy 95.926254 -303.763225) (xy 95.889037 -303.804762)
			(xy 95.846169 -303.840437) (xy 95.798563 -303.869491) (xy 95.747234 -303.891303) (xy 95.693277 -303.905409)
			(xy 95.63784 -303.911509) (xy 95.582106 -303.909472) (xy 95.527263 -303.899342) (xy 95.474479 -303.881335)
			(xy 95.424879 -303.855834) (xy 95.379521 -303.823383) (xy 95.339372 -303.784674) (xy 95.305286 -303.740531)
			(xy 95.27799 -303.691896) (xy 95.258067 -303.639805) (xy 95.245941 -303.585368) (xy 95.24187 -303.529746)
			(xy 36.145058 -303.529746) (xy 36.140713 -303.533707) (xy 36.071366 -303.586076) (xy 35.997482 -303.631823)
			(xy 35.919693 -303.670557) (xy 35.838661 -303.701949) (xy 35.755079 -303.72573) (xy 35.669659 -303.741698)
			(xy 35.58313 -303.749716) (xy 35.49623 -303.749716) (xy 35.409701 -303.741698) (xy 35.324281 -303.72573)
			(xy 35.240699 -303.701949) (xy 35.159667 -303.670557) (xy 35.081878 -303.631823) (xy 35.007994 -303.586076)
			(xy 34.938647 -303.533707) (xy 34.874427 -303.475163) (xy 34.815883 -303.410943) (xy 34.763514 -303.341596)
			(xy 34.717767 -303.267712) (xy 34.679033 -303.189923) (xy 34.647641 -303.108891) (xy 34.62386 -303.025309)
			(xy 34.607892 -302.939889) (xy 34.599874 -302.85336) (xy 31.399486 -302.85336) (xy 31.391468 -302.939889)
			(xy 31.3755 -303.025309) (xy 31.351719 -303.108891) (xy 31.320327 -303.189923) (xy 31.281593 -303.267712)
			(xy 31.235846 -303.341596) (xy 31.183477 -303.410943) (xy 31.124933 -303.475163) (xy 31.060713 -303.533707)
			(xy 30.991366 -303.586076) (xy 30.917482 -303.631823) (xy 30.839693 -303.670557) (xy 30.758661 -303.701949)
			(xy 30.675079 -303.72573) (xy 30.589659 -303.741698) (xy 30.50313 -303.749716) (xy 30.41623 -303.749716)
			(xy 30.329701 -303.741698) (xy 30.244281 -303.72573) (xy 30.160699 -303.701949) (xy 30.079667 -303.670557)
			(xy 30.001878 -303.631823) (xy 29.927994 -303.586076) (xy 29.858647 -303.533707) (xy 29.794427 -303.475163)
			(xy 29.735883 -303.410943) (xy 29.683514 -303.341596) (xy 29.637767 -303.267712) (xy 29.599033 -303.189923)
			(xy 29.567641 -303.108891) (xy 29.54386 -303.025309) (xy 29.527892 -302.939889) (xy 29.519874 -302.85336)
			(xy 28.912312 -302.85336) (xy 28.912312 -304.391923) (xy 38.215054 -304.391923) (xy 38.215054 -304.320601)
			(xy 38.22304 -304.249727) (xy 38.23891 -304.180192) (xy 38.262467 -304.112872) (xy 38.293412 -304.048613)
			(xy 38.331358 -303.988222) (xy 38.375827 -303.93246) (xy 38.42626 -303.882027) (xy 38.482022 -303.837558)
			(xy 38.542413 -303.799612) (xy 38.606672 -303.768667) (xy 38.673992 -303.74511) (xy 38.743527 -303.72924)
			(xy 38.814401 -303.721254) (xy 38.885723 -303.721254) (xy 38.956597 -303.72924) (xy 39.026132 -303.74511)
			(xy 39.093452 -303.768667) (xy 39.157711 -303.799612) (xy 39.218102 -303.837558) (xy 39.273864 -303.882027)
			(xy 39.324297 -303.93246) (xy 39.368766 -303.988222) (xy 39.406712 -304.048613) (xy 39.437657 -304.112872)
			(xy 39.461214 -304.180192) (xy 39.477084 -304.249727) (xy 39.48507 -304.320601) (xy 39.48557 -304.356262)
			(xy 39.48507 -304.391923) (xy 40.101766 -304.391923) (xy 40.101766 -304.320601) (xy 40.109752 -304.249727)
			(xy 40.125622 -304.180192) (xy 40.149179 -304.112872) (xy 40.180124 -304.048613) (xy 40.21807 -303.988222)
			(xy 40.262539 -303.93246) (xy 40.312972 -303.882027) (xy 40.368734 -303.837558) (xy 40.429125 -303.799612)
			(xy 40.493384 -303.768667) (xy 40.560704 -303.74511) (xy 40.630239 -303.72924) (xy 40.701113 -303.721254)
			(xy 40.772435 -303.721254) (xy 40.843309 -303.72924) (xy 40.912844 -303.74511) (xy 40.980164 -303.768667)
			(xy 41.044423 -303.799612) (xy 41.104814 -303.837558) (xy 41.160576 -303.882027) (xy 41.211009 -303.93246)
			(xy 41.255478 -303.988222) (xy 41.293424 -304.048613) (xy 41.324369 -304.112872) (xy 41.347926 -304.180192)
			(xy 41.363796 -304.249727) (xy 41.371782 -304.320601) (xy 41.372282 -304.356262) (xy 41.371782 -304.391923)
			(xy 42.342808 -304.391923) (xy 42.342808 -304.320601) (xy 42.350794 -304.249727) (xy 42.366664 -304.180192)
			(xy 42.390221 -304.112872) (xy 42.421166 -304.048613) (xy 42.459112 -303.988222) (xy 42.503581 -303.93246)
			(xy 42.554014 -303.882027) (xy 42.609776 -303.837558) (xy 42.670167 -303.799612) (xy 42.734426 -303.768667)
			(xy 42.801746 -303.74511) (xy 42.871281 -303.72924) (xy 42.942155 -303.721254) (xy 43.013477 -303.721254)
			(xy 43.084351 -303.72924) (xy 43.153886 -303.74511) (xy 43.221206 -303.768667) (xy 43.285465 -303.799612)
			(xy 43.345856 -303.837558) (xy 43.401618 -303.882027) (xy 43.452051 -303.93246) (xy 43.49652 -303.988222)
			(xy 43.534466 -304.048613) (xy 43.565411 -304.112872) (xy 43.588968 -304.180192) (xy 43.604838 -304.249727)
			(xy 43.612824 -304.320601) (xy 43.613324 -304.356262) (xy 43.612824 -304.391923) (xy 44.246792 -304.391923)
			(xy 44.246792 -304.320601) (xy 44.254778 -304.249727) (xy 44.270648 -304.180192) (xy 44.294205 -304.112872)
			(xy 44.32515 -304.048613) (xy 44.363096 -303.988222) (xy 44.407565 -303.93246) (xy 44.457998 -303.882027)
			(xy 44.51376 -303.837558) (xy 44.574151 -303.799612) (xy 44.63841 -303.768667) (xy 44.70573 -303.74511)
			(xy 44.775265 -303.72924) (xy 44.846139 -303.721254) (xy 44.917461 -303.721254) (xy 44.988335 -303.72924)
			(xy 45.05787 -303.74511) (xy 45.12519 -303.768667) (xy 45.189449 -303.799612) (xy 45.24984 -303.837558)
			(xy 45.305602 -303.882027) (xy 45.356035 -303.93246) (xy 45.400504 -303.988222) (xy 45.43845 -304.048613)
			(xy 45.469395 -304.112872) (xy 45.492952 -304.180192) (xy 45.508822 -304.249727) (xy 45.516808 -304.320601)
			(xy 45.517308 -304.356262) (xy 45.516808 -304.391923) (xy 45.508822 -304.462797) (xy 45.492952 -304.532332)
			(xy 45.469395 -304.599652) (xy 45.43845 -304.663911) (xy 45.400504 -304.724302) (xy 45.364161 -304.769875)
			(xy 58.097666 -304.769875) (xy 58.097666 -304.698553) (xy 58.105652 -304.627679) (xy 58.121522 -304.558144)
			(xy 58.145079 -304.490824) (xy 58.176024 -304.426565) (xy 58.21397 -304.366174) (xy 58.258439 -304.310412)
			(xy 58.308872 -304.259979) (xy 58.364634 -304.21551) (xy 58.425025 -304.177564) (xy 58.489284 -304.146619)
			(xy 58.556604 -304.123062) (xy 58.626139 -304.107192) (xy 58.697013 -304.099206) (xy 58.768335 -304.099206)
			(xy 58.839209 -304.107192) (xy 58.908744 -304.123062) (xy 58.976064 -304.146619) (xy 59.040323 -304.177564)
			(xy 59.100714 -304.21551) (xy 59.156476 -304.259979) (xy 59.206909 -304.310412) (xy 59.251378 -304.366174)
			(xy 59.289324 -304.426565) (xy 59.320269 -304.490824) (xy 59.343826 -304.558144) (xy 59.359696 -304.627679)
			(xy 59.367682 -304.698553) (xy 59.368182 -304.734214) (xy 59.367682 -304.769875) (xy 59.984378 -304.769875)
			(xy 59.984378 -304.698553) (xy 59.992364 -304.627679) (xy 60.008234 -304.558144) (xy 60.031791 -304.490824)
			(xy 60.062736 -304.426565) (xy 60.100682 -304.366174) (xy 60.145151 -304.310412) (xy 60.195584 -304.259979)
			(xy 60.251346 -304.21551) (xy 60.311737 -304.177564) (xy 60.375996 -304.146619) (xy 60.443316 -304.123062)
			(xy 60.512851 -304.107192) (xy 60.583725 -304.099206) (xy 60.655047 -304.099206) (xy 60.725921 -304.107192)
			(xy 60.795456 -304.123062) (xy 60.862776 -304.146619) (xy 60.927035 -304.177564) (xy 60.987426 -304.21551)
			(xy 61.043188 -304.259979) (xy 61.093621 -304.310412) (xy 61.13809 -304.366174) (xy 61.176036 -304.426565)
			(xy 61.206981 -304.490824) (xy 61.230538 -304.558144) (xy 61.246408 -304.627679) (xy 61.254394 -304.698553)
			(xy 61.254894 -304.734214) (xy 61.254394 -304.769875) (xy 62.22542 -304.769875) (xy 62.22542 -304.698553)
			(xy 62.233406 -304.627679) (xy 62.249276 -304.558144) (xy 62.272833 -304.490824) (xy 62.303778 -304.426565)
			(xy 62.341724 -304.366174) (xy 62.386193 -304.310412) (xy 62.436626 -304.259979) (xy 62.492388 -304.21551)
			(xy 62.552779 -304.177564) (xy 62.617038 -304.146619) (xy 62.684358 -304.123062) (xy 62.753893 -304.107192)
			(xy 62.824767 -304.099206) (xy 62.896089 -304.099206) (xy 62.966963 -304.107192) (xy 63.036498 -304.123062)
			(xy 63.103818 -304.146619) (xy 63.168077 -304.177564) (xy 63.228468 -304.21551) (xy 63.28423 -304.259979)
			(xy 63.334663 -304.310412) (xy 63.379132 -304.366174) (xy 63.417078 -304.426565) (xy 63.448023 -304.490824)
			(xy 63.47158 -304.558144) (xy 63.48745 -304.627679) (xy 63.495436 -304.698553) (xy 63.495936 -304.734214)
			(xy 63.495436 -304.769875) (xy 64.129404 -304.769875) (xy 64.129404 -304.698553) (xy 64.13739 -304.627679)
			(xy 64.15326 -304.558144) (xy 64.176817 -304.490824) (xy 64.207762 -304.426565) (xy 64.245708 -304.366174)
			(xy 64.290177 -304.310412) (xy 64.34061 -304.259979) (xy 64.396372 -304.21551) (xy 64.456763 -304.177564)
			(xy 64.521022 -304.146619) (xy 64.588342 -304.123062) (xy 64.657877 -304.107192) (xy 64.728751 -304.099206)
			(xy 64.800073 -304.099206) (xy 64.870947 -304.107192) (xy 64.940482 -304.123062) (xy 65.007802 -304.146619)
			(xy 65.072061 -304.177564) (xy 65.132452 -304.21551) (xy 65.188214 -304.259979) (xy 65.238647 -304.310412)
			(xy 65.283116 -304.366174) (xy 65.321062 -304.426565) (xy 65.352007 -304.490824) (xy 65.375564 -304.558144)
			(xy 65.391434 -304.627679) (xy 65.39942 -304.698553) (xy 65.39992 -304.734214) (xy 65.39942 -304.769875)
			(xy 65.39697 -304.791618) (xy 94.531178 -304.791618) (xy 94.535249 -304.735996) (xy 94.547375 -304.681559)
			(xy 94.567298 -304.629468) (xy 94.594594 -304.580833) (xy 94.62868 -304.53669) (xy 94.668829 -304.497981)
			(xy 94.714187 -304.46553) (xy 94.763787 -304.440029) (xy 94.816571 -304.422022) (xy 94.871414 -304.411892)
			(xy 94.927148 -304.409855) (xy 94.982585 -304.415955) (xy 95.036542 -304.430061) (xy 95.087871 -304.451873)
			(xy 95.135477 -304.480927) (xy 95.178345 -304.516602) (xy 95.215562 -304.558139) (xy 95.246335 -304.604652)
			(xy 95.270007 -304.655149) (xy 95.286075 -304.708556) (xy 95.294195 -304.763732) (xy 95.294704 -304.791618)
			(xy 95.294195 -304.819504) (xy 95.286075 -304.87468) (xy 95.270007 -304.928087) (xy 95.246335 -304.978584)
			(xy 95.215562 -305.025097) (xy 95.178345 -305.066634) (xy 95.135477 -305.102309) (xy 95.087871 -305.131363)
			(xy 95.036542 -305.153175) (xy 94.982585 -305.167281) (xy 94.927148 -305.173381) (xy 94.871414 -305.171344)
			(xy 94.816571 -305.161214) (xy 94.763787 -305.143207) (xy 94.714187 -305.117706) (xy 94.668829 -305.085255)
			(xy 94.62868 -305.046546) (xy 94.594594 -305.002403) (xy 94.567298 -304.953768) (xy 94.547375 -304.901677)
			(xy 94.535249 -304.84724) (xy 94.531178 -304.791618) (xy 65.39697 -304.791618) (xy 65.391434 -304.840749)
			(xy 65.375564 -304.910284) (xy 65.352007 -304.977604) (xy 65.321062 -305.041863) (xy 65.283116 -305.102254)
			(xy 65.238647 -305.158016) (xy 65.188214 -305.208449) (xy 65.132452 -305.252918) (xy 65.072061 -305.290864)
			(xy 65.007802 -305.321809) (xy 64.940482 -305.345366) (xy 64.870947 -305.361236) (xy 64.800073 -305.369222)
			(xy 64.728751 -305.369222) (xy 64.657877 -305.361236) (xy 64.588342 -305.345366) (xy 64.521022 -305.321809)
			(xy 64.456763 -305.290864) (xy 64.396372 -305.252918) (xy 64.34061 -305.208449) (xy 64.290177 -305.158016)
			(xy 64.245708 -305.102254) (xy 64.207762 -305.041863) (xy 64.176817 -304.977604) (xy 64.15326 -304.910284)
			(xy 64.13739 -304.840749) (xy 64.129404 -304.769875) (xy 63.495436 -304.769875) (xy 63.48745 -304.840749)
			(xy 63.47158 -304.910284) (xy 63.448023 -304.977604) (xy 63.417078 -305.041863) (xy 63.379132 -305.102254)
			(xy 63.334663 -305.158016) (xy 63.28423 -305.208449) (xy 63.228468 -305.252918) (xy 63.168077 -305.290864)
			(xy 63.103818 -305.321809) (xy 63.036498 -305.345366) (xy 62.966963 -305.361236) (xy 62.896089 -305.369222)
			(xy 62.824767 -305.369222) (xy 62.753893 -305.361236) (xy 62.684358 -305.345366) (xy 62.617038 -305.321809)
			(xy 62.552779 -305.290864) (xy 62.492388 -305.252918) (xy 62.436626 -305.208449) (xy 62.386193 -305.158016)
			(xy 62.341724 -305.102254) (xy 62.303778 -305.041863) (xy 62.272833 -304.977604) (xy 62.249276 -304.910284)
			(xy 62.233406 -304.840749) (xy 62.22542 -304.769875) (xy 61.254394 -304.769875) (xy 61.246408 -304.840749)
			(xy 61.230538 -304.910284) (xy 61.206981 -304.977604) (xy 61.176036 -305.041863) (xy 61.13809 -305.102254)
			(xy 61.093621 -305.158016) (xy 61.043188 -305.208449) (xy 60.987426 -305.252918) (xy 60.927035 -305.290864)
			(xy 60.862776 -305.321809) (xy 60.795456 -305.345366) (xy 60.725921 -305.361236) (xy 60.655047 -305.369222)
			(xy 60.583725 -305.369222) (xy 60.512851 -305.361236) (xy 60.443316 -305.345366) (xy 60.375996 -305.321809)
			(xy 60.311737 -305.290864) (xy 60.251346 -305.252918) (xy 60.195584 -305.208449) (xy 60.145151 -305.158016)
			(xy 60.100682 -305.102254) (xy 60.062736 -305.041863) (xy 60.031791 -304.977604) (xy 60.008234 -304.910284)
			(xy 59.992364 -304.840749) (xy 59.984378 -304.769875) (xy 59.367682 -304.769875) (xy 59.359696 -304.840749)
			(xy 59.343826 -304.910284) (xy 59.320269 -304.977604) (xy 59.289324 -305.041863) (xy 59.251378 -305.102254)
			(xy 59.206909 -305.158016) (xy 59.156476 -305.208449) (xy 59.100714 -305.252918) (xy 59.040323 -305.290864)
			(xy 58.976064 -305.321809) (xy 58.908744 -305.345366) (xy 58.839209 -305.361236) (xy 58.768335 -305.369222)
			(xy 58.697013 -305.369222) (xy 58.626139 -305.361236) (xy 58.556604 -305.345366) (xy 58.489284 -305.321809)
			(xy 58.425025 -305.290864) (xy 58.364634 -305.252918) (xy 58.308872 -305.208449) (xy 58.258439 -305.158016)
			(xy 58.21397 -305.102254) (xy 58.176024 -305.041863) (xy 58.145079 -304.977604) (xy 58.121522 -304.910284)
			(xy 58.105652 -304.840749) (xy 58.097666 -304.769875) (xy 45.364161 -304.769875) (xy 45.356035 -304.780064)
			(xy 45.305602 -304.830497) (xy 45.24984 -304.874966) (xy 45.189449 -304.912912) (xy 45.12519 -304.943857)
			(xy 45.05787 -304.967414) (xy 44.988335 -304.983284) (xy 44.917461 -304.99127) (xy 44.846139 -304.99127)
			(xy 44.775265 -304.983284) (xy 44.70573 -304.967414) (xy 44.63841 -304.943857) (xy 44.574151 -304.912912)
			(xy 44.51376 -304.874966) (xy 44.457998 -304.830497) (xy 44.407565 -304.780064) (xy 44.363096 -304.724302)
			(xy 44.32515 -304.663911) (xy 44.294205 -304.599652) (xy 44.270648 -304.532332) (xy 44.254778 -304.462797)
			(xy 44.246792 -304.391923) (xy 43.612824 -304.391923) (xy 43.604838 -304.462797) (xy 43.588968 -304.532332)
			(xy 43.565411 -304.599652) (xy 43.534466 -304.663911) (xy 43.49652 -304.724302) (xy 43.452051 -304.780064)
			(xy 43.401618 -304.830497) (xy 43.345856 -304.874966) (xy 43.285465 -304.912912) (xy 43.221206 -304.943857)
			(xy 43.153886 -304.967414) (xy 43.084351 -304.983284) (xy 43.013477 -304.99127) (xy 42.942155 -304.99127)
			(xy 42.871281 -304.983284) (xy 42.801746 -304.967414) (xy 42.734426 -304.943857) (xy 42.670167 -304.912912)
			(xy 42.609776 -304.874966) (xy 42.554014 -304.830497) (xy 42.503581 -304.780064) (xy 42.459112 -304.724302)
			(xy 42.421166 -304.663911) (xy 42.390221 -304.599652) (xy 42.366664 -304.532332) (xy 42.350794 -304.462797)
			(xy 42.342808 -304.391923) (xy 41.371782 -304.391923) (xy 41.363796 -304.462797) (xy 41.347926 -304.532332)
			(xy 41.324369 -304.599652) (xy 41.293424 -304.663911) (xy 41.255478 -304.724302) (xy 41.211009 -304.780064)
			(xy 41.160576 -304.830497) (xy 41.104814 -304.874966) (xy 41.044423 -304.912912) (xy 40.980164 -304.943857)
			(xy 40.912844 -304.967414) (xy 40.843309 -304.983284) (xy 40.772435 -304.99127) (xy 40.701113 -304.99127)
			(xy 40.630239 -304.983284) (xy 40.560704 -304.967414) (xy 40.493384 -304.943857) (xy 40.429125 -304.912912)
			(xy 40.368734 -304.874966) (xy 40.312972 -304.830497) (xy 40.262539 -304.780064) (xy 40.21807 -304.724302)
			(xy 40.180124 -304.663911) (xy 40.149179 -304.599652) (xy 40.125622 -304.532332) (xy 40.109752 -304.462797)
			(xy 40.101766 -304.391923) (xy 39.48507 -304.391923) (xy 39.477084 -304.462797) (xy 39.461214 -304.532332)
			(xy 39.437657 -304.599652) (xy 39.406712 -304.663911) (xy 39.368766 -304.724302) (xy 39.324297 -304.780064)
			(xy 39.273864 -304.830497) (xy 39.218102 -304.874966) (xy 39.157711 -304.912912) (xy 39.093452 -304.943857)
			(xy 39.026132 -304.967414) (xy 38.956597 -304.983284) (xy 38.885723 -304.99127) (xy 38.814401 -304.99127)
			(xy 38.743527 -304.983284) (xy 38.673992 -304.967414) (xy 38.606672 -304.943857) (xy 38.542413 -304.912912)
			(xy 38.482022 -304.874966) (xy 38.42626 -304.830497) (xy 38.375827 -304.780064) (xy 38.331358 -304.724302)
			(xy 38.293412 -304.663911) (xy 38.262467 -304.599652) (xy 38.23891 -304.532332) (xy 38.22304 -304.462797)
			(xy 38.215054 -304.391923) (xy 28.912312 -304.391923) (xy 28.912312 -305.39336) (xy 29.519874 -305.39336)
			(xy 29.519874 -305.30646) (xy 29.527892 -305.219931) (xy 29.54386 -305.134511) (xy 29.567641 -305.050929)
			(xy 29.599033 -304.969897) (xy 29.637767 -304.892108) (xy 29.683514 -304.818224) (xy 29.735883 -304.748877)
			(xy 29.794427 -304.684657) (xy 29.858647 -304.626113) (xy 29.927994 -304.573744) (xy 30.001878 -304.527997)
			(xy 30.079667 -304.489263) (xy 30.160699 -304.457871) (xy 30.244281 -304.43409) (xy 30.329701 -304.418122)
			(xy 30.41623 -304.410104) (xy 30.50313 -304.410104) (xy 30.589659 -304.418122) (xy 30.675079 -304.43409)
			(xy 30.758661 -304.457871) (xy 30.839693 -304.489263) (xy 30.917482 -304.527997) (xy 30.991366 -304.573744)
			(xy 31.060713 -304.626113) (xy 31.124933 -304.684657) (xy 31.183477 -304.748877) (xy 31.235846 -304.818224)
			(xy 31.281593 -304.892108) (xy 31.320327 -304.969897) (xy 31.351719 -305.050929) (xy 31.3755 -305.134511)
			(xy 31.391468 -305.219931) (xy 31.399486 -305.30646) (xy 31.399988 -305.34991) (xy 31.399486 -305.39336)
			(xy 34.599874 -305.39336) (xy 34.599874 -305.30646) (xy 34.607892 -305.219931) (xy 34.62386 -305.134511)
			(xy 34.647641 -305.050929) (xy 34.679033 -304.969897) (xy 34.717767 -304.892108) (xy 34.763514 -304.818224)
			(xy 34.815883 -304.748877) (xy 34.874427 -304.684657) (xy 34.938647 -304.626113) (xy 35.007994 -304.573744)
			(xy 35.081878 -304.527997) (xy 35.159667 -304.489263) (xy 35.240699 -304.457871) (xy 35.324281 -304.43409)
			(xy 35.409701 -304.418122) (xy 35.49623 -304.410104) (xy 35.58313 -304.410104) (xy 35.669659 -304.418122)
			(xy 35.755079 -304.43409) (xy 35.838661 -304.457871) (xy 35.919693 -304.489263) (xy 35.997482 -304.527997)
			(xy 36.071366 -304.573744) (xy 36.140713 -304.626113) (xy 36.204933 -304.684657) (xy 36.263477 -304.748877)
			(xy 36.315846 -304.818224) (xy 36.361593 -304.892108) (xy 36.400327 -304.969897) (xy 36.431719 -305.050929)
			(xy 36.4555 -305.134511) (xy 36.471468 -305.219931) (xy 36.479486 -305.30646) (xy 36.479988 -305.34991)
			(xy 36.479486 -305.39336) (xy 36.471468 -305.479889) (xy 36.4555 -305.565309) (xy 36.431719 -305.648891)
			(xy 36.400327 -305.729923) (xy 36.361593 -305.807712) (xy 36.315846 -305.881596) (xy 36.263477 -305.950943)
			(xy 36.204933 -306.015163) (xy 36.140713 -306.073707) (xy 36.071366 -306.126076) (xy 35.997482 -306.171823)
			(xy 35.919693 -306.210557) (xy 35.838661 -306.241949) (xy 35.755079 -306.26573) (xy 35.669659 -306.281698)
			(xy 35.58313 -306.289716) (xy 35.49623 -306.289716) (xy 35.409701 -306.281698) (xy 35.324281 -306.26573)
			(xy 35.240699 -306.241949) (xy 35.159667 -306.210557) (xy 35.081878 -306.171823) (xy 35.007994 -306.126076)
			(xy 34.938647 -306.073707) (xy 34.874427 -306.015163) (xy 34.815883 -305.950943) (xy 34.763514 -305.881596)
			(xy 34.717767 -305.807712) (xy 34.679033 -305.729923) (xy 34.647641 -305.648891) (xy 34.62386 -305.565309)
			(xy 34.607892 -305.479889) (xy 34.599874 -305.39336) (xy 31.399486 -305.39336) (xy 31.391468 -305.479889)
			(xy 31.3755 -305.565309) (xy 31.351719 -305.648891) (xy 31.320327 -305.729923) (xy 31.281593 -305.807712)
			(xy 31.235846 -305.881596) (xy 31.183477 -305.950943) (xy 31.124933 -306.015163) (xy 31.060713 -306.073707)
			(xy 30.991366 -306.126076) (xy 30.917482 -306.171823) (xy 30.839693 -306.210557) (xy 30.758661 -306.241949)
			(xy 30.675079 -306.26573) (xy 30.589659 -306.281698) (xy 30.50313 -306.289716) (xy 30.41623 -306.289716)
			(xy 30.329701 -306.281698) (xy 30.244281 -306.26573) (xy 30.160699 -306.241949) (xy 30.079667 -306.210557)
			(xy 30.001878 -306.171823) (xy 29.927994 -306.126076) (xy 29.858647 -306.073707) (xy 29.794427 -306.015163)
			(xy 29.735883 -305.950943) (xy 29.683514 -305.881596) (xy 29.637767 -305.807712) (xy 29.599033 -305.729923)
			(xy 29.567641 -305.648891) (xy 29.54386 -305.565309) (xy 29.527892 -305.479889) (xy 29.519874 -305.39336)
			(xy 28.912312 -305.39336) (xy 28.912312 -306.423737) (xy 47.775358 -306.423737) (xy 47.775358 -306.342627)
			(xy 47.783308 -306.261908) (xy 47.799131 -306.182357) (xy 47.822676 -306.104741) (xy 47.853715 -306.029805)
			(xy 47.89195 -305.958273) (xy 47.937012 -305.890833) (xy 47.988467 -305.828134) (xy 48.04582 -305.770781)
			(xy 48.108519 -305.719326) (xy 48.175959 -305.674264) (xy 48.247491 -305.636029) (xy 48.322427 -305.60499)
			(xy 48.400043 -305.581445) (xy 48.479594 -305.565622) (xy 48.560313 -305.557672) (xy 48.641423 -305.557672)
			(xy 48.722142 -305.565622) (xy 48.801693 -305.581445) (xy 48.879309 -305.60499) (xy 48.954245 -305.636029)
			(xy 49.025777 -305.674264) (xy 49.093217 -305.719326) (xy 49.155916 -305.770781) (xy 49.213269 -305.828134)
			(xy 49.264724 -305.890833) (xy 49.309786 -305.958273) (xy 49.33217 -306.00015) (xy 93.984824 -306.00015)
			(xy 93.988895 -305.944528) (xy 94.001021 -305.890091) (xy 94.020944 -305.838) (xy 94.04824 -305.789365)
			(xy 94.082326 -305.745222) (xy 94.122475 -305.706513) (xy 94.167833 -305.674062) (xy 94.217433 -305.648561)
			(xy 94.270217 -305.630554) (xy 94.32506 -305.620424) (xy 94.380794 -305.618387) (xy 94.436231 -305.624487)
			(xy 94.490188 -305.638593) (xy 94.541517 -305.660405) (xy 94.589123 -305.689459) (xy 94.631991 -305.725134)
			(xy 94.669208 -305.766671) (xy 94.699981 -305.813184) (xy 94.723653 -305.863681) (xy 94.739721 -305.917088)
			(xy 94.747841 -305.972264) (xy 94.74835 -306.00015) (xy 94.747841 -306.028036) (xy 94.739721 -306.083212)
			(xy 94.723653 -306.136619) (xy 94.699981 -306.187116) (xy 94.669208 -306.233629) (xy 94.631991 -306.275166)
			(xy 94.589123 -306.310841) (xy 94.541517 -306.339895) (xy 94.490188 -306.361707) (xy 94.436231 -306.375813)
			(xy 94.380794 -306.381913) (xy 94.32506 -306.379876) (xy 94.270217 -306.369746) (xy 94.217433 -306.351739)
			(xy 94.167833 -306.326238) (xy 94.122475 -306.293787) (xy 94.082326 -306.255078) (xy 94.04824 -306.210935)
			(xy 94.020944 -306.1623) (xy 94.001021 -306.110209) (xy 93.988895 -306.055772) (xy 93.984824 -306.00015)
			(xy 49.33217 -306.00015) (xy 49.348021 -306.029805) (xy 49.37906 -306.104741) (xy 49.402605 -306.182357)
			(xy 49.418428 -306.261908) (xy 49.426378 -306.342627) (xy 49.426876 -306.383182) (xy 49.426378 -306.423737)
			(xy 49.418428 -306.504456) (xy 49.402605 -306.584007) (xy 49.37906 -306.661623) (xy 49.348021 -306.736559)
			(xy 49.309786 -306.808091) (xy 49.30783 -306.811019) (xy 58.097666 -306.811019) (xy 58.097666 -306.739697)
			(xy 58.105652 -306.668823) (xy 58.121522 -306.599288) (xy 58.145079 -306.531968) (xy 58.176024 -306.467709)
			(xy 58.21397 -306.407318) (xy 58.258439 -306.351556) (xy 58.308872 -306.301123) (xy 58.364634 -306.256654)
			(xy 58.425025 -306.218708) (xy 58.489284 -306.187763) (xy 58.556604 -306.164206) (xy 58.626139 -306.148336)
			(xy 58.697013 -306.14035) (xy 58.768335 -306.14035) (xy 58.839209 -306.148336) (xy 58.908744 -306.164206)
			(xy 58.976064 -306.187763) (xy 59.040323 -306.218708) (xy 59.100714 -306.256654) (xy 59.156476 -306.301123)
			(xy 59.206909 -306.351556) (xy 59.251378 -306.407318) (xy 59.289324 -306.467709) (xy 59.320269 -306.531968)
			(xy 59.343826 -306.599288) (xy 59.359696 -306.668823) (xy 59.367682 -306.739697) (xy 59.368182 -306.775358)
			(xy 59.367682 -306.811019) (xy 59.984378 -306.811019) (xy 59.984378 -306.739697) (xy 59.992364 -306.668823)
			(xy 60.008234 -306.599288) (xy 60.031791 -306.531968) (xy 60.062736 -306.467709) (xy 60.100682 -306.407318)
			(xy 60.145151 -306.351556) (xy 60.195584 -306.301123) (xy 60.251346 -306.256654) (xy 60.311737 -306.218708)
			(xy 60.375996 -306.187763) (xy 60.443316 -306.164206) (xy 60.512851 -306.148336) (xy 60.583725 -306.14035)
			(xy 60.655047 -306.14035) (xy 60.725921 -306.148336) (xy 60.795456 -306.164206) (xy 60.862776 -306.187763)
			(xy 60.927035 -306.218708) (xy 60.987426 -306.256654) (xy 61.043188 -306.301123) (xy 61.093621 -306.351556)
			(xy 61.13809 -306.407318) (xy 61.176036 -306.467709) (xy 61.206981 -306.531968) (xy 61.230538 -306.599288)
			(xy 61.246408 -306.668823) (xy 61.254394 -306.739697) (xy 61.254894 -306.775358) (xy 61.254394 -306.811019)
			(xy 62.22542 -306.811019) (xy 62.22542 -306.739697) (xy 62.233406 -306.668823) (xy 62.249276 -306.599288)
			(xy 62.272833 -306.531968) (xy 62.303778 -306.467709) (xy 62.341724 -306.407318) (xy 62.386193 -306.351556)
			(xy 62.436626 -306.301123) (xy 62.492388 -306.256654) (xy 62.552779 -306.218708) (xy 62.617038 -306.187763)
			(xy 62.684358 -306.164206) (xy 62.753893 -306.148336) (xy 62.824767 -306.14035) (xy 62.896089 -306.14035)
			(xy 62.966963 -306.148336) (xy 63.036498 -306.164206) (xy 63.103818 -306.187763) (xy 63.168077 -306.218708)
			(xy 63.228468 -306.256654) (xy 63.28423 -306.301123) (xy 63.334663 -306.351556) (xy 63.379132 -306.407318)
			(xy 63.417078 -306.467709) (xy 63.448023 -306.531968) (xy 63.47158 -306.599288) (xy 63.48745 -306.668823)
			(xy 63.495436 -306.739697) (xy 63.495936 -306.775358) (xy 63.495436 -306.811019) (xy 64.129404 -306.811019)
			(xy 64.129404 -306.739697) (xy 64.13739 -306.668823) (xy 64.15326 -306.599288) (xy 64.176817 -306.531968)
			(xy 64.207762 -306.467709) (xy 64.245708 -306.407318) (xy 64.290177 -306.351556) (xy 64.34061 -306.301123)
			(xy 64.396372 -306.256654) (xy 64.456763 -306.218708) (xy 64.521022 -306.187763) (xy 64.588342 -306.164206)
			(xy 64.657877 -306.148336) (xy 64.728751 -306.14035) (xy 64.800073 -306.14035) (xy 64.870947 -306.148336)
			(xy 64.940482 -306.164206) (xy 65.007802 -306.187763) (xy 65.072061 -306.218708) (xy 65.132452 -306.256654)
			(xy 65.188214 -306.301123) (xy 65.238647 -306.351556) (xy 65.283116 -306.407318) (xy 65.321062 -306.467709)
			(xy 65.346898 -306.521358) (xy 70.625968 -306.521358) (xy 70.630039 -306.465736) (xy 70.642165 -306.411299)
			(xy 70.662088 -306.359208) (xy 70.689384 -306.310573) (xy 70.72347 -306.26643) (xy 70.763619 -306.227721)
			(xy 70.808977 -306.19527) (xy 70.858577 -306.169769) (xy 70.911361 -306.151762) (xy 70.966204 -306.141632)
			(xy 71.021938 -306.139595) (xy 71.077375 -306.145695) (xy 71.131332 -306.159801) (xy 71.182661 -306.181613)
			(xy 71.230267 -306.210667) (xy 71.273135 -306.246342) (xy 71.310352 -306.287879) (xy 71.341125 -306.334392)
			(xy 71.364797 -306.384889) (xy 71.380865 -306.438296) (xy 71.388985 -306.493472) (xy 71.389494 -306.521358)
			(xy 71.803258 -306.521358) (xy 71.807329 -306.465736) (xy 71.819455 -306.411299) (xy 71.839378 -306.359208)
			(xy 71.866674 -306.310573) (xy 71.90076 -306.26643) (xy 71.940909 -306.227721) (xy 71.986267 -306.19527)
			(xy 72.035867 -306.169769) (xy 72.088651 -306.151762) (xy 72.143494 -306.141632) (xy 72.199228 -306.139595)
			(xy 72.254665 -306.145695) (xy 72.308622 -306.159801) (xy 72.359951 -306.181613) (xy 72.407557 -306.210667)
			(xy 72.450425 -306.246342) (xy 72.487642 -306.287879) (xy 72.518415 -306.334392) (xy 72.542087 -306.384889)
			(xy 72.558155 -306.438296) (xy 72.566275 -306.493472) (xy 72.566784 -306.521358) (xy 73.04481 -306.521358)
			(xy 73.048881 -306.465736) (xy 73.061007 -306.411299) (xy 73.08093 -306.359208) (xy 73.108226 -306.310573)
			(xy 73.142312 -306.26643) (xy 73.182461 -306.227721) (xy 73.227819 -306.19527) (xy 73.277419 -306.169769)
			(xy 73.330203 -306.151762) (xy 73.385046 -306.141632) (xy 73.44078 -306.139595) (xy 73.496217 -306.145695)
			(xy 73.550174 -306.159801) (xy 73.601503 -306.181613) (xy 73.649109 -306.210667) (xy 73.691977 -306.246342)
			(xy 73.729194 -306.287879) (xy 73.759967 -306.334392) (xy 73.783639 -306.384889) (xy 73.799707 -306.438296)
			(xy 73.807827 -306.493472) (xy 73.808336 -306.521358) (xy 74.24496 -306.521358) (xy 74.249031 -306.465736)
			(xy 74.261157 -306.411299) (xy 74.28108 -306.359208) (xy 74.308376 -306.310573) (xy 74.342462 -306.26643)
			(xy 74.382611 -306.227721) (xy 74.427969 -306.19527) (xy 74.477569 -306.169769) (xy 74.530353 -306.151762)
			(xy 74.585196 -306.141632) (xy 74.64093 -306.139595) (xy 74.696367 -306.145695) (xy 74.750324 -306.159801)
			(xy 74.801653 -306.181613) (xy 74.849259 -306.210667) (xy 74.892127 -306.246342) (xy 74.929344 -306.287879)
			(xy 74.960117 -306.334392) (xy 74.983789 -306.384889) (xy 74.999857 -306.438296) (xy 75.007977 -306.493472)
			(xy 75.008486 -306.521358) (xy 75.007977 -306.549244) (xy 74.999857 -306.60442) (xy 74.983789 -306.657827)
			(xy 74.960117 -306.708324) (xy 74.929344 -306.754837) (xy 74.892127 -306.796374) (xy 74.849259 -306.832049)
			(xy 74.801653 -306.861103) (xy 74.750324 -306.882915) (xy 74.696367 -306.897021) (xy 74.64093 -306.903121)
			(xy 74.585196 -306.901084) (xy 74.530353 -306.890954) (xy 74.477569 -306.872947) (xy 74.427969 -306.847446)
			(xy 74.382611 -306.814995) (xy 74.342462 -306.776286) (xy 74.308376 -306.732143) (xy 74.28108 -306.683508)
			(xy 74.261157 -306.631417) (xy 74.249031 -306.57698) (xy 74.24496 -306.521358) (xy 73.808336 -306.521358)
			(xy 73.807827 -306.549244) (xy 73.799707 -306.60442) (xy 73.783639 -306.657827) (xy 73.759967 -306.708324)
			(xy 73.729194 -306.754837) (xy 73.691977 -306.796374) (xy 73.649109 -306.832049) (xy 73.601503 -306.861103)
			(xy 73.550174 -306.882915) (xy 73.496217 -306.897021) (xy 73.44078 -306.903121) (xy 73.385046 -306.901084)
			(xy 73.330203 -306.890954) (xy 73.277419 -306.872947) (xy 73.227819 -306.847446) (xy 73.182461 -306.814995)
			(xy 73.142312 -306.776286) (xy 73.108226 -306.732143) (xy 73.08093 -306.683508) (xy 73.061007 -306.631417)
			(xy 73.048881 -306.57698) (xy 73.04481 -306.521358) (xy 72.566784 -306.521358) (xy 72.566275 -306.549244)
			(xy 72.558155 -306.60442) (xy 72.542087 -306.657827) (xy 72.518415 -306.708324) (xy 72.487642 -306.754837)
			(xy 72.450425 -306.796374) (xy 72.407557 -306.832049) (xy 72.359951 -306.861103) (xy 72.308622 -306.882915)
			(xy 72.254665 -306.897021) (xy 72.199228 -306.903121) (xy 72.143494 -306.901084) (xy 72.088651 -306.890954)
			(xy 72.035867 -306.872947) (xy 71.986267 -306.847446) (xy 71.940909 -306.814995) (xy 71.90076 -306.776286)
			(xy 71.866674 -306.732143) (xy 71.839378 -306.683508) (xy 71.819455 -306.631417) (xy 71.807329 -306.57698)
			(xy 71.803258 -306.521358) (xy 71.389494 -306.521358) (xy 71.388985 -306.549244) (xy 71.380865 -306.60442)
			(xy 71.364797 -306.657827) (xy 71.341125 -306.708324) (xy 71.310352 -306.754837) (xy 71.273135 -306.796374)
			(xy 71.230267 -306.832049) (xy 71.182661 -306.861103) (xy 71.131332 -306.882915) (xy 71.077375 -306.897021)
			(xy 71.021938 -306.903121) (xy 70.966204 -306.901084) (xy 70.911361 -306.890954) (xy 70.858577 -306.872947)
			(xy 70.808977 -306.847446) (xy 70.763619 -306.814995) (xy 70.72347 -306.776286) (xy 70.689384 -306.732143)
			(xy 70.662088 -306.683508) (xy 70.642165 -306.631417) (xy 70.630039 -306.57698) (xy 70.625968 -306.521358)
			(xy 65.346898 -306.521358) (xy 65.352007 -306.531968) (xy 65.375564 -306.599288) (xy 65.391434 -306.668823)
			(xy 65.39942 -306.739697) (xy 65.39992 -306.775358) (xy 65.39942 -306.811019) (xy 65.391434 -306.881893)
			(xy 65.375564 -306.951428) (xy 65.352007 -307.018748) (xy 65.321062 -307.083007) (xy 65.283116 -307.143398)
			(xy 65.238647 -307.19916) (xy 65.188214 -307.249593) (xy 65.132452 -307.294062) (xy 65.072061 -307.332008)
			(xy 65.007802 -307.362953) (xy 64.940482 -307.38651) (xy 64.870947 -307.40238) (xy 64.800073 -307.410366)
			(xy 64.728751 -307.410366) (xy 64.657877 -307.40238) (xy 64.588342 -307.38651) (xy 64.521022 -307.362953)
			(xy 64.456763 -307.332008) (xy 64.396372 -307.294062) (xy 64.34061 -307.249593) (xy 64.290177 -307.19916)
			(xy 64.245708 -307.143398) (xy 64.207762 -307.083007) (xy 64.176817 -307.018748) (xy 64.15326 -306.951428)
			(xy 64.13739 -306.881893) (xy 64.129404 -306.811019) (xy 63.495436 -306.811019) (xy 63.48745 -306.881893)
			(xy 63.47158 -306.951428) (xy 63.448023 -307.018748) (xy 63.417078 -307.083007) (xy 63.379132 -307.143398)
			(xy 63.334663 -307.19916) (xy 63.28423 -307.249593) (xy 63.228468 -307.294062) (xy 63.168077 -307.332008)
			(xy 63.103818 -307.362953) (xy 63.036498 -307.38651) (xy 62.966963 -307.40238) (xy 62.896089 -307.410366)
			(xy 62.824767 -307.410366) (xy 62.753893 -307.40238) (xy 62.684358 -307.38651) (xy 62.617038 -307.362953)
			(xy 62.552779 -307.332008) (xy 62.492388 -307.294062) (xy 62.436626 -307.249593) (xy 62.386193 -307.19916)
			(xy 62.341724 -307.143398) (xy 62.303778 -307.083007) (xy 62.272833 -307.018748) (xy 62.249276 -306.951428)
			(xy 62.233406 -306.881893) (xy 62.22542 -306.811019) (xy 61.254394 -306.811019) (xy 61.246408 -306.881893)
			(xy 61.230538 -306.951428) (xy 61.206981 -307.018748) (xy 61.176036 -307.083007) (xy 61.13809 -307.143398)
			(xy 61.093621 -307.19916) (xy 61.043188 -307.249593) (xy 60.987426 -307.294062) (xy 60.927035 -307.332008)
			(xy 60.862776 -307.362953) (xy 60.795456 -307.38651) (xy 60.725921 -307.40238) (xy 60.655047 -307.410366)
			(xy 60.583725 -307.410366) (xy 60.512851 -307.40238) (xy 60.443316 -307.38651) (xy 60.375996 -307.362953)
			(xy 60.311737 -307.332008) (xy 60.251346 -307.294062) (xy 60.195584 -307.249593) (xy 60.145151 -307.19916)
			(xy 60.100682 -307.143398) (xy 60.062736 -307.083007) (xy 60.031791 -307.018748) (xy 60.008234 -306.951428)
			(xy 59.992364 -306.881893) (xy 59.984378 -306.811019) (xy 59.367682 -306.811019) (xy 59.359696 -306.881893)
			(xy 59.343826 -306.951428) (xy 59.320269 -307.018748) (xy 59.289324 -307.083007) (xy 59.251378 -307.143398)
			(xy 59.206909 -307.19916) (xy 59.156476 -307.249593) (xy 59.100714 -307.294062) (xy 59.040323 -307.332008)
			(xy 58.976064 -307.362953) (xy 58.908744 -307.38651) (xy 58.839209 -307.40238) (xy 58.768335 -307.410366)
			(xy 58.697013 -307.410366) (xy 58.626139 -307.40238) (xy 58.556604 -307.38651) (xy 58.489284 -307.362953)
			(xy 58.425025 -307.332008) (xy 58.364634 -307.294062) (xy 58.308872 -307.249593) (xy 58.258439 -307.19916)
			(xy 58.21397 -307.143398) (xy 58.176024 -307.083007) (xy 58.145079 -307.018748) (xy 58.121522 -306.951428)
			(xy 58.105652 -306.881893) (xy 58.097666 -306.811019) (xy 49.30783 -306.811019) (xy 49.264724 -306.875531)
			(xy 49.213269 -306.93823) (xy 49.155916 -306.995583) (xy 49.093217 -307.047038) (xy 49.025777 -307.0921)
			(xy 48.954245 -307.130335) (xy 48.879309 -307.161374) (xy 48.801693 -307.184919) (xy 48.722142 -307.200742)
			(xy 48.641423 -307.208692) (xy 48.560313 -307.208692) (xy 48.479594 -307.200742) (xy 48.400043 -307.184919)
			(xy 48.322427 -307.161374) (xy 48.247491 -307.130335) (xy 48.175959 -307.0921) (xy 48.108519 -307.047038)
			(xy 48.04582 -306.995583) (xy 47.988467 -306.93823) (xy 47.937012 -306.875531) (xy 47.89195 -306.808091)
			(xy 47.853715 -306.736559) (xy 47.822676 -306.661623) (xy 47.799131 -306.584007) (xy 47.783308 -306.504456)
			(xy 47.775358 -306.423737) (xy 28.912312 -306.423737) (xy 28.912312 -307.93336) (xy 29.519874 -307.93336)
			(xy 29.519874 -307.84646) (xy 29.527892 -307.759931) (xy 29.54386 -307.674511) (xy 29.567641 -307.590929)
			(xy 29.599033 -307.509897) (xy 29.637767 -307.432108) (xy 29.683514 -307.358224) (xy 29.735883 -307.288877)
			(xy 29.794427 -307.224657) (xy 29.858647 -307.166113) (xy 29.927994 -307.113744) (xy 30.001878 -307.067997)
			(xy 30.079667 -307.029263) (xy 30.160699 -306.997871) (xy 30.244281 -306.97409) (xy 30.329701 -306.958122)
			(xy 30.41623 -306.950104) (xy 30.50313 -306.950104) (xy 30.589659 -306.958122) (xy 30.675079 -306.97409)
			(xy 30.758661 -306.997871) (xy 30.839693 -307.029263) (xy 30.917482 -307.067997) (xy 30.991366 -307.113744)
			(xy 31.060713 -307.166113) (xy 31.124933 -307.224657) (xy 31.183477 -307.288877) (xy 31.235846 -307.358224)
			(xy 31.281593 -307.432108) (xy 31.320327 -307.509897) (xy 31.351719 -307.590929) (xy 31.3755 -307.674511)
			(xy 31.391468 -307.759931) (xy 31.399486 -307.84646) (xy 31.399988 -307.88991) (xy 31.399486 -307.93336)
			(xy 34.599874 -307.93336) (xy 34.599874 -307.84646) (xy 34.607892 -307.759931) (xy 34.62386 -307.674511)
			(xy 34.647641 -307.590929) (xy 34.679033 -307.509897) (xy 34.717767 -307.432108) (xy 34.763514 -307.358224)
			(xy 34.815883 -307.288877) (xy 34.874427 -307.224657) (xy 34.938647 -307.166113) (xy 35.007994 -307.113744)
			(xy 35.081878 -307.067997) (xy 35.159667 -307.029263) (xy 35.240699 -306.997871) (xy 35.324281 -306.97409)
			(xy 35.409701 -306.958122) (xy 35.49623 -306.950104) (xy 35.58313 -306.950104) (xy 35.669659 -306.958122)
			(xy 35.755079 -306.97409) (xy 35.838661 -306.997871) (xy 35.919693 -307.029263) (xy 35.997482 -307.067997)
			(xy 36.071366 -307.113744) (xy 36.140713 -307.166113) (xy 36.204933 -307.224657) (xy 36.263477 -307.288877)
			(xy 36.315846 -307.358224) (xy 36.361593 -307.432108) (xy 36.400327 -307.509897) (xy 36.431719 -307.590929)
			(xy 36.4555 -307.674511) (xy 36.471468 -307.759931) (xy 36.479486 -307.84646) (xy 36.479988 -307.88991)
			(xy 36.479486 -307.93336) (xy 36.471468 -308.019889) (xy 36.4555 -308.105309) (xy 36.431719 -308.188891)
			(xy 36.400327 -308.269923) (xy 36.361593 -308.347712) (xy 36.315846 -308.421596) (xy 36.263477 -308.490943)
			(xy 36.204933 -308.555163) (xy 36.140713 -308.613707) (xy 36.071366 -308.666076) (xy 35.997482 -308.711823)
			(xy 35.979363 -308.720845) (xy 58.097666 -308.720845) (xy 58.097666 -308.649523) (xy 58.105652 -308.578649)
			(xy 58.121522 -308.509114) (xy 58.145079 -308.441794) (xy 58.176024 -308.377535) (xy 58.21397 -308.317144)
			(xy 58.258439 -308.261382) (xy 58.308872 -308.210949) (xy 58.364634 -308.16648) (xy 58.425025 -308.128534)
			(xy 58.489284 -308.097589) (xy 58.556604 -308.074032) (xy 58.626139 -308.058162) (xy 58.697013 -308.050176)
			(xy 58.768335 -308.050176) (xy 58.839209 -308.058162) (xy 58.908744 -308.074032) (xy 58.976064 -308.097589)
			(xy 59.040323 -308.128534) (xy 59.100714 -308.16648) (xy 59.156476 -308.210949) (xy 59.206909 -308.261382)
			(xy 59.251378 -308.317144) (xy 59.289324 -308.377535) (xy 59.320269 -308.441794) (xy 59.343826 -308.509114)
			(xy 59.359696 -308.578649) (xy 59.367682 -308.649523) (xy 59.368182 -308.685184) (xy 59.367682 -308.720845)
			(xy 59.984378 -308.720845) (xy 59.984378 -308.649523) (xy 59.992364 -308.578649) (xy 60.008234 -308.509114)
			(xy 60.031791 -308.441794) (xy 60.062736 -308.377535) (xy 60.100682 -308.317144) (xy 60.145151 -308.261382)
			(xy 60.195584 -308.210949) (xy 60.251346 -308.16648) (xy 60.311737 -308.128534) (xy 60.375996 -308.097589)
			(xy 60.443316 -308.074032) (xy 60.512851 -308.058162) (xy 60.583725 -308.050176) (xy 60.655047 -308.050176)
			(xy 60.725921 -308.058162) (xy 60.795456 -308.074032) (xy 60.862776 -308.097589) (xy 60.927035 -308.128534)
			(xy 60.987426 -308.16648) (xy 61.043188 -308.210949) (xy 61.093621 -308.261382) (xy 61.13809 -308.317144)
			(xy 61.176036 -308.377535) (xy 61.206981 -308.441794) (xy 61.230538 -308.509114) (xy 61.246408 -308.578649)
			(xy 61.254394 -308.649523) (xy 61.254894 -308.685184) (xy 61.254394 -308.720845) (xy 62.22542 -308.720845)
			(xy 62.22542 -308.649523) (xy 62.233406 -308.578649) (xy 62.249276 -308.509114) (xy 62.272833 -308.441794)
			(xy 62.303778 -308.377535) (xy 62.341724 -308.317144) (xy 62.386193 -308.261382) (xy 62.436626 -308.210949)
			(xy 62.492388 -308.16648) (xy 62.552779 -308.128534) (xy 62.617038 -308.097589) (xy 62.684358 -308.074032)
			(xy 62.753893 -308.058162) (xy 62.824767 -308.050176) (xy 62.896089 -308.050176) (xy 62.966963 -308.058162)
			(xy 63.036498 -308.074032) (xy 63.103818 -308.097589) (xy 63.168077 -308.128534) (xy 63.228468 -308.16648)
			(xy 63.28423 -308.210949) (xy 63.334663 -308.261382) (xy 63.379132 -308.317144) (xy 63.417078 -308.377535)
			(xy 63.448023 -308.441794) (xy 63.47158 -308.509114) (xy 63.48745 -308.578649) (xy 63.495436 -308.649523)
			(xy 63.495936 -308.685184) (xy 63.495436 -308.720845) (xy 64.129404 -308.720845) (xy 64.129404 -308.649523)
			(xy 64.13739 -308.578649) (xy 64.15326 -308.509114) (xy 64.176817 -308.441794) (xy 64.207762 -308.377535)
			(xy 64.245708 -308.317144) (xy 64.290177 -308.261382) (xy 64.34061 -308.210949) (xy 64.396372 -308.16648)
			(xy 64.456763 -308.128534) (xy 64.521022 -308.097589) (xy 64.588342 -308.074032) (xy 64.657877 -308.058162)
			(xy 64.728751 -308.050176) (xy 64.800073 -308.050176) (xy 64.870947 -308.058162) (xy 64.940482 -308.074032)
			(xy 65.007802 -308.097589) (xy 65.072061 -308.128534) (xy 65.132452 -308.16648) (xy 65.188214 -308.210949)
			(xy 65.238647 -308.261382) (xy 65.283116 -308.317144) (xy 65.321062 -308.377535) (xy 65.352007 -308.441794)
			(xy 65.375564 -308.509114) (xy 65.391434 -308.578649) (xy 65.39942 -308.649523) (xy 65.39992 -308.685184)
			(xy 65.39942 -308.720845) (xy 65.391434 -308.791719) (xy 65.375564 -308.861254) (xy 65.352007 -308.928574)
			(xy 65.321062 -308.992833) (xy 65.283116 -309.053224) (xy 65.238647 -309.108986) (xy 65.188214 -309.159419)
			(xy 65.132452 -309.203888) (xy 65.072061 -309.241834) (xy 65.007802 -309.272779) (xy 64.940482 -309.296336)
			(xy 64.870947 -309.312206) (xy 64.800073 -309.320192) (xy 64.728751 -309.320192) (xy 64.657877 -309.312206)
			(xy 64.588342 -309.296336) (xy 64.521022 -309.272779) (xy 64.456763 -309.241834) (xy 64.396372 -309.203888)
			(xy 64.34061 -309.159419) (xy 64.290177 -309.108986) (xy 64.245708 -309.053224) (xy 64.207762 -308.992833)
			(xy 64.176817 -308.928574) (xy 64.15326 -308.861254) (xy 64.13739 -308.791719) (xy 64.129404 -308.720845)
			(xy 63.495436 -308.720845) (xy 63.48745 -308.791719) (xy 63.47158 -308.861254) (xy 63.448023 -308.928574)
			(xy 63.417078 -308.992833) (xy 63.379132 -309.053224) (xy 63.334663 -309.108986) (xy 63.28423 -309.159419)
			(xy 63.228468 -309.203888) (xy 63.168077 -309.241834) (xy 63.103818 -309.272779) (xy 63.036498 -309.296336)
			(xy 62.966963 -309.312206) (xy 62.896089 -309.320192) (xy 62.824767 -309.320192) (xy 62.753893 -309.312206)
			(xy 62.684358 -309.296336) (xy 62.617038 -309.272779) (xy 62.552779 -309.241834) (xy 62.492388 -309.203888)
			(xy 62.436626 -309.159419) (xy 62.386193 -309.108986) (xy 62.341724 -309.053224) (xy 62.303778 -308.992833)
			(xy 62.272833 -308.928574) (xy 62.249276 -308.861254) (xy 62.233406 -308.791719) (xy 62.22542 -308.720845)
			(xy 61.254394 -308.720845) (xy 61.246408 -308.791719) (xy 61.230538 -308.861254) (xy 61.206981 -308.928574)
			(xy 61.176036 -308.992833) (xy 61.13809 -309.053224) (xy 61.093621 -309.108986) (xy 61.043188 -309.159419)
			(xy 60.987426 -309.203888) (xy 60.927035 -309.241834) (xy 60.862776 -309.272779) (xy 60.795456 -309.296336)
			(xy 60.725921 -309.312206) (xy 60.655047 -309.320192) (xy 60.583725 -309.320192) (xy 60.512851 -309.312206)
			(xy 60.443316 -309.296336) (xy 60.375996 -309.272779) (xy 60.311737 -309.241834) (xy 60.251346 -309.203888)
			(xy 60.195584 -309.159419) (xy 60.145151 -309.108986) (xy 60.100682 -309.053224) (xy 60.062736 -308.992833)
			(xy 60.031791 -308.928574) (xy 60.008234 -308.861254) (xy 59.992364 -308.791719) (xy 59.984378 -308.720845)
			(xy 59.367682 -308.720845) (xy 59.359696 -308.791719) (xy 59.343826 -308.861254) (xy 59.320269 -308.928574)
			(xy 59.289324 -308.992833) (xy 59.251378 -309.053224) (xy 59.206909 -309.108986) (xy 59.156476 -309.159419)
			(xy 59.100714 -309.203888) (xy 59.040323 -309.241834) (xy 58.976064 -309.272779) (xy 58.908744 -309.296336)
			(xy 58.839209 -309.312206) (xy 58.768335 -309.320192) (xy 58.697013 -309.320192) (xy 58.626139 -309.312206)
			(xy 58.556604 -309.296336) (xy 58.489284 -309.272779) (xy 58.425025 -309.241834) (xy 58.364634 -309.203888)
			(xy 58.308872 -309.159419) (xy 58.258439 -309.108986) (xy 58.21397 -309.053224) (xy 58.176024 -308.992833)
			(xy 58.145079 -308.928574) (xy 58.121522 -308.861254) (xy 58.105652 -308.791719) (xy 58.097666 -308.720845)
			(xy 35.979363 -308.720845) (xy 35.919693 -308.750557) (xy 35.838661 -308.781949) (xy 35.755079 -308.80573)
			(xy 35.669659 -308.821698) (xy 35.58313 -308.829716) (xy 35.49623 -308.829716) (xy 35.409701 -308.821698)
			(xy 35.324281 -308.80573) (xy 35.240699 -308.781949) (xy 35.159667 -308.750557) (xy 35.081878 -308.711823)
			(xy 35.007994 -308.666076) (xy 34.938647 -308.613707) (xy 34.874427 -308.555163) (xy 34.815883 -308.490943)
			(xy 34.763514 -308.421596) (xy 34.717767 -308.347712) (xy 34.679033 -308.269923) (xy 34.647641 -308.188891)
			(xy 34.62386 -308.105309) (xy 34.607892 -308.019889) (xy 34.599874 -307.93336) (xy 31.399486 -307.93336)
			(xy 31.391468 -308.019889) (xy 31.3755 -308.105309) (xy 31.351719 -308.188891) (xy 31.320327 -308.269923)
			(xy 31.281593 -308.347712) (xy 31.235846 -308.421596) (xy 31.183477 -308.490943) (xy 31.124933 -308.555163)
			(xy 31.060713 -308.613707) (xy 30.991366 -308.666076) (xy 30.917482 -308.711823) (xy 30.839693 -308.750557)
			(xy 30.758661 -308.781949) (xy 30.675079 -308.80573) (xy 30.589659 -308.821698) (xy 30.50313 -308.829716)
			(xy 30.41623 -308.829716) (xy 30.329701 -308.821698) (xy 30.244281 -308.80573) (xy 30.160699 -308.781949)
			(xy 30.079667 -308.750557) (xy 30.001878 -308.711823) (xy 29.927994 -308.666076) (xy 29.858647 -308.613707)
			(xy 29.794427 -308.555163) (xy 29.735883 -308.490943) (xy 29.683514 -308.421596) (xy 29.637767 -308.347712)
			(xy 29.599033 -308.269923) (xy 29.567641 -308.188891) (xy 29.54386 -308.105309) (xy 29.527892 -308.019889)
			(xy 29.519874 -307.93336) (xy 28.912312 -307.93336) (xy 28.912312 -310.47336) (xy 29.519874 -310.47336)
			(xy 29.519874 -310.38646) (xy 29.527892 -310.299931) (xy 29.54386 -310.214511) (xy 29.567641 -310.130929)
			(xy 29.599033 -310.049897) (xy 29.637767 -309.972108) (xy 29.683514 -309.898224) (xy 29.735883 -309.828877)
			(xy 29.794427 -309.764657) (xy 29.858647 -309.706113) (xy 29.927994 -309.653744) (xy 30.001878 -309.607997)
			(xy 30.079667 -309.569263) (xy 30.160699 -309.537871) (xy 30.244281 -309.51409) (xy 30.329701 -309.498122)
			(xy 30.41623 -309.490104) (xy 30.50313 -309.490104) (xy 30.589659 -309.498122) (xy 30.675079 -309.51409)
			(xy 30.758661 -309.537871) (xy 30.839693 -309.569263) (xy 30.917482 -309.607997) (xy 30.991366 -309.653744)
			(xy 31.060713 -309.706113) (xy 31.124933 -309.764657) (xy 31.183477 -309.828877) (xy 31.235846 -309.898224)
			(xy 31.281593 -309.972108) (xy 31.320327 -310.049897) (xy 31.351719 -310.130929) (xy 31.3755 -310.214511)
			(xy 31.391468 -310.299931) (xy 31.399486 -310.38646) (xy 31.399988 -310.42991) (xy 31.399486 -310.47336)
			(xy 34.599874 -310.47336) (xy 34.599874 -310.38646) (xy 34.607892 -310.299931) (xy 34.62386 -310.214511)
			(xy 34.647641 -310.130929) (xy 34.679033 -310.049897) (xy 34.717767 -309.972108) (xy 34.763514 -309.898224)
			(xy 34.815883 -309.828877) (xy 34.874427 -309.764657) (xy 34.938647 -309.706113) (xy 35.007994 -309.653744)
			(xy 35.081878 -309.607997) (xy 35.159667 -309.569263) (xy 35.240699 -309.537871) (xy 35.324281 -309.51409)
			(xy 35.409701 -309.498122) (xy 35.49623 -309.490104) (xy 35.58313 -309.490104) (xy 35.669659 -309.498122)
			(xy 35.755079 -309.51409) (xy 35.838661 -309.537871) (xy 35.919693 -309.569263) (xy 35.997482 -309.607997)
			(xy 36.071366 -309.653744) (xy 36.140713 -309.706113) (xy 36.204933 -309.764657) (xy 36.263477 -309.828877)
			(xy 36.315846 -309.898224) (xy 36.361593 -309.972108) (xy 36.400327 -310.049897) (xy 36.431719 -310.130929)
			(xy 36.4555 -310.214511) (xy 36.471468 -310.299931) (xy 36.479486 -310.38646) (xy 36.479988 -310.42991)
			(xy 36.479486 -310.47336) (xy 36.471468 -310.559889) (xy 36.4555 -310.645309) (xy 36.431719 -310.728891)
			(xy 36.400327 -310.809923) (xy 36.361593 -310.887712) (xy 36.315846 -310.961596) (xy 36.263477 -311.030943)
			(xy 36.204933 -311.095163) (xy 36.140713 -311.153707) (xy 36.071366 -311.206076) (xy 35.997482 -311.251823)
			(xy 35.919693 -311.290557) (xy 35.838661 -311.321949) (xy 35.755079 -311.34573) (xy 35.669659 -311.361698)
			(xy 35.58313 -311.369716) (xy 35.49623 -311.369716) (xy 35.409701 -311.361698) (xy 35.324281 -311.34573)
			(xy 35.240699 -311.321949) (xy 35.159667 -311.290557) (xy 35.081878 -311.251823) (xy 35.007994 -311.206076)
			(xy 34.938647 -311.153707) (xy 34.874427 -311.095163) (xy 34.815883 -311.030943) (xy 34.763514 -310.961596)
			(xy 34.717767 -310.887712) (xy 34.679033 -310.809923) (xy 34.647641 -310.728891) (xy 34.62386 -310.645309)
			(xy 34.607892 -310.559889) (xy 34.599874 -310.47336) (xy 31.399486 -310.47336) (xy 31.391468 -310.559889)
			(xy 31.3755 -310.645309) (xy 31.351719 -310.728891) (xy 31.320327 -310.809923) (xy 31.281593 -310.887712)
			(xy 31.235846 -310.961596) (xy 31.183477 -311.030943) (xy 31.124933 -311.095163) (xy 31.060713 -311.153707)
			(xy 30.991366 -311.206076) (xy 30.917482 -311.251823) (xy 30.839693 -311.290557) (xy 30.758661 -311.321949)
			(xy 30.675079 -311.34573) (xy 30.589659 -311.361698) (xy 30.50313 -311.369716) (xy 30.41623 -311.369716)
			(xy 30.329701 -311.361698) (xy 30.244281 -311.34573) (xy 30.160699 -311.321949) (xy 30.079667 -311.290557)
			(xy 30.001878 -311.251823) (xy 29.927994 -311.206076) (xy 29.858647 -311.153707) (xy 29.794427 -311.095163)
			(xy 29.735883 -311.030943) (xy 29.683514 -310.961596) (xy 29.637767 -310.887712) (xy 29.599033 -310.809923)
			(xy 29.567641 -310.728891) (xy 29.54386 -310.645309) (xy 29.527892 -310.559889) (xy 29.519874 -310.47336)
			(xy 28.912312 -310.47336) (xy 28.912312 -313.01336) (xy 29.519874 -313.01336) (xy 29.519874 -312.92646)
			(xy 29.527892 -312.839931) (xy 29.54386 -312.754511) (xy 29.567641 -312.670929) (xy 29.599033 -312.589897)
			(xy 29.637767 -312.512108) (xy 29.683514 -312.438224) (xy 29.735883 -312.368877) (xy 29.794427 -312.304657)
			(xy 29.858647 -312.246113) (xy 29.927994 -312.193744) (xy 30.001878 -312.147997) (xy 30.079667 -312.109263)
			(xy 30.160699 -312.077871) (xy 30.244281 -312.05409) (xy 30.329701 -312.038122) (xy 30.41623 -312.030104)
			(xy 30.50313 -312.030104) (xy 30.589659 -312.038122) (xy 30.675079 -312.05409) (xy 30.758661 -312.077871)
			(xy 30.839693 -312.109263) (xy 30.917482 -312.147997) (xy 30.991366 -312.193744) (xy 31.060713 -312.246113)
			(xy 31.124933 -312.304657) (xy 31.183477 -312.368877) (xy 31.235846 -312.438224) (xy 31.281593 -312.512108)
			(xy 31.320327 -312.589897) (xy 31.351719 -312.670929) (xy 31.3755 -312.754511) (xy 31.391468 -312.839931)
			(xy 31.399486 -312.92646) (xy 31.399988 -312.96991) (xy 31.399486 -313.01336) (xy 34.599874 -313.01336)
			(xy 34.599874 -312.92646) (xy 34.607892 -312.839931) (xy 34.62386 -312.754511) (xy 34.647641 -312.670929)
			(xy 34.679033 -312.589897) (xy 34.717767 -312.512108) (xy 34.763514 -312.438224) (xy 34.815883 -312.368877)
			(xy 34.874427 -312.304657) (xy 34.938647 -312.246113) (xy 35.007994 -312.193744) (xy 35.081878 -312.147997)
			(xy 35.159667 -312.109263) (xy 35.240699 -312.077871) (xy 35.324281 -312.05409) (xy 35.409701 -312.038122)
			(xy 35.49623 -312.030104) (xy 35.58313 -312.030104) (xy 35.669659 -312.038122) (xy 35.755079 -312.05409)
			(xy 35.838661 -312.077871) (xy 35.919693 -312.109263) (xy 35.997482 -312.147997) (xy 36.071366 -312.193744)
			(xy 36.140713 -312.246113) (xy 36.204933 -312.304657) (xy 36.263477 -312.368877) (xy 36.315846 -312.438224)
			(xy 36.361593 -312.512108) (xy 36.400327 -312.589897) (xy 36.431719 -312.670929) (xy 36.4555 -312.754511)
			(xy 36.471468 -312.839931) (xy 36.479486 -312.92646) (xy 36.479988 -312.96991) (xy 36.479486 -313.01336)
			(xy 36.471468 -313.099889) (xy 36.4555 -313.185309) (xy 36.431719 -313.268891) (xy 36.400327 -313.349923)
			(xy 36.361593 -313.427712) (xy 36.315846 -313.501596) (xy 36.263477 -313.570943) (xy 36.204933 -313.635163)
			(xy 36.140713 -313.693707) (xy 36.071366 -313.746076) (xy 35.997482 -313.791823) (xy 35.919693 -313.830557)
			(xy 35.838661 -313.861949) (xy 35.755079 -313.88573) (xy 35.669659 -313.901698) (xy 35.58313 -313.909716)
			(xy 35.49623 -313.909716) (xy 35.409701 -313.901698) (xy 35.324281 -313.88573) (xy 35.240699 -313.861949)
			(xy 35.159667 -313.830557) (xy 35.081878 -313.791823) (xy 35.007994 -313.746076) (xy 34.938647 -313.693707)
			(xy 34.874427 -313.635163) (xy 34.815883 -313.570943) (xy 34.763514 -313.501596) (xy 34.717767 -313.427712)
			(xy 34.679033 -313.349923) (xy 34.647641 -313.268891) (xy 34.62386 -313.185309) (xy 34.607892 -313.099889)
			(xy 34.599874 -313.01336) (xy 31.399486 -313.01336) (xy 31.391468 -313.099889) (xy 31.3755 -313.185309)
			(xy 31.351719 -313.268891) (xy 31.320327 -313.349923) (xy 31.281593 -313.427712) (xy 31.235846 -313.501596)
			(xy 31.183477 -313.570943) (xy 31.124933 -313.635163) (xy 31.060713 -313.693707) (xy 30.991366 -313.746076)
			(xy 30.917482 -313.791823) (xy 30.839693 -313.830557) (xy 30.758661 -313.861949) (xy 30.675079 -313.88573)
			(xy 30.589659 -313.901698) (xy 30.50313 -313.909716) (xy 30.41623 -313.909716) (xy 30.329701 -313.901698)
			(xy 30.244281 -313.88573) (xy 30.160699 -313.861949) (xy 30.079667 -313.830557) (xy 30.001878 -313.791823)
			(xy 29.927994 -313.746076) (xy 29.858647 -313.693707) (xy 29.794427 -313.635163) (xy 29.735883 -313.570943)
			(xy 29.683514 -313.501596) (xy 29.637767 -313.427712) (xy 29.599033 -313.349923) (xy 29.567641 -313.268891)
			(xy 29.54386 -313.185309) (xy 29.527892 -313.099889) (xy 29.519874 -313.01336) (xy 28.912312 -313.01336)
			(xy 28.912312 -315.55336) (xy 29.519874 -315.55336) (xy 29.519874 -315.46646) (xy 29.527892 -315.379931)
			(xy 29.54386 -315.294511) (xy 29.567641 -315.210929) (xy 29.599033 -315.129897) (xy 29.637767 -315.052108)
			(xy 29.683514 -314.978224) (xy 29.735883 -314.908877) (xy 29.794427 -314.844657) (xy 29.858647 -314.786113)
			(xy 29.927994 -314.733744) (xy 30.001878 -314.687997) (xy 30.079667 -314.649263) (xy 30.160699 -314.617871)
			(xy 30.244281 -314.59409) (xy 30.329701 -314.578122) (xy 30.41623 -314.570104) (xy 30.50313 -314.570104)
			(xy 30.589659 -314.578122) (xy 30.675079 -314.59409) (xy 30.758661 -314.617871) (xy 30.839693 -314.649263)
			(xy 30.917482 -314.687997) (xy 30.991366 -314.733744) (xy 31.060713 -314.786113) (xy 31.124933 -314.844657)
			(xy 31.183477 -314.908877) (xy 31.235846 -314.978224) (xy 31.281593 -315.052108) (xy 31.320327 -315.129897)
			(xy 31.351719 -315.210929) (xy 31.3755 -315.294511) (xy 31.391468 -315.379931) (xy 31.399486 -315.46646)
			(xy 31.399988 -315.50991) (xy 31.399486 -315.55336) (xy 34.599874 -315.55336) (xy 34.599874 -315.46646)
			(xy 34.607892 -315.379931) (xy 34.62386 -315.294511) (xy 34.647641 -315.210929) (xy 34.679033 -315.129897)
			(xy 34.717767 -315.052108) (xy 34.763514 -314.978224) (xy 34.815883 -314.908877) (xy 34.874427 -314.844657)
			(xy 34.938647 -314.786113) (xy 35.007994 -314.733744) (xy 35.081878 -314.687997) (xy 35.159667 -314.649263)
			(xy 35.240699 -314.617871) (xy 35.324281 -314.59409) (xy 35.409701 -314.578122) (xy 35.49623 -314.570104)
			(xy 35.58313 -314.570104) (xy 35.669659 -314.578122) (xy 35.755079 -314.59409) (xy 35.838661 -314.617871)
			(xy 35.919693 -314.649263) (xy 35.997482 -314.687997) (xy 36.071366 -314.733744) (xy 36.140713 -314.786113)
			(xy 36.204933 -314.844657) (xy 36.263477 -314.908877) (xy 36.315846 -314.978224) (xy 36.361593 -315.052108)
			(xy 36.400327 -315.129897) (xy 36.431719 -315.210929) (xy 36.4555 -315.294511) (xy 36.471468 -315.379931)
			(xy 36.479486 -315.46646) (xy 36.479988 -315.50991) (xy 36.479486 -315.55336) (xy 36.471468 -315.639889)
			(xy 36.4555 -315.725309) (xy 36.431719 -315.808891) (xy 36.400327 -315.889923) (xy 36.361593 -315.967712)
			(xy 36.315846 -316.041596) (xy 36.263477 -316.110943) (xy 36.204933 -316.175163) (xy 36.140713 -316.233707)
			(xy 36.071366 -316.286076) (xy 35.997482 -316.331823) (xy 35.919693 -316.370557) (xy 35.838661 -316.401949)
			(xy 35.755079 -316.42573) (xy 35.669659 -316.441698) (xy 35.58313 -316.449716) (xy 35.49623 -316.449716)
			(xy 35.409701 -316.441698) (xy 35.324281 -316.42573) (xy 35.240699 -316.401949) (xy 35.159667 -316.370557)
			(xy 35.081878 -316.331823) (xy 35.007994 -316.286076) (xy 34.938647 -316.233707) (xy 34.874427 -316.175163)
			(xy 34.815883 -316.110943) (xy 34.763514 -316.041596) (xy 34.717767 -315.967712) (xy 34.679033 -315.889923)
			(xy 34.647641 -315.808891) (xy 34.62386 -315.725309) (xy 34.607892 -315.639889) (xy 34.599874 -315.55336)
			(xy 31.399486 -315.55336) (xy 31.391468 -315.639889) (xy 31.3755 -315.725309) (xy 31.351719 -315.808891)
			(xy 31.320327 -315.889923) (xy 31.281593 -315.967712) (xy 31.235846 -316.041596) (xy 31.183477 -316.110943)
			(xy 31.124933 -316.175163) (xy 31.060713 -316.233707) (xy 30.991366 -316.286076) (xy 30.917482 -316.331823)
			(xy 30.839693 -316.370557) (xy 30.758661 -316.401949) (xy 30.675079 -316.42573) (xy 30.589659 -316.441698)
			(xy 30.50313 -316.449716) (xy 30.41623 -316.449716) (xy 30.329701 -316.441698) (xy 30.244281 -316.42573)
			(xy 30.160699 -316.401949) (xy 30.079667 -316.370557) (xy 30.001878 -316.331823) (xy 29.927994 -316.286076)
			(xy 29.858647 -316.233707) (xy 29.794427 -316.175163) (xy 29.735883 -316.110943) (xy 29.683514 -316.041596)
			(xy 29.637767 -315.967712) (xy 29.599033 -315.889923) (xy 29.567641 -315.808891) (xy 29.54386 -315.725309)
			(xy 29.527892 -315.639889) (xy 29.519874 -315.55336) (xy 28.912312 -315.55336) (xy 28.912312 -318.09336)
			(xy 29.519874 -318.09336) (xy 29.519874 -318.00646) (xy 29.527892 -317.919931) (xy 29.54386 -317.834511)
			(xy 29.567641 -317.750929) (xy 29.599033 -317.669897) (xy 29.637767 -317.592108) (xy 29.683514 -317.518224)
			(xy 29.735883 -317.448877) (xy 29.794427 -317.384657) (xy 29.858647 -317.326113) (xy 29.927994 -317.273744)
			(xy 30.001878 -317.227997) (xy 30.079667 -317.189263) (xy 30.160699 -317.157871) (xy 30.244281 -317.13409)
			(xy 30.329701 -317.118122) (xy 30.41623 -317.110104) (xy 30.50313 -317.110104) (xy 30.589659 -317.118122)
			(xy 30.675079 -317.13409) (xy 30.758661 -317.157871) (xy 30.839693 -317.189263) (xy 30.917482 -317.227997)
			(xy 30.991366 -317.273744) (xy 31.060713 -317.326113) (xy 31.124933 -317.384657) (xy 31.183477 -317.448877)
			(xy 31.235846 -317.518224) (xy 31.281593 -317.592108) (xy 31.320327 -317.669897) (xy 31.351719 -317.750929)
			(xy 31.3755 -317.834511) (xy 31.391468 -317.919931) (xy 31.399486 -318.00646) (xy 31.399988 -318.04991)
			(xy 31.399486 -318.09336) (xy 34.599874 -318.09336) (xy 34.599874 -318.00646) (xy 34.607892 -317.919931)
			(xy 34.62386 -317.834511) (xy 34.647641 -317.750929) (xy 34.679033 -317.669897) (xy 34.717767 -317.592108)
			(xy 34.763514 -317.518224) (xy 34.815883 -317.448877) (xy 34.874427 -317.384657) (xy 34.938647 -317.326113)
			(xy 35.007994 -317.273744) (xy 35.081878 -317.227997) (xy 35.159667 -317.189263) (xy 35.240699 -317.157871)
			(xy 35.324281 -317.13409) (xy 35.409701 -317.118122) (xy 35.49623 -317.110104) (xy 35.58313 -317.110104)
			(xy 35.669659 -317.118122) (xy 35.755079 -317.13409) (xy 35.838661 -317.157871) (xy 35.919693 -317.189263)
			(xy 35.997482 -317.227997) (xy 36.071366 -317.273744) (xy 36.140713 -317.326113) (xy 36.204933 -317.384657)
			(xy 36.263477 -317.448877) (xy 36.315846 -317.518224) (xy 36.361593 -317.592108) (xy 36.400327 -317.669897)
			(xy 36.431719 -317.750929) (xy 36.4555 -317.834511) (xy 36.471468 -317.919931) (xy 36.479486 -318.00646)
			(xy 36.479988 -318.04991) (xy 36.479871 -318.06007) (xy 39.818063 -318.06007) (xy 39.82207 -317.944046)
			(xy 39.834072 -317.828574) (xy 39.854012 -317.714206) (xy 39.881795 -317.601486) (xy 39.917289 -317.490952)
			(xy 39.960324 -317.383129) (xy 40.010695 -317.278532) (xy 40.068162 -317.17766) (xy 40.132452 -317.080993)
			(xy 40.203257 -316.988992) (xy 40.280241 -316.902095) (xy 40.363037 -316.820716) (xy 40.45125 -316.745243)
			(xy 40.54446 -316.676036) (xy 40.642223 -316.613424) (xy 40.744072 -316.557707) (xy 40.849522 -316.509149)
			(xy 40.958071 -316.467981) (xy 41.069202 -316.434401) (xy 41.182385 -316.408568) (xy 41.29708 -316.390605)
			(xy 41.412742 -316.380597) (xy 41.528818 -316.378594) (xy 41.644756 -316.384603) (xy 41.760003 -316.398596)
			(xy 41.874009 -316.420507) (xy 41.986233 -316.450232) (xy 42.096139 -316.487628) (xy 42.203202 -316.532517)
			(xy 42.306914 -316.584686) (xy 42.406779 -316.643886) (xy 42.502322 -316.709835) (xy 42.502604 -316.71006)
			(xy 43.327577 -316.71006) (xy 43.331612 -316.634356) (xy 43.343671 -316.559511) (xy 43.363617 -316.48637)
			(xy 43.391224 -316.415765) (xy 43.42618 -316.348494) (xy 43.468088 -316.285319) (xy 43.516474 -316.226957)
			(xy 43.57079 -316.174069) (xy 43.630419 -316.127254) (xy 43.694687 -316.087042) (xy 43.762864 -316.05389)
			(xy 43.83418 -316.028172) (xy 43.907825 -316.01018) (xy 43.982965 -316.000118) (xy 44.058749 -315.998099)
			(xy 44.134319 -316.004148) (xy 44.208817 -316.018195) (xy 44.2814 -316.040081) (xy 44.351246 -316.069558)
			(xy 44.417563 -316.106293) (xy 44.479599 -316.149868) (xy 44.536652 -316.19979) (xy 44.588076 -316.255494)
			(xy 44.633287 -316.316349) (xy 44.671774 -316.381664) (xy 44.7031 -316.4507) (xy 44.72691 -316.522675)
			(xy 44.742935 -316.596773) (xy 44.750994 -316.672154) (xy 44.751498 -316.71006) (xy 45.867577 -316.71006)
			(xy 45.871612 -316.634356) (xy 45.883671 -316.559511) (xy 45.903617 -316.48637) (xy 45.931224 -316.415765)
			(xy 45.96618 -316.348494) (xy 46.008088 -316.285319) (xy 46.056474 -316.226957) (xy 46.11079 -316.174069)
			(xy 46.170419 -316.127254) (xy 46.234687 -316.087042) (xy 46.302864 -316.05389) (xy 46.37418 -316.028172)
			(xy 46.447825 -316.01018) (xy 46.522965 -316.000118) (xy 46.598749 -315.998099) (xy 46.674319 -316.004148)
			(xy 46.748817 -316.018195) (xy 46.8214 -316.040081) (xy 46.891246 -316.069558) (xy 46.957563 -316.106293)
			(xy 47.019599 -316.149868) (xy 47.076652 -316.19979) (xy 47.128076 -316.255494) (xy 47.173287 -316.316349)
			(xy 47.211774 -316.381664) (xy 47.2431 -316.4507) (xy 47.26691 -316.522675) (xy 47.282935 -316.596773)
			(xy 47.290994 -316.672154) (xy 47.291498 -316.71006) (xy 48.407577 -316.71006) (xy 48.411612 -316.634356)
			(xy 48.423671 -316.559511) (xy 48.443617 -316.48637) (xy 48.471224 -316.415765) (xy 48.50618 -316.348494)
			(xy 48.548088 -316.285319) (xy 48.596474 -316.226957) (xy 48.65079 -316.174069) (xy 48.710419 -316.127254)
			(xy 48.774687 -316.087042) (xy 48.842864 -316.05389) (xy 48.91418 -316.028172) (xy 48.987825 -316.01018)
			(xy 49.062965 -316.000118) (xy 49.138749 -315.998099) (xy 49.214319 -316.004148) (xy 49.288817 -316.018195)
			(xy 49.3614 -316.040081) (xy 49.431246 -316.069558) (xy 49.497563 -316.106293) (xy 49.559599 -316.149868)
			(xy 49.616652 -316.19979) (xy 49.668076 -316.255494) (xy 49.713287 -316.316349) (xy 49.751774 -316.381664)
			(xy 49.7831 -316.4507) (xy 49.80691 -316.522675) (xy 49.822935 -316.596773) (xy 49.830994 -316.672154)
			(xy 49.831498 -316.71006) (xy 50.947577 -316.71006) (xy 50.951612 -316.634356) (xy 50.963671 -316.559511)
			(xy 50.983617 -316.48637) (xy 51.011224 -316.415765) (xy 51.04618 -316.348494) (xy 51.088088 -316.285319)
			(xy 51.136474 -316.226957) (xy 51.19079 -316.174069) (xy 51.250419 -316.127254) (xy 51.314687 -316.087042)
			(xy 51.382864 -316.05389) (xy 51.45418 -316.028172) (xy 51.527825 -316.01018) (xy 51.602965 -316.000118)
			(xy 51.678749 -315.998099) (xy 51.754319 -316.004148) (xy 51.828817 -316.018195) (xy 51.9014 -316.040081)
			(xy 51.971246 -316.069558) (xy 52.037563 -316.106293) (xy 52.099599 -316.149868) (xy 52.156652 -316.19979)
			(xy 52.208076 -316.255494) (xy 52.253287 -316.316349) (xy 52.291774 -316.381664) (xy 52.3231 -316.4507)
			(xy 52.34691 -316.522675) (xy 52.362935 -316.596773) (xy 52.370994 -316.672154) (xy 52.371498 -316.71006)
			(xy 53.487577 -316.71006) (xy 53.491612 -316.634356) (xy 53.503671 -316.559511) (xy 53.523617 -316.48637)
			(xy 53.551224 -316.415765) (xy 53.58618 -316.348494) (xy 53.628088 -316.285319) (xy 53.676474 -316.226957)
			(xy 53.73079 -316.174069) (xy 53.790419 -316.127254) (xy 53.854687 -316.087042) (xy 53.922864 -316.05389)
			(xy 53.99418 -316.028172) (xy 54.067825 -316.01018) (xy 54.142965 -316.000118) (xy 54.218749 -315.998099)
			(xy 54.294319 -316.004148) (xy 54.368817 -316.018195) (xy 54.4414 -316.040081) (xy 54.511246 -316.069558)
			(xy 54.577563 -316.106293) (xy 54.639599 -316.149868) (xy 54.696652 -316.19979) (xy 54.748076 -316.255494)
			(xy 54.793287 -316.316349) (xy 54.831774 -316.381664) (xy 54.8631 -316.4507) (xy 54.88691 -316.522675)
			(xy 54.902935 -316.596773) (xy 54.910994 -316.672154) (xy 54.911498 -316.71006) (xy 56.027577 -316.71006)
			(xy 56.031612 -316.634356) (xy 56.043671 -316.559511) (xy 56.063617 -316.48637) (xy 56.091224 -316.415765)
			(xy 56.12618 -316.348494) (xy 56.168088 -316.285319) (xy 56.216474 -316.226957) (xy 56.27079 -316.174069)
			(xy 56.330419 -316.127254) (xy 56.394687 -316.087042) (xy 56.462864 -316.05389) (xy 56.53418 -316.028172)
			(xy 56.607825 -316.01018) (xy 56.682965 -316.000118) (xy 56.758749 -315.998099) (xy 56.834319 -316.004148)
			(xy 56.908817 -316.018195) (xy 56.9814 -316.040081) (xy 57.051246 -316.069558) (xy 57.117563 -316.106293)
			(xy 57.179599 -316.149868) (xy 57.236652 -316.19979) (xy 57.288076 -316.255494) (xy 57.333287 -316.316349)
			(xy 57.371774 -316.381664) (xy 57.4031 -316.4507) (xy 57.42691 -316.522675) (xy 57.442935 -316.596773)
			(xy 57.450994 -316.672154) (xy 57.451498 -316.71006) (xy 58.567577 -316.71006) (xy 58.571612 -316.634356)
			(xy 58.583671 -316.559511) (xy 58.603617 -316.48637) (xy 58.631224 -316.415765) (xy 58.66618 -316.348494)
			(xy 58.708088 -316.285319) (xy 58.756474 -316.226957) (xy 58.81079 -316.174069) (xy 58.870419 -316.127254)
			(xy 58.934687 -316.087042) (xy 59.002864 -316.05389) (xy 59.07418 -316.028172) (xy 59.147825 -316.01018)
			(xy 59.222965 -316.000118) (xy 59.298749 -315.998099) (xy 59.374319 -316.004148) (xy 59.448817 -316.018195)
			(xy 59.5214 -316.040081) (xy 59.591246 -316.069558) (xy 59.657563 -316.106293) (xy 59.719599 -316.149868)
			(xy 59.776652 -316.19979) (xy 59.828076 -316.255494) (xy 59.873287 -316.316349) (xy 59.911774 -316.381664)
			(xy 59.9431 -316.4507) (xy 59.96691 -316.522675) (xy 59.982935 -316.596773) (xy 59.990994 -316.672154)
			(xy 59.991498 -316.71006) (xy 61.107577 -316.71006) (xy 61.111612 -316.634356) (xy 61.123671 -316.559511)
			(xy 61.143617 -316.48637) (xy 61.171224 -316.415765) (xy 61.20618 -316.348494) (xy 61.248088 -316.285319)
			(xy 61.296474 -316.226957) (xy 61.35079 -316.174069) (xy 61.410419 -316.127254) (xy 61.474687 -316.087042)
			(xy 61.542864 -316.05389) (xy 61.61418 -316.028172) (xy 61.687825 -316.01018) (xy 61.762965 -316.000118)
			(xy 61.838749 -315.998099) (xy 61.914319 -316.004148) (xy 61.988817 -316.018195) (xy 62.0614 -316.040081)
			(xy 62.131246 -316.069558) (xy 62.197563 -316.106293) (xy 62.259599 -316.149868) (xy 62.316652 -316.19979)
			(xy 62.368076 -316.255494) (xy 62.413287 -316.316349) (xy 62.451774 -316.381664) (xy 62.4831 -316.4507)
			(xy 62.50691 -316.522675) (xy 62.522935 -316.596773) (xy 62.530994 -316.672154) (xy 62.531498 -316.71006)
			(xy 62.530994 -316.747966) (xy 62.522935 -316.823347) (xy 62.50691 -316.897445) (xy 62.4831 -316.96942)
			(xy 62.451774 -317.038456) (xy 62.413287 -317.103771) (xy 62.368076 -317.164626) (xy 62.316652 -317.22033)
			(xy 62.259599 -317.270252) (xy 62.197563 -317.313827) (xy 62.131246 -317.350562) (xy 62.0614 -317.380039)
			(xy 61.988817 -317.401925) (xy 61.914319 -317.415972) (xy 61.838749 -317.422021) (xy 61.762965 -317.420002)
			(xy 61.687825 -317.40994) (xy 61.61418 -317.391948) (xy 61.542864 -317.36623) (xy 61.474687 -317.333078)
			(xy 61.410419 -317.292866) (xy 61.35079 -317.246051) (xy 61.296474 -317.193163) (xy 61.248088 -317.134801)
			(xy 61.20618 -317.071626) (xy 61.171224 -317.004355) (xy 61.143617 -316.93375) (xy 61.123671 -316.860609)
			(xy 61.111612 -316.785764) (xy 61.107577 -316.71006) (xy 59.991498 -316.71006) (xy 59.990994 -316.747966)
			(xy 59.982935 -316.823347) (xy 59.96691 -316.897445) (xy 59.9431 -316.96942) (xy 59.911774 -317.038456)
			(xy 59.873287 -317.103771) (xy 59.828076 -317.164626) (xy 59.776652 -317.22033) (xy 59.719599 -317.270252)
			(xy 59.657563 -317.313827) (xy 59.591246 -317.350562) (xy 59.5214 -317.380039) (xy 59.448817 -317.401925)
			(xy 59.374319 -317.415972) (xy 59.298749 -317.422021) (xy 59.222965 -317.420002) (xy 59.147825 -317.40994)
			(xy 59.07418 -317.391948) (xy 59.002864 -317.36623) (xy 58.934687 -317.333078) (xy 58.870419 -317.292866)
			(xy 58.81079 -317.246051) (xy 58.756474 -317.193163) (xy 58.708088 -317.134801) (xy 58.66618 -317.071626)
			(xy 58.631224 -317.004355) (xy 58.603617 -316.93375) (xy 58.583671 -316.860609) (xy 58.571612 -316.785764)
			(xy 58.567577 -316.71006) (xy 57.451498 -316.71006) (xy 57.450994 -316.747966) (xy 57.442935 -316.823347)
			(xy 57.42691 -316.897445) (xy 57.4031 -316.96942) (xy 57.371774 -317.038456) (xy 57.333287 -317.103771)
			(xy 57.288076 -317.164626) (xy 57.236652 -317.22033) (xy 57.179599 -317.270252) (xy 57.117563 -317.313827)
			(xy 57.051246 -317.350562) (xy 56.9814 -317.380039) (xy 56.908817 -317.401925) (xy 56.834319 -317.415972)
			(xy 56.758749 -317.422021) (xy 56.682965 -317.420002) (xy 56.607825 -317.40994) (xy 56.53418 -317.391948)
			(xy 56.462864 -317.36623) (xy 56.394687 -317.333078) (xy 56.330419 -317.292866) (xy 56.27079 -317.246051)
			(xy 56.216474 -317.193163) (xy 56.168088 -317.134801) (xy 56.12618 -317.071626) (xy 56.091224 -317.004355)
			(xy 56.063617 -316.93375) (xy 56.043671 -316.860609) (xy 56.031612 -316.785764) (xy 56.027577 -316.71006)
			(xy 54.911498 -316.71006) (xy 54.910994 -316.747966) (xy 54.902935 -316.823347) (xy 54.88691 -316.897445)
			(xy 54.8631 -316.96942) (xy 54.831774 -317.038456) (xy 54.793287 -317.103771) (xy 54.748076 -317.164626)
			(xy 54.696652 -317.22033) (xy 54.639599 -317.270252) (xy 54.577563 -317.313827) (xy 54.511246 -317.350562)
			(xy 54.4414 -317.380039) (xy 54.368817 -317.401925) (xy 54.294319 -317.415972) (xy 54.218749 -317.422021)
			(xy 54.142965 -317.420002) (xy 54.067825 -317.40994) (xy 53.99418 -317.391948) (xy 53.922864 -317.36623)
			(xy 53.854687 -317.333078) (xy 53.790419 -317.292866) (xy 53.73079 -317.246051) (xy 53.676474 -317.193163)
			(xy 53.628088 -317.134801) (xy 53.58618 -317.071626) (xy 53.551224 -317.004355) (xy 53.523617 -316.93375)
			(xy 53.503671 -316.860609) (xy 53.491612 -316.785764) (xy 53.487577 -316.71006) (xy 52.371498 -316.71006)
			(xy 52.370994 -316.747966) (xy 52.362935 -316.823347) (xy 52.34691 -316.897445) (xy 52.3231 -316.96942)
			(xy 52.291774 -317.038456) (xy 52.253287 -317.103771) (xy 52.208076 -317.164626) (xy 52.156652 -317.22033)
			(xy 52.099599 -317.270252) (xy 52.037563 -317.313827) (xy 51.971246 -317.350562) (xy 51.9014 -317.380039)
			(xy 51.828817 -317.401925) (xy 51.754319 -317.415972) (xy 51.678749 -317.422021) (xy 51.602965 -317.420002)
			(xy 51.527825 -317.40994) (xy 51.45418 -317.391948) (xy 51.382864 -317.36623) (xy 51.314687 -317.333078)
			(xy 51.250419 -317.292866) (xy 51.19079 -317.246051) (xy 51.136474 -317.193163) (xy 51.088088 -317.134801)
			(xy 51.04618 -317.071626) (xy 51.011224 -317.004355) (xy 50.983617 -316.93375) (xy 50.963671 -316.860609)
			(xy 50.951612 -316.785764) (xy 50.947577 -316.71006) (xy 49.831498 -316.71006) (xy 49.830994 -316.747966)
			(xy 49.822935 -316.823347) (xy 49.80691 -316.897445) (xy 49.7831 -316.96942) (xy 49.751774 -317.038456)
			(xy 49.713287 -317.103771) (xy 49.668076 -317.164626) (xy 49.616652 -317.22033) (xy 49.559599 -317.270252)
			(xy 49.497563 -317.313827) (xy 49.431246 -317.350562) (xy 49.3614 -317.380039) (xy 49.288817 -317.401925)
			(xy 49.214319 -317.415972) (xy 49.138749 -317.422021) (xy 49.062965 -317.420002) (xy 48.987825 -317.40994)
			(xy 48.91418 -317.391948) (xy 48.842864 -317.36623) (xy 48.774687 -317.333078) (xy 48.710419 -317.292866)
			(xy 48.65079 -317.246051) (xy 48.596474 -317.193163) (xy 48.548088 -317.134801) (xy 48.50618 -317.071626)
			(xy 48.471224 -317.004355) (xy 48.443617 -316.93375) (xy 48.423671 -316.860609) (xy 48.411612 -316.785764)
			(xy 48.407577 -316.71006) (xy 47.291498 -316.71006) (xy 47.290994 -316.747966) (xy 47.282935 -316.823347)
			(xy 47.26691 -316.897445) (xy 47.2431 -316.96942) (xy 47.211774 -317.038456) (xy 47.173287 -317.103771)
			(xy 47.128076 -317.164626) (xy 47.076652 -317.22033) (xy 47.019599 -317.270252) (xy 46.957563 -317.313827)
			(xy 46.891246 -317.350562) (xy 46.8214 -317.380039) (xy 46.748817 -317.401925) (xy 46.674319 -317.415972)
			(xy 46.598749 -317.422021) (xy 46.522965 -317.420002) (xy 46.447825 -317.40994) (xy 46.37418 -317.391948)
			(xy 46.302864 -317.36623) (xy 46.234687 -317.333078) (xy 46.170419 -317.292866) (xy 46.11079 -317.246051)
			(xy 46.056474 -317.193163) (xy 46.008088 -317.134801) (xy 45.96618 -317.071626) (xy 45.931224 -317.004355)
			(xy 45.903617 -316.93375) (xy 45.883671 -316.860609) (xy 45.871612 -316.785764) (xy 45.867577 -316.71006)
			(xy 44.751498 -316.71006) (xy 44.750994 -316.747966) (xy 44.742935 -316.823347) (xy 44.72691 -316.897445)
			(xy 44.7031 -316.96942) (xy 44.671774 -317.038456) (xy 44.633287 -317.103771) (xy 44.588076 -317.164626)
			(xy 44.536652 -317.22033) (xy 44.479599 -317.270252) (xy 44.417563 -317.313827) (xy 44.351246 -317.350562)
			(xy 44.2814 -317.380039) (xy 44.208817 -317.401925) (xy 44.134319 -317.415972) (xy 44.058749 -317.422021)
			(xy 43.982965 -317.420002) (xy 43.907825 -317.40994) (xy 43.83418 -317.391948) (xy 43.762864 -317.36623)
			(xy 43.694687 -317.333078) (xy 43.630419 -317.292866) (xy 43.57079 -317.246051) (xy 43.516474 -317.193163)
			(xy 43.468088 -317.134801) (xy 43.42618 -317.071626) (xy 43.391224 -317.004355) (xy 43.363617 -316.93375)
			(xy 43.343671 -316.860609) (xy 43.331612 -316.785764) (xy 43.327577 -316.71006) (xy 42.502604 -316.71006)
			(xy 42.593088 -316.782218) (xy 42.678643 -316.860691) (xy 42.758581 -316.944879) (xy 42.83252 -317.034381)
			(xy 42.900108 -317.128772) (xy 42.961022 -317.2276) (xy 43.014974 -317.330396) (xy 43.056604 -317.42507)
			(xy 84.927697 -317.42507) (xy 84.931732 -317.349366) (xy 84.943791 -317.274521) (xy 84.963737 -317.20138)
			(xy 84.991344 -317.130775) (xy 85.0263 -317.063504) (xy 85.068208 -317.000329) (xy 85.116594 -316.941967)
			(xy 85.17091 -316.889079) (xy 85.230539 -316.842264) (xy 85.294807 -316.802052) (xy 85.362984 -316.7689)
			(xy 85.4343 -316.743182) (xy 85.507945 -316.72519) (xy 85.583085 -316.715128) (xy 85.658869 -316.713109)
			(xy 85.734439 -316.719158) (xy 85.808937 -316.733205) (xy 85.88152 -316.755091) (xy 85.951366 -316.784568)
			(xy 86.017683 -316.821303) (xy 86.079719 -316.864878) (xy 86.136772 -316.9148) (xy 86.188196 -316.970504)
			(xy 86.233407 -317.031359) (xy 86.271894 -317.096674) (xy 86.30322 -317.16571) (xy 86.32703 -317.237685)
			(xy 86.343055 -317.311783) (xy 86.351114 -317.387164) (xy 86.351618 -317.42507) (xy 86.351114 -317.462976)
			(xy 86.343055 -317.538357) (xy 86.32703 -317.612455) (xy 86.30322 -317.68443) (xy 86.271894 -317.753466)
			(xy 86.233407 -317.818781) (xy 86.188196 -317.879636) (xy 86.136772 -317.93534) (xy 86.079719 -317.985262)
			(xy 86.017683 -318.028837) (xy 85.951366 -318.065572) (xy 85.88152 -318.095049) (xy 85.808937 -318.116935)
			(xy 85.734439 -318.130982) (xy 85.658869 -318.137031) (xy 85.583085 -318.135012) (xy 85.507945 -318.12495)
			(xy 85.4343 -318.106958) (xy 85.362984 -318.08124) (xy 85.294807 -318.048088) (xy 85.230539 -318.007876)
			(xy 85.17091 -317.961061) (xy 85.116594 -317.908173) (xy 85.068208 -317.849811) (xy 85.0263 -317.786636)
			(xy 84.991344 -317.719365) (xy 84.963737 -317.64876) (xy 84.943791 -317.575619) (xy 84.931732 -317.500774)
			(xy 84.927697 -317.42507) (xy 43.056604 -317.42507) (xy 43.061704 -317.436669) (xy 43.100992 -317.545913)
			(xy 43.132649 -317.657606) (xy 43.156525 -317.771218) (xy 43.172506 -317.886206) (xy 43.180515 -318.002023)
			(xy 43.181016 -318.06007) (xy 43.180515 -318.118117) (xy 43.172506 -318.233934) (xy 43.156525 -318.348922)
			(xy 43.132649 -318.462534) (xy 43.100992 -318.574227) (xy 43.061704 -318.683471) (xy 43.014974 -318.789744)
			(xy 42.961022 -318.89254) (xy 42.900108 -318.991368) (xy 42.83252 -319.085759) (xy 42.758581 -319.175261)
			(xy 42.678643 -319.259449) (xy 42.593088 -319.337922) (xy 42.502604 -319.41008) (xy 43.327577 -319.41008)
			(xy 43.331612 -319.334376) (xy 43.343671 -319.259531) (xy 43.363617 -319.18639) (xy 43.391224 -319.115785)
			(xy 43.42618 -319.048514) (xy 43.468088 -318.985339) (xy 43.516474 -318.926977) (xy 43.57079 -318.874089)
			(xy 43.630419 -318.827274) (xy 43.694687 -318.787062) (xy 43.762864 -318.75391) (xy 43.83418 -318.728192)
			(xy 43.907825 -318.7102) (xy 43.982965 -318.700138) (xy 44.058749 -318.698119) (xy 44.134319 -318.704168)
			(xy 44.208817 -318.718215) (xy 44.2814 -318.740101) (xy 44.351246 -318.769578) (xy 44.417563 -318.806313)
			(xy 44.479599 -318.849888) (xy 44.536652 -318.89981) (xy 44.588076 -318.955514) (xy 44.633287 -319.016369)
			(xy 44.671774 -319.081684) (xy 44.7031 -319.15072) (xy 44.72691 -319.222695) (xy 44.742935 -319.296793)
			(xy 44.750994 -319.372174) (xy 44.751498 -319.41008) (xy 45.867577 -319.41008) (xy 45.871612 -319.334376)
			(xy 45.883671 -319.259531) (xy 45.903617 -319.18639) (xy 45.931224 -319.115785) (xy 45.96618 -319.048514)
			(xy 46.008088 -318.985339) (xy 46.056474 -318.926977) (xy 46.11079 -318.874089) (xy 46.170419 -318.827274)
			(xy 46.234687 -318.787062) (xy 46.302864 -318.75391) (xy 46.37418 -318.728192) (xy 46.447825 -318.7102)
			(xy 46.522965 -318.700138) (xy 46.598749 -318.698119) (xy 46.674319 -318.704168) (xy 46.748817 -318.718215)
			(xy 46.8214 -318.740101) (xy 46.891246 -318.769578) (xy 46.957563 -318.806313) (xy 47.019599 -318.849888)
			(xy 47.076652 -318.89981) (xy 47.128076 -318.955514) (xy 47.173287 -319.016369) (xy 47.211774 -319.081684)
			(xy 47.2431 -319.15072) (xy 47.26691 -319.222695) (xy 47.282935 -319.296793) (xy 47.290994 -319.372174)
			(xy 47.291498 -319.41008) (xy 48.407577 -319.41008) (xy 48.411612 -319.334376) (xy 48.423671 -319.259531)
			(xy 48.443617 -319.18639) (xy 48.471224 -319.115785) (xy 48.50618 -319.048514) (xy 48.548088 -318.985339)
			(xy 48.596474 -318.926977) (xy 48.65079 -318.874089) (xy 48.710419 -318.827274) (xy 48.774687 -318.787062)
			(xy 48.842864 -318.75391) (xy 48.91418 -318.728192) (xy 48.987825 -318.7102) (xy 49.062965 -318.700138)
			(xy 49.138749 -318.698119) (xy 49.214319 -318.704168) (xy 49.288817 -318.718215) (xy 49.3614 -318.740101)
			(xy 49.431246 -318.769578) (xy 49.497563 -318.806313) (xy 49.559599 -318.849888) (xy 49.616652 -318.89981)
			(xy 49.668076 -318.955514) (xy 49.713287 -319.016369) (xy 49.751774 -319.081684) (xy 49.7831 -319.15072)
			(xy 49.80691 -319.222695) (xy 49.822935 -319.296793) (xy 49.830994 -319.372174) (xy 49.831498 -319.41008)
			(xy 50.947577 -319.41008) (xy 50.951612 -319.334376) (xy 50.963671 -319.259531) (xy 50.983617 -319.18639)
			(xy 51.011224 -319.115785) (xy 51.04618 -319.048514) (xy 51.088088 -318.985339) (xy 51.136474 -318.926977)
			(xy 51.19079 -318.874089) (xy 51.250419 -318.827274) (xy 51.314687 -318.787062) (xy 51.382864 -318.75391)
			(xy 51.45418 -318.728192) (xy 51.527825 -318.7102) (xy 51.602965 -318.700138) (xy 51.678749 -318.698119)
			(xy 51.754319 -318.704168) (xy 51.828817 -318.718215) (xy 51.9014 -318.740101) (xy 51.971246 -318.769578)
			(xy 52.037563 -318.806313) (xy 52.099599 -318.849888) (xy 52.156652 -318.89981) (xy 52.208076 -318.955514)
			(xy 52.253287 -319.016369) (xy 52.291774 -319.081684) (xy 52.3231 -319.15072) (xy 52.34691 -319.222695)
			(xy 52.362935 -319.296793) (xy 52.370994 -319.372174) (xy 52.371498 -319.41008) (xy 53.487577 -319.41008)
			(xy 53.491612 -319.334376) (xy 53.503671 -319.259531) (xy 53.523617 -319.18639) (xy 53.551224 -319.115785)
			(xy 53.58618 -319.048514) (xy 53.628088 -318.985339) (xy 53.676474 -318.926977) (xy 53.73079 -318.874089)
			(xy 53.790419 -318.827274) (xy 53.854687 -318.787062) (xy 53.922864 -318.75391) (xy 53.99418 -318.728192)
			(xy 54.067825 -318.7102) (xy 54.142965 -318.700138) (xy 54.218749 -318.698119) (xy 54.294319 -318.704168)
			(xy 54.368817 -318.718215) (xy 54.4414 -318.740101) (xy 54.511246 -318.769578) (xy 54.577563 -318.806313)
			(xy 54.639599 -318.849888) (xy 54.696652 -318.89981) (xy 54.748076 -318.955514) (xy 54.793287 -319.016369)
			(xy 54.831774 -319.081684) (xy 54.8631 -319.15072) (xy 54.88691 -319.222695) (xy 54.902935 -319.296793)
			(xy 54.910994 -319.372174) (xy 54.911498 -319.41008) (xy 56.027577 -319.41008) (xy 56.031612 -319.334376)
			(xy 56.043671 -319.259531) (xy 56.063617 -319.18639) (xy 56.091224 -319.115785) (xy 56.12618 -319.048514)
			(xy 56.168088 -318.985339) (xy 56.216474 -318.926977) (xy 56.27079 -318.874089) (xy 56.330419 -318.827274)
			(xy 56.394687 -318.787062) (xy 56.462864 -318.75391) (xy 56.53418 -318.728192) (xy 56.607825 -318.7102)
			(xy 56.682965 -318.700138) (xy 56.758749 -318.698119) (xy 56.834319 -318.704168) (xy 56.908817 -318.718215)
			(xy 56.9814 -318.740101) (xy 57.051246 -318.769578) (xy 57.117563 -318.806313) (xy 57.179599 -318.849888)
			(xy 57.236652 -318.89981) (xy 57.288076 -318.955514) (xy 57.333287 -319.016369) (xy 57.371774 -319.081684)
			(xy 57.4031 -319.15072) (xy 57.42691 -319.222695) (xy 57.442935 -319.296793) (xy 57.450994 -319.372174)
			(xy 57.451498 -319.41008) (xy 58.567577 -319.41008) (xy 58.571612 -319.334376) (xy 58.583671 -319.259531)
			(xy 58.603617 -319.18639) (xy 58.631224 -319.115785) (xy 58.66618 -319.048514) (xy 58.708088 -318.985339)
			(xy 58.756474 -318.926977) (xy 58.81079 -318.874089) (xy 58.870419 -318.827274) (xy 58.934687 -318.787062)
			(xy 59.002864 -318.75391) (xy 59.07418 -318.728192) (xy 59.147825 -318.7102) (xy 59.222965 -318.700138)
			(xy 59.298749 -318.698119) (xy 59.374319 -318.704168) (xy 59.448817 -318.718215) (xy 59.5214 -318.740101)
			(xy 59.591246 -318.769578) (xy 59.657563 -318.806313) (xy 59.719599 -318.849888) (xy 59.776652 -318.89981)
			(xy 59.828076 -318.955514) (xy 59.873287 -319.016369) (xy 59.911774 -319.081684) (xy 59.9431 -319.15072)
			(xy 59.96691 -319.222695) (xy 59.982935 -319.296793) (xy 59.990994 -319.372174) (xy 59.991498 -319.41008)
			(xy 61.107577 -319.41008) (xy 61.111612 -319.334376) (xy 61.123671 -319.259531) (xy 61.143617 -319.18639)
			(xy 61.171224 -319.115785) (xy 61.20618 -319.048514) (xy 61.248088 -318.985339) (xy 61.296474 -318.926977)
			(xy 61.35079 -318.874089) (xy 61.410419 -318.827274) (xy 61.474687 -318.787062) (xy 61.542864 -318.75391)
			(xy 61.61418 -318.728192) (xy 61.687825 -318.7102) (xy 61.762965 -318.700138) (xy 61.838749 -318.698119)
			(xy 61.914319 -318.704168) (xy 61.988817 -318.718215) (xy 62.0614 -318.740101) (xy 62.131246 -318.769578)
			(xy 62.197563 -318.806313) (xy 62.259599 -318.849888) (xy 62.316652 -318.89981) (xy 62.368076 -318.955514)
			(xy 62.413287 -319.016369) (xy 62.451774 -319.081684) (xy 62.4831 -319.15072) (xy 62.50691 -319.222695)
			(xy 62.522935 -319.296793) (xy 62.530994 -319.372174) (xy 62.531498 -319.41008) (xy 62.530994 -319.447986)
			(xy 62.522935 -319.523367) (xy 62.50691 -319.597465) (xy 62.4831 -319.66944) (xy 62.451774 -319.738476)
			(xy 62.413287 -319.803791) (xy 62.368076 -319.864646) (xy 62.316652 -319.92035) (xy 62.259599 -319.970272)
			(xy 62.197563 -320.013847) (xy 62.131246 -320.050582) (xy 62.0614 -320.080059) (xy 61.988817 -320.101945)
			(xy 61.914319 -320.115992) (xy 61.838749 -320.122041) (xy 61.762965 -320.120022) (xy 61.687825 -320.10996)
			(xy 61.61418 -320.091968) (xy 61.542864 -320.06625) (xy 61.474687 -320.033098) (xy 61.410419 -319.992886)
			(xy 61.35079 -319.946071) (xy 61.296474 -319.893183) (xy 61.248088 -319.834821) (xy 61.20618 -319.771646)
			(xy 61.171224 -319.704375) (xy 61.143617 -319.63377) (xy 61.123671 -319.560629) (xy 61.111612 -319.485784)
			(xy 61.107577 -319.41008) (xy 59.991498 -319.41008) (xy 59.990994 -319.447986) (xy 59.982935 -319.523367)
			(xy 59.96691 -319.597465) (xy 59.9431 -319.66944) (xy 59.911774 -319.738476) (xy 59.873287 -319.803791)
			(xy 59.828076 -319.864646) (xy 59.776652 -319.92035) (xy 59.719599 -319.970272) (xy 59.657563 -320.013847)
			(xy 59.591246 -320.050582) (xy 59.5214 -320.080059) (xy 59.448817 -320.101945) (xy 59.374319 -320.115992)
			(xy 59.298749 -320.122041) (xy 59.222965 -320.120022) (xy 59.147825 -320.10996) (xy 59.07418 -320.091968)
			(xy 59.002864 -320.06625) (xy 58.934687 -320.033098) (xy 58.870419 -319.992886) (xy 58.81079 -319.946071)
			(xy 58.756474 -319.893183) (xy 58.708088 -319.834821) (xy 58.66618 -319.771646) (xy 58.631224 -319.704375)
			(xy 58.603617 -319.63377) (xy 58.583671 -319.560629) (xy 58.571612 -319.485784) (xy 58.567577 -319.41008)
			(xy 57.451498 -319.41008) (xy 57.450994 -319.447986) (xy 57.442935 -319.523367) (xy 57.42691 -319.597465)
			(xy 57.4031 -319.66944) (xy 57.371774 -319.738476) (xy 57.333287 -319.803791) (xy 57.288076 -319.864646)
			(xy 57.236652 -319.92035) (xy 57.179599 -319.970272) (xy 57.117563 -320.013847) (xy 57.051246 -320.050582)
			(xy 56.9814 -320.080059) (xy 56.908817 -320.101945) (xy 56.834319 -320.115992) (xy 56.758749 -320.122041)
			(xy 56.682965 -320.120022) (xy 56.607825 -320.10996) (xy 56.53418 -320.091968) (xy 56.462864 -320.06625)
			(xy 56.394687 -320.033098) (xy 56.330419 -319.992886) (xy 56.27079 -319.946071) (xy 56.216474 -319.893183)
			(xy 56.168088 -319.834821) (xy 56.12618 -319.771646) (xy 56.091224 -319.704375) (xy 56.063617 -319.63377)
			(xy 56.043671 -319.560629) (xy 56.031612 -319.485784) (xy 56.027577 -319.41008) (xy 54.911498 -319.41008)
			(xy 54.910994 -319.447986) (xy 54.902935 -319.523367) (xy 54.88691 -319.597465) (xy 54.8631 -319.66944)
			(xy 54.831774 -319.738476) (xy 54.793287 -319.803791) (xy 54.748076 -319.864646) (xy 54.696652 -319.92035)
			(xy 54.639599 -319.970272) (xy 54.577563 -320.013847) (xy 54.511246 -320.050582) (xy 54.4414 -320.080059)
			(xy 54.368817 -320.101945) (xy 54.294319 -320.115992) (xy 54.218749 -320.122041) (xy 54.142965 -320.120022)
			(xy 54.067825 -320.10996) (xy 53.99418 -320.091968) (xy 53.922864 -320.06625) (xy 53.854687 -320.033098)
			(xy 53.790419 -319.992886) (xy 53.73079 -319.946071) (xy 53.676474 -319.893183) (xy 53.628088 -319.834821)
			(xy 53.58618 -319.771646) (xy 53.551224 -319.704375) (xy 53.523617 -319.63377) (xy 53.503671 -319.560629)
			(xy 53.491612 -319.485784) (xy 53.487577 -319.41008) (xy 52.371498 -319.41008) (xy 52.370994 -319.447986)
			(xy 52.362935 -319.523367) (xy 52.34691 -319.597465) (xy 52.3231 -319.66944) (xy 52.291774 -319.738476)
			(xy 52.253287 -319.803791) (xy 52.208076 -319.864646) (xy 52.156652 -319.92035) (xy 52.099599 -319.970272)
			(xy 52.037563 -320.013847) (xy 51.971246 -320.050582) (xy 51.9014 -320.080059) (xy 51.828817 -320.101945)
			(xy 51.754319 -320.115992) (xy 51.678749 -320.122041) (xy 51.602965 -320.120022) (xy 51.527825 -320.10996)
			(xy 51.45418 -320.091968) (xy 51.382864 -320.06625) (xy 51.314687 -320.033098) (xy 51.250419 -319.992886)
			(xy 51.19079 -319.946071) (xy 51.136474 -319.893183) (xy 51.088088 -319.834821) (xy 51.04618 -319.771646)
			(xy 51.011224 -319.704375) (xy 50.983617 -319.63377) (xy 50.963671 -319.560629) (xy 50.951612 -319.485784)
			(xy 50.947577 -319.41008) (xy 49.831498 -319.41008) (xy 49.830994 -319.447986) (xy 49.822935 -319.523367)
			(xy 49.80691 -319.597465) (xy 49.7831 -319.66944) (xy 49.751774 -319.738476) (xy 49.713287 -319.803791)
			(xy 49.668076 -319.864646) (xy 49.616652 -319.92035) (xy 49.559599 -319.970272) (xy 49.497563 -320.013847)
			(xy 49.431246 -320.050582) (xy 49.3614 -320.080059) (xy 49.288817 -320.101945) (xy 49.214319 -320.115992)
			(xy 49.138749 -320.122041) (xy 49.062965 -320.120022) (xy 48.987825 -320.10996) (xy 48.91418 -320.091968)
			(xy 48.842864 -320.06625) (xy 48.774687 -320.033098) (xy 48.710419 -319.992886) (xy 48.65079 -319.946071)
			(xy 48.596474 -319.893183) (xy 48.548088 -319.834821) (xy 48.50618 -319.771646) (xy 48.471224 -319.704375)
			(xy 48.443617 -319.63377) (xy 48.423671 -319.560629) (xy 48.411612 -319.485784) (xy 48.407577 -319.41008)
			(xy 47.291498 -319.41008) (xy 47.290994 -319.447986) (xy 47.282935 -319.523367) (xy 47.26691 -319.597465)
			(xy 47.2431 -319.66944) (xy 47.211774 -319.738476) (xy 47.173287 -319.803791) (xy 47.128076 -319.864646)
			(xy 47.076652 -319.92035) (xy 47.019599 -319.970272) (xy 46.957563 -320.013847) (xy 46.891246 -320.050582)
			(xy 46.8214 -320.080059) (xy 46.748817 -320.101945) (xy 46.674319 -320.115992) (xy 46.598749 -320.122041)
			(xy 46.522965 -320.120022) (xy 46.447825 -320.10996) (xy 46.37418 -320.091968) (xy 46.302864 -320.06625)
			(xy 46.234687 -320.033098) (xy 46.170419 -319.992886) (xy 46.11079 -319.946071) (xy 46.056474 -319.893183)
			(xy 46.008088 -319.834821) (xy 45.96618 -319.771646) (xy 45.931224 -319.704375) (xy 45.903617 -319.63377)
			(xy 45.883671 -319.560629) (xy 45.871612 -319.485784) (xy 45.867577 -319.41008) (xy 44.751498 -319.41008)
			(xy 44.750994 -319.447986) (xy 44.742935 -319.523367) (xy 44.72691 -319.597465) (xy 44.7031 -319.66944)
			(xy 44.671774 -319.738476) (xy 44.633287 -319.803791) (xy 44.588076 -319.864646) (xy 44.536652 -319.92035)
			(xy 44.479599 -319.970272) (xy 44.417563 -320.013847) (xy 44.351246 -320.050582) (xy 44.2814 -320.080059)
			(xy 44.208817 -320.101945) (xy 44.134319 -320.115992) (xy 44.058749 -320.122041) (xy 43.982965 -320.120022)
			(xy 43.907825 -320.10996) (xy 43.83418 -320.091968) (xy 43.762864 -320.06625) (xy 43.694687 -320.033098)
			(xy 43.630419 -319.992886) (xy 43.57079 -319.946071) (xy 43.516474 -319.893183) (xy 43.468088 -319.834821)
			(xy 43.42618 -319.771646) (xy 43.391224 -319.704375) (xy 43.363617 -319.63377) (xy 43.343671 -319.560629)
			(xy 43.331612 -319.485784) (xy 43.327577 -319.41008) (xy 42.502604 -319.41008) (xy 42.502322 -319.410305)
			(xy 42.406779 -319.476254) (xy 42.306914 -319.535454) (xy 42.203202 -319.587623) (xy 42.096139 -319.632512)
			(xy 41.986233 -319.669908) (xy 41.874009 -319.699633) (xy 41.760003 -319.721544) (xy 41.644756 -319.735537)
			(xy 41.528818 -319.741546) (xy 41.412742 -319.739543) (xy 41.29708 -319.729535) (xy 41.182385 -319.711572)
			(xy 41.069202 -319.685739) (xy 40.958071 -319.652159) (xy 40.849522 -319.610991) (xy 40.744072 -319.562433)
			(xy 40.642223 -319.506716) (xy 40.54446 -319.444104) (xy 40.45125 -319.374897) (xy 40.363037 -319.299424)
			(xy 40.280241 -319.218045) (xy 40.203257 -319.131148) (xy 40.132452 -319.039147) (xy 40.068162 -318.94248)
			(xy 40.010695 -318.841608) (xy 39.960324 -318.737011) (xy 39.917289 -318.629188) (xy 39.881795 -318.518654)
			(xy 39.854012 -318.405934) (xy 39.834072 -318.291566) (xy 39.82207 -318.176094) (xy 39.818063 -318.06007)
			(xy 36.479871 -318.06007) (xy 36.479486 -318.09336) (xy 36.471468 -318.179889) (xy 36.4555 -318.265309)
			(xy 36.431719 -318.348891) (xy 36.400327 -318.429923) (xy 36.361593 -318.507712) (xy 36.315846 -318.581596)
			(xy 36.263477 -318.650943) (xy 36.204933 -318.715163) (xy 36.140713 -318.773707) (xy 36.071366 -318.826076)
			(xy 35.997482 -318.871823) (xy 35.919693 -318.910557) (xy 35.838661 -318.941949) (xy 35.755079 -318.96573)
			(xy 35.669659 -318.981698) (xy 35.58313 -318.989716) (xy 35.49623 -318.989716) (xy 35.409701 -318.981698)
			(xy 35.324281 -318.96573) (xy 35.240699 -318.941949) (xy 35.159667 -318.910557) (xy 35.081878 -318.871823)
			(xy 35.007994 -318.826076) (xy 34.938647 -318.773707) (xy 34.874427 -318.715163) (xy 34.815883 -318.650943)
			(xy 34.763514 -318.581596) (xy 34.717767 -318.507712) (xy 34.679033 -318.429923) (xy 34.647641 -318.348891)
			(xy 34.62386 -318.265309) (xy 34.607892 -318.179889) (xy 34.599874 -318.09336) (xy 31.399486 -318.09336)
			(xy 31.391468 -318.179889) (xy 31.3755 -318.265309) (xy 31.351719 -318.348891) (xy 31.320327 -318.429923)
			(xy 31.281593 -318.507712) (xy 31.235846 -318.581596) (xy 31.183477 -318.650943) (xy 31.124933 -318.715163)
			(xy 31.060713 -318.773707) (xy 30.991366 -318.826076) (xy 30.917482 -318.871823) (xy 30.839693 -318.910557)
			(xy 30.758661 -318.941949) (xy 30.675079 -318.96573) (xy 30.589659 -318.981698) (xy 30.50313 -318.989716)
			(xy 30.41623 -318.989716) (xy 30.329701 -318.981698) (xy 30.244281 -318.96573) (xy 30.160699 -318.941949)
			(xy 30.079667 -318.910557) (xy 30.001878 -318.871823) (xy 29.927994 -318.826076) (xy 29.858647 -318.773707)
			(xy 29.794427 -318.715163) (xy 29.735883 -318.650943) (xy 29.683514 -318.581596) (xy 29.637767 -318.507712)
			(xy 29.599033 -318.429923) (xy 29.567641 -318.348891) (xy 29.54386 -318.265309) (xy 29.527892 -318.179889)
			(xy 29.519874 -318.09336) (xy 28.912312 -318.09336) (xy 28.912312 -327.821036) (xy 73.077322 -327.821036)
			(xy 73.081393 -327.765414) (xy 73.093519 -327.710977) (xy 73.113442 -327.658886) (xy 73.140738 -327.610251)
			(xy 73.174824 -327.566108) (xy 73.214973 -327.527399) (xy 73.260331 -327.494948) (xy 73.309931 -327.469447)
			(xy 73.362715 -327.45144) (xy 73.417558 -327.44131) (xy 73.473292 -327.439273) (xy 73.528729 -327.445373)
			(xy 73.582686 -327.459479) (xy 73.634015 -327.481291) (xy 73.681621 -327.510345) (xy 73.724489 -327.54602)
			(xy 73.761706 -327.587557) (xy 73.792479 -327.63407) (xy 73.816151 -327.684567) (xy 73.832219 -327.737974)
			(xy 73.840339 -327.79315) (xy 73.840848 -327.821036) (xy 74.327764 -327.821036) (xy 74.331835 -327.765414)
			(xy 74.343961 -327.710977) (xy 74.363884 -327.658886) (xy 74.39118 -327.610251) (xy 74.425266 -327.566108)
			(xy 74.465415 -327.527399) (xy 74.510773 -327.494948) (xy 74.560373 -327.469447) (xy 74.613157 -327.45144)
			(xy 74.668 -327.44131) (xy 74.723734 -327.439273) (xy 74.779171 -327.445373) (xy 74.833128 -327.459479)
			(xy 74.884457 -327.481291) (xy 74.932063 -327.510345) (xy 74.974931 -327.54602) (xy 75.012148 -327.587557)
			(xy 75.042921 -327.63407) (xy 75.066593 -327.684567) (xy 75.082661 -327.737974) (xy 75.090781 -327.79315)
			(xy 75.09129 -327.821036) (xy 75.090781 -327.848922) (xy 75.082661 -327.904098) (xy 75.066593 -327.957505)
			(xy 75.042921 -328.008002) (xy 75.012148 -328.054515) (xy 74.974931 -328.096052) (xy 74.932063 -328.131727)
			(xy 74.884457 -328.160781) (xy 74.833128 -328.182593) (xy 74.779171 -328.196699) (xy 74.723734 -328.202799)
			(xy 74.668 -328.200762) (xy 74.613157 -328.190632) (xy 74.560373 -328.172625) (xy 74.510773 -328.147124)
			(xy 74.465415 -328.114673) (xy 74.425266 -328.075964) (xy 74.39118 -328.031821) (xy 74.363884 -327.983186)
			(xy 74.343961 -327.931095) (xy 74.331835 -327.876658) (xy 74.327764 -327.821036) (xy 73.840848 -327.821036)
			(xy 73.840339 -327.848922) (xy 73.832219 -327.904098) (xy 73.816151 -327.957505) (xy 73.792479 -328.008002)
			(xy 73.761706 -328.054515) (xy 73.724489 -328.096052) (xy 73.681621 -328.131727) (xy 73.634015 -328.160781)
			(xy 73.582686 -328.182593) (xy 73.528729 -328.196699) (xy 73.473292 -328.202799) (xy 73.417558 -328.200762)
			(xy 73.362715 -328.190632) (xy 73.309931 -328.172625) (xy 73.260331 -328.147124) (xy 73.214973 -328.114673)
			(xy 73.174824 -328.075964) (xy 73.140738 -328.031821) (xy 73.113442 -327.983186) (xy 73.093519 -327.931095)
			(xy 73.081393 -327.876658) (xy 73.077322 -327.821036) (xy 28.912312 -327.821036) (xy 28.912312 -328.665586)
			(xy 71.705214 -328.665586) (xy 71.709285 -328.609964) (xy 71.721411 -328.555527) (xy 71.741334 -328.503436)
			(xy 71.76863 -328.454801) (xy 71.802716 -328.410658) (xy 71.842865 -328.371949) (xy 71.888223 -328.339498)
			(xy 71.937823 -328.313997) (xy 71.990607 -328.29599) (xy 72.04545 -328.28586) (xy 72.101184 -328.283823)
			(xy 72.156621 -328.289923) (xy 72.210578 -328.304029) (xy 72.261907 -328.325841) (xy 72.309513 -328.354895)
			(xy 72.352381 -328.39057) (xy 72.389598 -328.432107) (xy 72.420371 -328.47862) (xy 72.444043 -328.529117)
			(xy 72.460111 -328.582524) (xy 72.468231 -328.6377) (xy 72.46874 -328.665586) (xy 72.468231 -328.693472)
			(xy 72.460111 -328.748648) (xy 72.444043 -328.802055) (xy 72.420371 -328.852552) (xy 72.389598 -328.899065)
			(xy 72.352381 -328.940602) (xy 72.309513 -328.976277) (xy 72.261907 -329.005331) (xy 72.210578 -329.027143)
			(xy 72.156621 -329.041249) (xy 72.101184 -329.047349) (xy 72.04545 -329.045312) (xy 71.990607 -329.035182)
			(xy 71.937823 -329.017175) (xy 71.888223 -328.991674) (xy 71.842865 -328.959223) (xy 71.802716 -328.920514)
			(xy 71.76863 -328.876371) (xy 71.741334 -328.827736) (xy 71.721411 -328.775645) (xy 71.709285 -328.721208)
			(xy 71.705214 -328.665586) (xy 28.912312 -328.665586) (xy 28.912312 -330.012971) (xy 47.903374 -330.012971)
			(xy 47.903374 -329.931861) (xy 47.911324 -329.851142) (xy 47.927147 -329.771591) (xy 47.950692 -329.693975)
			(xy 47.981731 -329.619039) (xy 48.019966 -329.547507) (xy 48.065028 -329.480067) (xy 48.116483 -329.417368)
			(xy 48.173836 -329.360015) (xy 48.236535 -329.30856) (xy 48.303975 -329.263498) (xy 48.375507 -329.225263)
			(xy 48.450443 -329.194224) (xy 48.528059 -329.170679) (xy 48.60761 -329.154856) (xy 48.688329 -329.146906)
			(xy 48.769439 -329.146906) (xy 48.850158 -329.154856) (xy 48.929709 -329.170679) (xy 49.007325 -329.194224)
			(xy 49.082261 -329.225263) (xy 49.153793 -329.263498) (xy 49.221233 -329.30856) (xy 49.283932 -329.360015)
			(xy 49.341285 -329.417368) (xy 49.39274 -329.480067) (xy 49.437802 -329.547507) (xy 49.476037 -329.619039)
			(xy 49.507076 -329.693975) (xy 49.530621 -329.771591) (xy 49.546444 -329.851142) (xy 49.554394 -329.931861)
			(xy 49.554892 -329.972416) (xy 49.554394 -330.012971) (xy 49.546444 -330.09369) (xy 49.530621 -330.173241)
			(xy 49.507076 -330.250857) (xy 49.476037 -330.325793) (xy 49.437802 -330.397325) (xy 49.39274 -330.464765)
			(xy 49.341285 -330.527464) (xy 49.283932 -330.584817) (xy 49.221233 -330.636272) (xy 49.153793 -330.681334)
			(xy 49.082261 -330.719569) (xy 49.007325 -330.750608) (xy 48.929709 -330.774153) (xy 48.850158 -330.789976)
			(xy 48.769439 -330.797926) (xy 48.688329 -330.797926) (xy 48.60761 -330.789976) (xy 48.528059 -330.774153)
			(xy 48.450443 -330.750608) (xy 48.375507 -330.719569) (xy 48.303975 -330.681334) (xy 48.236535 -330.636272)
			(xy 48.173836 -330.584817) (xy 48.116483 -330.527464) (xy 48.065028 -330.464765) (xy 48.019966 -330.397325)
			(xy 47.981731 -330.325793) (xy 47.950692 -330.250857) (xy 47.927147 -330.173241) (xy 47.911324 -330.09369)
			(xy 47.903374 -330.012971) (xy 28.912312 -330.012971) (xy 28.912312 -348.234) (xy 29.068014 -348.389702)
			(xy 30.30601 -349.627952) (xy 30.318161 -349.639295) (xy 30.346958 -349.655873) (xy 30.379058 -349.664456)
			(xy 30.395672 -349.665036) (xy 43.162474 -349.665036) (xy 45.225462 -347.602048) (xy 59.333892 -347.602048)
			(xy 59.348493 -347.600961) (xy 59.376655 -347.592978) (xy 59.402258 -347.578788) (xy 59.413394 -347.569282)
			(xy 81.406492 -325.576184) (xy 81.415636 -325.544688) (xy 81.42371 -325.518286) (xy 81.446411 -325.46796)
			(xy 81.476129 -325.421431) (xy 81.512243 -325.379671) (xy 81.553999 -325.343553) (xy 81.600525 -325.31383)
			(xy 81.650849 -325.291124) (xy 81.677256 -325.283068) (xy 81.708752 -325.273924) (xy 85.28939 -321.693286)
			(xy 85.29891 -321.682161) (xy 85.313091 -321.656553) (xy 85.321057 -321.628385) (xy 85.322156 -321.613784)
			(xy 85.322156 -320.676016) (xy 85.321686 -320.659921) (xy 85.313628 -320.628756) (xy 85.298022 -320.600602)
			(xy 85.275862 -320.577254) (xy 85.262466 -320.56832) (xy 85.230486 -320.54774) (xy 85.170669 -320.50077)
			(xy 85.116203 -320.44769) (xy 85.067706 -320.389105) (xy 85.025734 -320.325682) (xy 84.990764 -320.258145)
			(xy 84.963195 -320.187264) (xy 84.943341 -320.113848) (xy 84.931429 -320.038733) (xy 84.927595 -319.962776)
			(xy 84.931882 -319.886843) (xy 84.9376 -319.849246) (xy 84.944134 -319.812614) (xy 84.96384 -319.740855)
			(xy 84.990925 -319.671545) (xy 85.025094 -319.605438) (xy 85.065973 -319.543258) (xy 85.113117 -319.485681)
			(xy 85.16601 -319.433338) (xy 85.224076 -319.386798) (xy 85.28668 -319.34657) (xy 85.35314 -319.313094)
			(xy 85.422729 -319.286734) (xy 85.49469 -319.267779) (xy 85.568235 -319.256434) (xy 85.642562 -319.252825)
			(xy 85.71686 -319.25699) (xy 85.790318 -319.268883) (xy 85.862134 -319.288376) (xy 85.931525 -319.315256)
			(xy 85.997733 -319.349228) (xy 86.060035 -319.389922) (xy 86.117751 -319.436894) (xy 86.144354 -319.462912)
			(xy 86.160753 -319.478679) (xy 86.198064 -319.504696) (xy 86.239413 -319.523652) (xy 86.283478 -319.534938)
			(xy 86.328848 -319.538195) (xy 86.374072 -319.533318) (xy 86.417705 -319.520463) (xy 86.45835 -319.500041)
			(xy 86.47684 -319.486788) (xy 86.591648 -319.37198) (xy 86.591648 -319.369948) (xy 86.496144 -319.27419)
			(xy 86.48827 -319.268602) (xy 86.458134 -319.24583) (xy 86.402355 -319.194894) (xy 86.352283 -319.138337)
			(xy 86.308482 -319.076796) (xy 86.271444 -319.010962) (xy 86.241585 -318.941577) (xy 86.219242 -318.86942)
			(xy 86.204666 -318.795302) (xy 86.19802 -318.720058) (xy 86.19938 -318.644533) (xy 86.20873 -318.569577)
			(xy 86.225965 -318.496032) (xy 86.250891 -318.424726) (xy 86.283227 -318.35646) (xy 86.322611 -318.292003)
			(xy 86.368599 -318.232078) (xy 86.420675 -318.17736) (xy 86.478252 -318.128465) (xy 86.540683 -318.085941)
			(xy 86.607266 -318.050268) (xy 86.677252 -318.021846) (xy 86.749854 -318.000996) (xy 86.824256 -317.98795)
			(xy 86.861904 -317.984886) (xy 86.909656 -317.981838) (xy 87.034624 -317.856362) (xy 87.034624 -316.993778)
			(xy 86.909656 -316.868302) (xy 86.861904 -316.865254) (xy 86.823869 -316.862187) (xy 86.748718 -316.848934)
			(xy 86.675416 -316.827717) (xy 86.604805 -316.798778) (xy 86.537696 -316.76245) (xy 86.474859 -316.719151)
			(xy 86.417015 -316.669377) (xy 86.364829 -316.613699) (xy 86.3189 -316.552758) (xy 86.279755 -316.487252)
			(xy 86.247844 -316.417934) (xy 86.223533 -316.345599) (xy 86.2071 -316.271079) (xy 86.198736 -316.195228)
			(xy 86.198535 -316.118917) (xy 86.2065 -316.043023) (xy 86.22254 -315.968417) (xy 86.24647 -315.895955)
			(xy 86.278016 -315.82647) (xy 86.297008 -315.793374) (xy 86.316569 -315.7612) (xy 86.361478 -315.700755)
			(xy 86.412516 -315.64539) (xy 86.469115 -315.595721) (xy 86.53064 -315.552305) (xy 86.596404 -315.515626)
			(xy 86.665674 -315.486095) (xy 86.737673 -315.464042) (xy 86.811599 -315.449712) (xy 86.886624 -315.443266)
			(xy 86.96191 -315.444776) (xy 87.036616 -315.454226) (xy 87.109907 -315.471509) (xy 87.180965 -315.496433)
			(xy 87.248994 -315.528718) (xy 87.313234 -315.568005) (xy 87.372969 -315.613853) (xy 87.42753 -315.665752)
			(xy 87.476307 -315.72312) (xy 87.518755 -315.785317) (xy 87.554401 -315.851647) (xy 87.56904 -315.886338)
			(xy 87.578086 -315.907224) (xy 87.602473 -315.945648) (xy 87.633314 -315.979115) (xy 87.669622 -316.006554)
			(xy 87.710237 -316.027087) (xy 87.753859 -316.040059) (xy 87.799095 -316.045054) (xy 87.844496 -316.041913)
			(xy 87.888613 -316.030736) (xy 87.930033 -316.011881) (xy 87.967433 -315.98595) (xy 87.983822 -315.970158)
			(xy 87.998808 -315.955426) (xy 88.116918 -315.837316) (xy 88.738964 -315.837316) (xy 88.755062 -315.836849)
			(xy 88.786233 -315.828797) (xy 88.814396 -315.813198) (xy 88.837757 -315.791044) (xy 88.84666 -315.777626)
			(xy 88.866969 -315.746082) (xy 88.913239 -315.68702) (xy 88.965465 -315.633154) (xy 89.02307 -315.585083)
			(xy 89.085412 -315.543338) (xy 89.1518 -315.508385) (xy 89.221497 -315.48061) (xy 89.29373 -315.460323)
			(xy 89.367696 -315.447748) (xy 89.442575 -315.443025) (xy 89.517535 -315.446207) (xy 89.591744 -315.457257)
			(xy 89.664379 -315.476054) (xy 89.734633 -315.502389) (xy 89.801726 -315.535969) (xy 89.864914 -315.576422)
			(xy 89.923495 -315.623299) (xy 89.976818 -315.676079) (xy 90.024293 -315.734176) (xy 90.065391 -315.796946)
			(xy 90.099658 -315.863691) (xy 90.126711 -315.933672) (xy 90.146252 -316.00611) (xy 90.158063 -316.080202)
			(xy 90.162009 -316.15507) (xy 91.277697 -316.15507) (xy 91.281732 -316.079366) (xy 91.293791 -316.004521)
			(xy 91.313737 -315.93138) (xy 91.341344 -315.860775) (xy 91.3763 -315.793504) (xy 91.418208 -315.730329)
			(xy 91.466594 -315.671967) (xy 91.52091 -315.619079) (xy 91.580539 -315.572264) (xy 91.644807 -315.532052)
			(xy 91.712984 -315.4989) (xy 91.7843 -315.473182) (xy 91.857945 -315.45519) (xy 91.933085 -315.445128)
			(xy 92.008869 -315.443109) (xy 92.084439 -315.449158) (xy 92.158937 -315.463205) (xy 92.23152 -315.485091)
			(xy 92.301366 -315.514568) (xy 92.367683 -315.551303) (xy 92.429719 -315.594878) (xy 92.486772 -315.6448)
			(xy 92.538196 -315.700504) (xy 92.583407 -315.761359) (xy 92.621894 -315.826674) (xy 92.65322 -315.89571)
			(xy 92.67703 -315.967685) (xy 92.693055 -316.041783) (xy 92.701114 -316.117164) (xy 92.701618 -316.15507)
			(xy 92.701114 -316.192976) (xy 92.693055 -316.268357) (xy 92.67703 -316.342455) (xy 92.65322 -316.41443)
			(xy 92.621894 -316.483466) (xy 92.583407 -316.548781) (xy 92.538196 -316.609636) (xy 92.486772 -316.66534)
			(xy 92.429719 -316.715262) (xy 92.367683 -316.758837) (xy 92.301366 -316.795572) (xy 92.23152 -316.825049)
			(xy 92.158937 -316.846935) (xy 92.084439 -316.860982) (xy 92.008869 -316.867031) (xy 91.933085 -316.865012)
			(xy 91.857945 -316.85495) (xy 91.7843 -316.836958) (xy 91.712984 -316.81124) (xy 91.644807 -316.778088)
			(xy 91.580539 -316.737876) (xy 91.52091 -316.691061) (xy 91.466594 -316.638173) (xy 91.418208 -316.579811)
			(xy 91.3763 -316.516636) (xy 91.341344 -316.449365) (xy 91.313737 -316.37876) (xy 91.293791 -316.305619)
			(xy 91.281732 -316.230774) (xy 91.277697 -316.15507) (xy 90.162009 -316.15507) (xy 90.162012 -316.155125)
			(xy 90.158057 -316.230049) (xy 90.146241 -316.30414) (xy 90.126695 -316.376577) (xy 90.099637 -316.446555)
			(xy 90.065366 -316.513298) (xy 90.024263 -316.576065) (xy 89.976784 -316.634159) (xy 89.923457 -316.686935)
			(xy 89.864872 -316.733807) (xy 89.801682 -316.774256) (xy 89.734586 -316.807831) (xy 89.66433 -316.834161)
			(xy 89.591694 -316.852953) (xy 89.517484 -316.863998) (xy 89.442524 -316.867174) (xy 89.367646 -316.862446)
			(xy 89.29368 -316.849866) (xy 89.221449 -316.829573) (xy 89.151754 -316.801794) (xy 89.085368 -316.766836)
			(xy 89.023029 -316.725087) (xy 88.965428 -316.677011) (xy 88.913205 -316.623142) (xy 88.86694 -316.564077)
			(xy 88.84666 -316.532514) (xy 88.83773 -316.519116) (xy 88.814379 -316.496962) (xy 88.786223 -316.481362)
			(xy 88.755058 -316.47331) (xy 88.738964 -316.472824) (xy 88.380316 -316.472824) (xy 88.32342 -316.52972)
			(xy 88.31198 -316.541837) (xy 88.295303 -316.570675) (xy 88.28667 -316.60285) (xy 88.286671 -316.636163)
			(xy 88.295308 -316.668337) (xy 88.311988 -316.697173) (xy 88.32342 -316.709298) (xy 88.346534 -316.732412)
			(xy 88.37803 -316.741556) (xy 88.413635 -316.752382) (xy 88.482561 -316.780451) (xy 88.548181 -316.815561)
			(xy 88.609778 -316.857328) (xy 88.666679 -316.905295) (xy 88.718263 -316.95894) (xy 88.763966 -317.017676)
			(xy 88.80329 -317.080861) (xy 88.835804 -317.147805) (xy 88.861153 -317.217777) (xy 88.87906 -317.290012)
			(xy 88.889331 -317.363722) (xy 88.89141 -317.42507) (xy 90.007697 -317.42507) (xy 90.011732 -317.349366)
			(xy 90.023791 -317.274521) (xy 90.043737 -317.20138) (xy 90.071344 -317.130775) (xy 90.1063 -317.063504)
			(xy 90.148208 -317.000329) (xy 90.196594 -316.941967) (xy 90.25091 -316.889079) (xy 90.310539 -316.842264)
			(xy 90.374807 -316.802052) (xy 90.442984 -316.7689) (xy 90.5143 -316.743182) (xy 90.587945 -316.72519)
			(xy 90.663085 -316.715128) (xy 90.738869 -316.713109) (xy 90.814439 -316.719158) (xy 90.888937 -316.733205)
			(xy 90.96152 -316.755091) (xy 91.031366 -316.784568) (xy 91.097683 -316.821303) (xy 91.159719 -316.864878)
			(xy 91.216772 -316.9148) (xy 91.268196 -316.970504) (xy 91.313407 -317.031359) (xy 91.351894 -317.096674)
			(xy 91.38322 -317.16571) (xy 91.40703 -317.237685) (xy 91.423055 -317.311783) (xy 91.431114 -317.387164)
			(xy 91.431618 -317.42507) (xy 91.431114 -317.462976) (xy 91.423055 -317.538357) (xy 91.40703 -317.612455)
			(xy 91.38322 -317.68443) (xy 91.351894 -317.753466) (xy 91.313407 -317.818781) (xy 91.268196 -317.879636)
			(xy 91.216772 -317.93534) (xy 91.159719 -317.985262) (xy 91.097683 -318.028837) (xy 91.031366 -318.065572)
			(xy 90.96152 -318.095049) (xy 90.888937 -318.116935) (xy 90.814439 -318.130982) (xy 90.738869 -318.137031)
			(xy 90.663085 -318.135012) (xy 90.587945 -318.12495) (xy 90.5143 -318.106958) (xy 90.442984 -318.08124)
			(xy 90.374807 -318.048088) (xy 90.310539 -318.007876) (xy 90.25091 -317.961061) (xy 90.196594 -317.908173)
			(xy 90.148208 -317.849811) (xy 90.1063 -317.786636) (xy 90.071344 -317.719365) (xy 90.043737 -317.64876)
			(xy 90.023791 -317.575619) (xy 90.011732 -317.500774) (xy 90.007697 -317.42507) (xy 88.89141 -317.42507)
			(xy 88.891852 -317.438102) (xy 88.886596 -317.512338) (xy 88.87362 -317.585621) (xy 88.853067 -317.657148)
			(xy 88.825161 -317.72614) (xy 88.790206 -317.791843) (xy 88.748584 -317.853538) (xy 88.700751 -317.910552)
			(xy 88.647228 -317.962263) (xy 88.5886 -318.008105) (xy 88.557354 -318.02832) (xy 88.54396 -318.037253)
			(xy 88.521812 -318.060607) (xy 88.506216 -318.088761) (xy 88.498163 -318.119923) (xy 88.497664 -318.136016)
			(xy 88.497664 -318.544194) (xy 88.498206 -318.560845) (xy 88.506823 -318.593012) (xy 88.523469 -318.621853)
			(xy 88.547013 -318.645405) (xy 88.575849 -318.662061) (xy 88.608014 -318.670688) (xy 88.624664 -318.671194)
			(xy 88.670892 -318.671194) (xy 88.74125 -318.61252) (xy 88.749632 -318.567054) (xy 88.757034 -318.529394)
			(xy 88.778876 -318.455814) (xy 88.808507 -318.385011) (xy 88.845585 -318.317808) (xy 88.889679 -318.254984)
			(xy 88.940277 -318.19727) (xy 88.996791 -318.145334) (xy 89.058565 -318.099782) (xy 89.124882 -318.061141)
			(xy 89.194972 -318.029859) (xy 89.268021 -318.006301) (xy 89.34318 -317.99074) (xy 89.419578 -317.983357)
			(xy 89.496326 -317.984236) (xy 89.572534 -317.993369) (xy 89.647317 -318.010649) (xy 89.719807 -318.035875)
			(xy 89.789161 -318.068754) (xy 89.854575 -318.108906) (xy 89.885266 -318.131952) (xy 89.915075 -318.155617)
			(xy 89.969988 -318.208324) (xy 90.018961 -318.266591) (xy 90.061435 -318.329753) (xy 90.096926 -318.397086)
			(xy 90.125028 -318.467824) (xy 90.145419 -318.541156) (xy 90.157867 -318.616246) (xy 90.16223 -318.692235)
			(xy 90.162089 -318.69507) (xy 91.277697 -318.69507) (xy 91.281732 -318.619366) (xy 91.293791 -318.544521)
			(xy 91.313737 -318.47138) (xy 91.341344 -318.400775) (xy 91.3763 -318.333504) (xy 91.418208 -318.270329)
			(xy 91.466594 -318.211967) (xy 91.52091 -318.159079) (xy 91.580539 -318.112264) (xy 91.644807 -318.072052)
			(xy 91.712984 -318.0389) (xy 91.7843 -318.013182) (xy 91.857945 -317.99519) (xy 91.933085 -317.985128)
			(xy 92.008869 -317.983109) (xy 92.084439 -317.989158) (xy 92.158937 -318.003205) (xy 92.23152 -318.025091)
			(xy 92.301366 -318.054568) (xy 92.367683 -318.091303) (xy 92.429719 -318.134878) (xy 92.486772 -318.1848)
			(xy 92.538196 -318.240504) (xy 92.583407 -318.301359) (xy 92.621894 -318.366674) (xy 92.65322 -318.43571)
			(xy 92.67703 -318.507685) (xy 92.693055 -318.581783) (xy 92.701114 -318.657164) (xy 92.701618 -318.69507)
			(xy 92.701114 -318.732976) (xy 92.693055 -318.808357) (xy 92.67703 -318.882455) (xy 92.65322 -318.95443)
			(xy 92.621894 -319.023466) (xy 92.583407 -319.088781) (xy 92.538196 -319.149636) (xy 92.486772 -319.20534)
			(xy 92.429719 -319.255262) (xy 92.367683 -319.298837) (xy 92.301366 -319.335572) (xy 92.23152 -319.365049)
			(xy 92.158937 -319.386935) (xy 92.084439 -319.400982) (xy 92.008869 -319.407031) (xy 91.933085 -319.405012)
			(xy 91.857945 -319.39495) (xy 91.7843 -319.376958) (xy 91.712984 -319.35124) (xy 91.644807 -319.318088)
			(xy 91.580539 -319.277876) (xy 91.52091 -319.231061) (xy 91.466594 -319.178173) (xy 91.418208 -319.119811)
			(xy 91.3763 -319.056636) (xy 91.341344 -318.989365) (xy 91.313737 -318.91876) (xy 91.293791 -318.845619)
			(xy 91.281732 -318.770774) (xy 91.277697 -318.69507) (xy 90.162089 -318.69507) (xy 90.158457 -318.768256)
			(xy 90.146592 -318.843441) (xy 90.126771 -318.916929) (xy 90.09922 -318.987882) (xy 90.064253 -319.05549)
			(xy 90.02227 -319.118979) (xy 89.973751 -319.177625) (xy 89.919249 -319.230757) (xy 89.859388 -319.277769)
			(xy 89.827354 -319.29832) (xy 89.81396 -319.307253) (xy 89.791812 -319.330607) (xy 89.776216 -319.358761)
			(xy 89.768163 -319.389923) (xy 89.767664 -319.406016) (xy 89.767664 -319.814194) (xy 89.768206 -319.830845)
			(xy 89.776823 -319.863012) (xy 89.793469 -319.891853) (xy 89.817013 -319.915405) (xy 89.845849 -319.932061)
			(xy 89.878014 -319.940688) (xy 89.894664 -319.941194) (xy 89.940892 -319.941194) (xy 90.01125 -319.88252)
			(xy 90.019632 -319.837054) (xy 90.02695 -319.799741) (xy 90.048513 -319.72682) (xy 90.077726 -319.656613)
			(xy 90.114256 -319.58992) (xy 90.157686 -319.5275) (xy 90.207523 -319.470066) (xy 90.263198 -319.41827)
			(xy 90.324076 -319.372705) (xy 90.389464 -319.333888) (xy 90.458618 -319.302262) (xy 90.530749 -319.278187)
			(xy 90.605034 -319.261938) (xy 90.680629 -319.2537) (xy 90.756671 -319.253566) (xy 90.832294 -319.261539)
			(xy 90.906636 -319.277527) (xy 90.978851 -319.301348) (xy 91.048115 -319.33273) (xy 91.11364 -319.371317)
			(xy 91.16581 -319.41008) (xy 93.154506 -319.41008) (xy 93.158522 -319.29381) (xy 93.170549 -319.178095)
			(xy 93.190531 -319.063485) (xy 93.218373 -318.950526) (xy 93.253942 -318.839758) (xy 93.297068 -318.731707)
			(xy 93.347545 -318.626889) (xy 93.405134 -318.525804) (xy 93.46956 -318.428932) (xy 93.540515 -318.336736)
			(xy 93.617662 -318.249655) (xy 93.700633 -318.168104) (xy 93.789033 -318.092472) (xy 93.88244 -318.023118)
			(xy 93.980409 -317.960375) (xy 94.082473 -317.904539) (xy 94.188147 -317.855878) (xy 94.296926 -317.814624)
			(xy 94.408291 -317.780973) (xy 94.521714 -317.755085) (xy 94.636651 -317.737084) (xy 94.752557 -317.727055)
			(xy 94.868879 -317.725047) (xy 94.985062 -317.731069) (xy 95.100553 -317.745092) (xy 95.214801 -317.76705)
			(xy 95.327262 -317.796837) (xy 95.4374 -317.834312) (xy 95.54469 -317.879297) (xy 95.648621 -317.931576)
			(xy 95.748697 -317.990901) (xy 95.844443 -318.056989) (xy 95.9354 -318.129525) (xy 96.021136 -318.208164)
			(xy 96.101243 -318.29253) (xy 96.175339 -318.382222) (xy 96.243069 -318.476812) (xy 96.304113 -318.57585)
			(xy 96.358178 -318.678863) (xy 96.405008 -318.78536) (xy 96.444379 -318.894835) (xy 96.476103 -319.006765)
			(xy 96.500029 -319.120617) (xy 96.516043 -319.235849) (xy 96.52407 -319.351911) (xy 96.524572 -319.41008)
			(xy 96.52407 -319.468249) (xy 96.516043 -319.584311) (xy 96.500029 -319.699543) (xy 96.476103 -319.813395)
			(xy 96.444379 -319.925325) (xy 96.405008 -320.0348) (xy 96.358178 -320.141297) (xy 96.304113 -320.24431)
			(xy 96.243069 -320.343348) (xy 96.175339 -320.437938) (xy 96.101243 -320.52763) (xy 96.021136 -320.611996)
			(xy 95.9354 -320.690635) (xy 95.844443 -320.763171) (xy 95.748697 -320.829259) (xy 95.648621 -320.888584)
			(xy 95.54469 -320.940863) (xy 95.4374 -320.985848) (xy 95.327262 -321.023323) (xy 95.214801 -321.05311)
			(xy 95.100553 -321.075068) (xy 94.985062 -321.089091) (xy 94.868879 -321.095113) (xy 94.752557 -321.093105)
			(xy 94.636651 -321.083076) (xy 94.521714 -321.065075) (xy 94.408291 -321.039187) (xy 94.296926 -321.005536)
			(xy 94.188147 -320.964282) (xy 94.082473 -320.915621) (xy 93.980409 -320.859785) (xy 93.88244 -320.797042)
			(xy 93.789033 -320.727688) (xy 93.700633 -320.652056) (xy 93.617662 -320.570505) (xy 93.540515 -320.483424)
			(xy 93.46956 -320.391228) (xy 93.405134 -320.294356) (xy 93.347545 -320.193271) (xy 93.297068 -320.088453)
			(xy 93.253942 -319.980402) (xy 93.218373 -319.869634) (xy 93.190531 -319.756675) (xy 93.170549 -319.642065)
			(xy 93.158522 -319.52635) (xy 93.154506 -319.41008) (xy 91.16581 -319.41008) (xy 91.174678 -319.416669)
			(xy 91.230534 -319.468268) (xy 91.280573 -319.525527) (xy 91.324222 -319.587793) (xy 91.360986 -319.654358)
			(xy 91.390446 -319.724462) (xy 91.412265 -319.797306) (xy 91.426195 -319.872062) (xy 91.432078 -319.947876)
			(xy 91.429846 -320.023885) (xy 91.419524 -320.099224) (xy 91.401232 -320.173033) (xy 91.375176 -320.244472)
			(xy 91.341653 -320.312726) (xy 91.301046 -320.377018) (xy 91.253818 -320.436616) (xy 91.200506 -320.49084)
			(xy 91.141718 -320.539073) (xy 91.078124 -320.580764) (xy 91.010448 -320.61544) (xy 90.939462 -320.642704)
			(xy 90.865974 -320.662247) (xy 90.790821 -320.673844) (xy 90.714861 -320.677366) (xy 90.638957 -320.67277)
			(xy 90.563977 -320.66011) (xy 90.490772 -320.63953) (xy 90.420179 -320.611264) (xy 90.353 -320.575635)
			(xy 90.290002 -320.533048) (xy 90.231902 -320.483988) (xy 90.205306 -320.456814) (xy 90.189091 -320.440561)
			(xy 90.151931 -320.41361) (xy 90.110536 -320.393767) (xy 90.066251 -320.381678) (xy 90.020515 -320.377735)
			(xy 89.974815 -320.382067) (xy 89.930635 -320.394533) (xy 89.88941 -320.414728) (xy 89.852481 -320.441995)
			(xy 89.821046 -320.475449) (xy 89.796128 -320.514003) (xy 89.778536 -320.556403) (xy 89.768842 -320.601273)
			(xy 89.767664 -320.6242) (xy 89.767664 -322.325746) (xy 86.239858 -325.853806) (xy 86.230714 -325.885302)
			(xy 86.222635 -325.911701) (xy 86.199928 -325.962021) (xy 86.170206 -326.008544) (xy 86.134091 -326.050298)
			(xy 86.092336 -326.086412) (xy 86.045812 -326.116132) (xy 85.995492 -326.138839) (xy 85.969094 -326.146922)
			(xy 85.937598 -326.156066) (xy 80.933544 -331.16012) (xy 86.877404 -331.16012) (xy 86.881424 -330.969469)
			(xy 86.893478 -330.779156) (xy 86.913544 -330.589521) (xy 86.941587 -330.4009) (xy 86.977556 -330.21363)
			(xy 87.021388 -330.028042) (xy 87.073005 -329.844467) (xy 87.132315 -329.663231) (xy 87.199213 -329.484656)
			(xy 87.273579 -329.309061) (xy 87.355281 -329.136756) (xy 87.444175 -328.968049) (xy 87.540101 -328.803239)
			(xy 87.64289 -328.64262) (xy 87.752359 -328.486477) (xy 87.868313 -328.335088) (xy 87.990547 -328.188721)
			(xy 88.118841 -328.047637) (xy 88.252969 -327.912088) (xy 88.392693 -327.782313) (xy 88.537763 -327.658543)
			(xy 88.687921 -327.541) (xy 88.842902 -327.429891) (xy 89.002429 -327.325414) (xy 89.166218 -327.227755)
			(xy 89.333978 -327.137088) (xy 89.505412 -327.053574) (xy 89.680214 -326.977361) (xy 89.858073 -326.908585)
			(xy 90.038674 -326.847367) (xy 90.221694 -326.793818) (xy 90.40681 -326.748032) (xy 90.593691 -326.71009)
			(xy 90.782006 -326.680061) (xy 90.971419 -326.657996) (xy 91.161593 -326.643937) (xy 91.352192 -326.637907)
			(xy 91.542875 -326.639917) (xy 91.733304 -326.649964) (xy 91.92314 -326.66803) (xy 92.112046 -326.694083)
			(xy 92.299685 -326.728076) (xy 92.485725 -326.769949) (xy 92.669834 -326.819628) (xy 92.851685 -326.877024)
			(xy 93.030955 -326.942035) (xy 93.207325 -327.014546) (xy 93.380481 -327.094427) (xy 93.550116 -327.181537)
			(xy 93.715928 -327.275721) (xy 93.877622 -327.376812) (xy 94.03491 -327.484628) (xy 94.187513 -327.59898)
			(xy 94.335161 -327.719663) (xy 94.477589 -327.846464) (xy 94.614545 -327.979155) (xy 94.745786 -328.117503)
			(xy 94.871078 -328.26126) (xy 94.990198 -328.410171) (xy 95.102934 -328.563972) (xy 95.209087 -328.722388)
			(xy 95.308467 -328.885139) (xy 95.400897 -329.051934) (xy 95.486214 -329.222478) (xy 95.564266 -329.396466)
			(xy 95.634913 -329.573591) (xy 95.698031 -329.753536) (xy 95.753507 -329.935982) (xy 95.801242 -330.120605)
			(xy 95.841152 -330.307075) (xy 95.873165 -330.495063) (xy 95.897225 -330.684233) (xy 95.913288 -330.874249)
			(xy 95.921327 -331.064773) (xy 95.92183 -331.16012) (xy 95.921327 -331.255467) (xy 95.913288 -331.445991)
			(xy 95.897225 -331.636007) (xy 95.873165 -331.825177) (xy 95.841152 -332.013165) (xy 95.801242 -332.199635)
			(xy 95.753507 -332.384258) (xy 95.698031 -332.566704) (xy 95.634913 -332.746649) (xy 95.564266 -332.923774)
			(xy 95.486214 -333.097762) (xy 95.400897 -333.268306) (xy 95.308467 -333.435101) (xy 95.209087 -333.597852)
			(xy 95.102934 -333.756268) (xy 94.990198 -333.910069) (xy 94.871078 -334.05898) (xy 94.745786 -334.202737)
			(xy 94.614545 -334.341085) (xy 94.477589 -334.473776) (xy 94.335161 -334.600577) (xy 94.187513 -334.72126)
			(xy 94.03491 -334.835612) (xy 93.877622 -334.943428) (xy 93.715928 -335.044519) (xy 93.550116 -335.138703)
			(xy 93.380481 -335.225813) (xy 93.207325 -335.305694) (xy 93.030955 -335.378205) (xy 92.851685 -335.443216)
			(xy 92.669834 -335.500612) (xy 92.485725 -335.550291) (xy 92.299685 -335.592164) (xy 92.112046 -335.626157)
			(xy 91.92314 -335.65221) (xy 91.733304 -335.670276) (xy 91.542875 -335.680323) (xy 91.352192 -335.682333)
			(xy 91.161593 -335.676303) (xy 90.971419 -335.662244) (xy 90.782006 -335.640179) (xy 90.593691 -335.61015)
			(xy 90.40681 -335.572208) (xy 90.221694 -335.526422) (xy 90.038674 -335.472873) (xy 89.858073 -335.411655)
			(xy 89.680214 -335.342879) (xy 89.505412 -335.266666) (xy 89.333978 -335.183152) (xy 89.166218 -335.092485)
			(xy 89.002429 -334.994826) (xy 88.842902 -334.890349) (xy 88.687921 -334.77924) (xy 88.537763 -334.661697)
			(xy 88.392693 -334.537927) (xy 88.252969 -334.408152) (xy 88.118841 -334.272603) (xy 87.990547 -334.131519)
			(xy 87.868313 -333.985152) (xy 87.752359 -333.833763) (xy 87.64289 -333.67762) (xy 87.540101 -333.517001)
			(xy 87.444175 -333.352191) (xy 87.355281 -333.183484) (xy 87.273579 -333.011179) (xy 87.199213 -332.835584)
			(xy 87.132315 -332.657009) (xy 87.073005 -332.475773) (xy 87.021388 -332.292198) (xy 86.977556 -332.10661)
			(xy 86.941587 -331.91934) (xy 86.913544 -331.730719) (xy 86.893478 -331.541084) (xy 86.881424 -331.350771)
			(xy 86.877404 -331.16012) (xy 80.933544 -331.16012) (xy 76.140056 -335.953608) (xy 76.12439 -335.969973)
			(xy 76.098541 -336.007172) (xy 76.079698 -336.048365) (xy 76.068457 -336.092246) (xy 76.065175 -336.137426)
			(xy 76.069955 -336.182471) (xy 76.082647 -336.225955) (xy 76.102848 -336.266499) (xy 76.129918 -336.30282)
			(xy 76.162999 -336.333765) (xy 76.201042 -336.358354) (xy 76.242843 -336.375808) (xy 76.287076 -336.385573)
			(xy 76.33234 -336.387341) (xy 76.3772 -336.381056) (xy 76.398882 -336.374486) (xy 76.49559 -336.343248)
			(xy 76.691056 -336.287522) (xy 76.888575 -336.239579) (xy 77.087838 -336.199495) (xy 77.288531 -336.167332)
			(xy 77.490341 -336.143142) (xy 77.69295 -336.126962) (xy 77.896041 -336.118817) (xy 78.099295 -336.118721)
			(xy 78.302393 -336.126673) (xy 78.505018 -336.142661) (xy 78.70685 -336.16666) (xy 78.907574 -336.198632)
			(xy 79.106874 -336.238527) (xy 79.304439 -336.286283) (xy 79.499957 -336.341824) (xy 79.693123 -336.405064)
			(xy 79.883633 -336.475903) (xy 80.071189 -336.554231) (xy 80.255495 -336.639923) (xy 80.436265 -336.732847)
			(xy 80.613213 -336.832855) (xy 80.786062 -336.939792) (xy 80.954541 -337.05349) (xy 81.118385 -337.173769)
			(xy 81.277339 -337.300442) (xy 81.431152 -337.43331) (xy 81.579583 -337.572164) (xy 81.722399 -337.716787)
			(xy 81.776325 -337.775905) (xy 89.380306 -337.775905) (xy 89.380306 -337.704583) (xy 89.388292 -337.633709)
			(xy 89.404162 -337.564174) (xy 89.427719 -337.496854) (xy 89.458664 -337.432595) (xy 89.49661 -337.372204)
			(xy 89.541079 -337.316442) (xy 89.591512 -337.266009) (xy 89.647274 -337.22154) (xy 89.707665 -337.183594)
			(xy 89.771924 -337.152649) (xy 89.839244 -337.129092) (xy 89.908779 -337.113222) (xy 89.979653 -337.105236)
			(xy 90.050975 -337.105236) (xy 90.121849 -337.113222) (xy 90.191384 -337.129092) (xy 90.258704 -337.152649)
			(xy 90.322963 -337.183594) (xy 90.383354 -337.22154) (xy 90.439116 -337.266009) (xy 90.489549 -337.316442)
			(xy 90.534018 -337.372204) (xy 90.571964 -337.432595) (xy 90.602909 -337.496854) (xy 90.626466 -337.564174)
			(xy 90.642336 -337.633709) (xy 90.650322 -337.704583) (xy 90.650822 -337.740244) (xy 90.650322 -337.775905)
			(xy 92.371918 -337.775905) (xy 92.371918 -337.704583) (xy 92.379904 -337.633709) (xy 92.395774 -337.564174)
			(xy 92.419331 -337.496854) (xy 92.450276 -337.432595) (xy 92.488222 -337.372204) (xy 92.532691 -337.316442)
			(xy 92.583124 -337.266009) (xy 92.638886 -337.22154) (xy 92.699277 -337.183594) (xy 92.763536 -337.152649)
			(xy 92.830856 -337.129092) (xy 92.900391 -337.113222) (xy 92.971265 -337.105236) (xy 93.042587 -337.105236)
			(xy 93.113461 -337.113222) (xy 93.182996 -337.129092) (xy 93.250316 -337.152649) (xy 93.314575 -337.183594)
			(xy 93.374966 -337.22154) (xy 93.430728 -337.266009) (xy 93.481161 -337.316442) (xy 93.52563 -337.372204)
			(xy 93.563576 -337.432595) (xy 93.594521 -337.496854) (xy 93.618078 -337.564174) (xy 93.633948 -337.633709)
			(xy 93.641934 -337.704583) (xy 93.642434 -337.740244) (xy 93.641934 -337.775905) (xy 93.633948 -337.846779)
			(xy 93.618078 -337.916314) (xy 93.594521 -337.983634) (xy 93.563576 -338.047893) (xy 93.52563 -338.108284)
			(xy 93.481161 -338.164046) (xy 93.430728 -338.214479) (xy 93.374966 -338.258948) (xy 93.314575 -338.296894)
			(xy 93.250316 -338.327839) (xy 93.182996 -338.351396) (xy 93.113461 -338.367266) (xy 93.042587 -338.375252)
			(xy 92.971265 -338.375252) (xy 92.900391 -338.367266) (xy 92.830856 -338.351396) (xy 92.763536 -338.327839)
			(xy 92.699277 -338.296894) (xy 92.638886 -338.258948) (xy 92.583124 -338.214479) (xy 92.532691 -338.164046)
			(xy 92.488222 -338.108284) (xy 92.450276 -338.047893) (xy 92.419331 -337.983634) (xy 92.395774 -337.916314)
			(xy 92.379904 -337.846779) (xy 92.371918 -337.775905) (xy 90.650322 -337.775905) (xy 90.642336 -337.846779)
			(xy 90.626466 -337.916314) (xy 90.602909 -337.983634) (xy 90.571964 -338.047893) (xy 90.534018 -338.108284)
			(xy 90.489549 -338.164046) (xy 90.439116 -338.214479) (xy 90.383354 -338.258948) (xy 90.322963 -338.296894)
			(xy 90.258704 -338.327839) (xy 90.191384 -338.351396) (xy 90.121849 -338.367266) (xy 90.050975 -338.375252)
			(xy 89.979653 -338.375252) (xy 89.908779 -338.367266) (xy 89.839244 -338.351396) (xy 89.771924 -338.327839)
			(xy 89.707665 -338.296894) (xy 89.647274 -338.258948) (xy 89.591512 -338.214479) (xy 89.541079 -338.164046)
			(xy 89.49661 -338.108284) (xy 89.458664 -338.047893) (xy 89.427719 -337.983634) (xy 89.404162 -337.916314)
			(xy 89.388292 -337.846779) (xy 89.380306 -337.775905) (xy 81.776325 -337.775905) (xy 81.859376 -337.866952)
			(xy 81.9903 -338.022423) (xy 82.114965 -338.182956) (xy 82.233176 -338.3483) (xy 82.344747 -338.518195)
			(xy 82.449502 -338.692374) (xy 82.547279 -338.870565) (xy 82.637923 -339.052488) (xy 82.721292 -339.237858)
			(xy 82.797255 -339.426383) (xy 82.865694 -339.617768) (xy 82.926501 -339.811714) (xy 82.97958 -340.007915)
			(xy 83.024849 -340.206064) (xy 83.062236 -340.40585) (xy 83.068219 -340.446715) (xy 89.380306 -340.446715)
			(xy 89.380306 -340.375393) (xy 89.388292 -340.304519) (xy 89.404162 -340.234984) (xy 89.427719 -340.167664)
			(xy 89.458664 -340.103405) (xy 89.49661 -340.043014) (xy 89.541079 -339.987252) (xy 89.591512 -339.936819)
			(xy 89.647274 -339.89235) (xy 89.707665 -339.854404) (xy 89.771924 -339.823459) (xy 89.839244 -339.799902)
			(xy 89.908779 -339.784032) (xy 89.979653 -339.776046) (xy 90.050975 -339.776046) (xy 90.121849 -339.784032)
			(xy 90.191384 -339.799902) (xy 90.258704 -339.823459) (xy 90.322963 -339.854404) (xy 90.383354 -339.89235)
			(xy 90.439116 -339.936819) (xy 90.489549 -339.987252) (xy 90.534018 -340.043014) (xy 90.571964 -340.103405)
			(xy 90.602909 -340.167664) (xy 90.626466 -340.234984) (xy 90.642336 -340.304519) (xy 90.650322 -340.375393)
			(xy 90.650822 -340.411054) (xy 90.650322 -340.446715) (xy 92.371918 -340.446715) (xy 92.371918 -340.375393)
			(xy 92.379904 -340.304519) (xy 92.395774 -340.234984) (xy 92.419331 -340.167664) (xy 92.450276 -340.103405)
			(xy 92.488222 -340.043014) (xy 92.532691 -339.987252) (xy 92.583124 -339.936819) (xy 92.638886 -339.89235)
			(xy 92.699277 -339.854404) (xy 92.763536 -339.823459) (xy 92.830856 -339.799902) (xy 92.900391 -339.784032)
			(xy 92.971265 -339.776046) (xy 93.042587 -339.776046) (xy 93.113461 -339.784032) (xy 93.182996 -339.799902)
			(xy 93.250316 -339.823459) (xy 93.314575 -339.854404) (xy 93.374966 -339.89235) (xy 93.430728 -339.936819)
			(xy 93.481161 -339.987252) (xy 93.52563 -340.043014) (xy 93.563576 -340.103405) (xy 93.594521 -340.167664)
			(xy 93.618078 -340.234984) (xy 93.633948 -340.304519) (xy 93.641934 -340.375393) (xy 93.642434 -340.411054)
			(xy 93.641934 -340.446715) (xy 93.633948 -340.517589) (xy 93.618078 -340.587124) (xy 93.594521 -340.654444)
			(xy 93.563576 -340.718703) (xy 93.52563 -340.779094) (xy 93.481161 -340.834856) (xy 93.430728 -340.885289)
			(xy 93.374966 -340.929758) (xy 93.314575 -340.967704) (xy 93.250316 -340.998649) (xy 93.182996 -341.022206)
			(xy 93.113461 -341.038076) (xy 93.042587 -341.046062) (xy 92.971265 -341.046062) (xy 92.900391 -341.038076)
			(xy 92.830856 -341.022206) (xy 92.763536 -340.998649) (xy 92.699277 -340.967704) (xy 92.638886 -340.929758)
			(xy 92.583124 -340.885289) (xy 92.532691 -340.834856) (xy 92.488222 -340.779094) (xy 92.450276 -340.718703)
			(xy 92.419331 -340.654444) (xy 92.395774 -340.587124) (xy 92.379904 -340.517589) (xy 92.371918 -340.446715)
			(xy 90.650322 -340.446715) (xy 90.642336 -340.517589) (xy 90.626466 -340.587124) (xy 90.602909 -340.654444)
			(xy 90.571964 -340.718703) (xy 90.534018 -340.779094) (xy 90.489549 -340.834856) (xy 90.439116 -340.885289)
			(xy 90.383354 -340.929758) (xy 90.322963 -340.967704) (xy 90.258704 -340.998649) (xy 90.191384 -341.022206)
			(xy 90.121849 -341.038076) (xy 90.050975 -341.046062) (xy 89.979653 -341.046062) (xy 89.908779 -341.038076)
			(xy 89.839244 -341.022206) (xy 89.771924 -340.998649) (xy 89.707665 -340.967704) (xy 89.647274 -340.929758)
			(xy 89.591512 -340.885289) (xy 89.541079 -340.834856) (xy 89.49661 -340.779094) (xy 89.458664 -340.718703)
			(xy 89.427719 -340.654444) (xy 89.404162 -340.587124) (xy 89.388292 -340.517589) (xy 89.380306 -340.446715)
			(xy 83.068219 -340.446715) (xy 83.091682 -340.60696) (xy 83.113143 -340.809078) (xy 83.126582 -341.011887)
			(xy 83.131981 -341.21507) (xy 83.12933 -341.418307) (xy 83.118633 -341.621279) (xy 83.099907 -341.823669)
			(xy 83.073182 -342.025159) (xy 83.038499 -342.225432) (xy 82.995914 -342.424175) (xy 82.945492 -342.621075)
			(xy 82.887312 -342.815825) (xy 82.821467 -343.008118) (xy 82.780077 -343.114985) (xy 89.380306 -343.114985)
			(xy 89.380306 -343.043663) (xy 89.388292 -342.972789) (xy 89.404162 -342.903254) (xy 89.427719 -342.835934)
			(xy 89.458664 -342.771675) (xy 89.49661 -342.711284) (xy 89.541079 -342.655522) (xy 89.591512 -342.605089)
			(xy 89.647274 -342.56062) (xy 89.707665 -342.522674) (xy 89.771924 -342.491729) (xy 89.839244 -342.468172)
			(xy 89.908779 -342.452302) (xy 89.979653 -342.444316) (xy 90.050975 -342.444316) (xy 90.121849 -342.452302)
			(xy 90.191384 -342.468172) (xy 90.258704 -342.491729) (xy 90.322963 -342.522674) (xy 90.383354 -342.56062)
			(xy 90.439116 -342.605089) (xy 90.489549 -342.655522) (xy 90.534018 -342.711284) (xy 90.571964 -342.771675)
			(xy 90.602909 -342.835934) (xy 90.626466 -342.903254) (xy 90.642336 -342.972789) (xy 90.650322 -343.043663)
			(xy 90.650822 -343.079324) (xy 90.650322 -343.114985) (xy 92.371918 -343.114985) (xy 92.371918 -343.043663)
			(xy 92.379904 -342.972789) (xy 92.395774 -342.903254) (xy 92.419331 -342.835934) (xy 92.450276 -342.771675)
			(xy 92.488222 -342.711284) (xy 92.532691 -342.655522) (xy 92.583124 -342.605089) (xy 92.638886 -342.56062)
			(xy 92.699277 -342.522674) (xy 92.763536 -342.491729) (xy 92.830856 -342.468172) (xy 92.900391 -342.452302)
			(xy 92.971265 -342.444316) (xy 93.042587 -342.444316) (xy 93.113461 -342.452302) (xy 93.182996 -342.468172)
			(xy 93.250316 -342.491729) (xy 93.314575 -342.522674) (xy 93.374966 -342.56062) (xy 93.430728 -342.605089)
			(xy 93.481161 -342.655522) (xy 93.52563 -342.711284) (xy 93.563576 -342.771675) (xy 93.594521 -342.835934)
			(xy 93.618078 -342.903254) (xy 93.633948 -342.972789) (xy 93.641934 -343.043663) (xy 93.642434 -343.079324)
			(xy 93.641934 -343.114985) (xy 93.633948 -343.185859) (xy 93.618078 -343.255394) (xy 93.594521 -343.322714)
			(xy 93.563576 -343.386973) (xy 93.52563 -343.447364) (xy 93.481161 -343.503126) (xy 93.430728 -343.553559)
			(xy 93.374966 -343.598028) (xy 93.314575 -343.635974) (xy 93.250316 -343.666919) (xy 93.182996 -343.690476)
			(xy 93.113461 -343.706346) (xy 93.042587 -343.714332) (xy 92.971265 -343.714332) (xy 92.900391 -343.706346)
			(xy 92.830856 -343.690476) (xy 92.763536 -343.666919) (xy 92.699277 -343.635974) (xy 92.638886 -343.598028)
			(xy 92.583124 -343.553559) (xy 92.532691 -343.503126) (xy 92.488222 -343.447364) (xy 92.450276 -343.386973)
			(xy 92.419331 -343.322714) (xy 92.395774 -343.255394) (xy 92.379904 -343.185859) (xy 92.371918 -343.114985)
			(xy 90.650322 -343.114985) (xy 90.642336 -343.185859) (xy 90.626466 -343.255394) (xy 90.602909 -343.322714)
			(xy 90.571964 -343.386973) (xy 90.534018 -343.447364) (xy 90.489549 -343.503126) (xy 90.439116 -343.553559)
			(xy 90.383354 -343.598028) (xy 90.322963 -343.635974) (xy 90.258704 -343.666919) (xy 90.191384 -343.690476)
			(xy 90.121849 -343.706346) (xy 90.050975 -343.714332) (xy 89.979653 -343.714332) (xy 89.908779 -343.706346)
			(xy 89.839244 -343.690476) (xy 89.771924 -343.666919) (xy 89.707665 -343.635974) (xy 89.647274 -343.598028)
			(xy 89.591512 -343.553559) (xy 89.541079 -343.503126) (xy 89.49661 -343.447364) (xy 89.458664 -343.386973)
			(xy 89.427719 -343.322714) (xy 89.404162 -343.255394) (xy 89.388292 -343.185859) (xy 89.380306 -343.114985)
			(xy 82.780077 -343.114985) (xy 82.748059 -343.197653) (xy 82.667204 -343.384133) (xy 82.579027 -343.567265)
			(xy 82.483669 -343.746761) (xy 82.381277 -343.922341) (xy 82.272014 -344.093729) (xy 82.156049 -344.260655)
			(xy 82.033566 -344.422859) (xy 81.904756 -344.580086) (xy 81.769821 -344.732088) (xy 81.628972 -344.878629)
			(xy 81.482432 -345.019477) (xy 81.33043 -345.154412) (xy 81.173203 -345.283223) (xy 81.010999 -345.405706)
			(xy 80.89458 -345.486583) (xy 89.380306 -345.486583) (xy 89.380306 -345.415261) (xy 89.388292 -345.344387)
			(xy 89.404162 -345.274852) (xy 89.427719 -345.207532) (xy 89.458664 -345.143273) (xy 89.49661 -345.082882)
			(xy 89.541079 -345.02712) (xy 89.591512 -344.976687) (xy 89.647274 -344.932218) (xy 89.707665 -344.894272)
			(xy 89.771924 -344.863327) (xy 89.839244 -344.83977) (xy 89.908779 -344.8239) (xy 89.979653 -344.815914)
			(xy 90.050975 -344.815914) (xy 90.121849 -344.8239) (xy 90.191384 -344.83977) (xy 90.258704 -344.863327)
			(xy 90.322963 -344.894272) (xy 90.383354 -344.932218) (xy 90.439116 -344.976687) (xy 90.489549 -345.02712)
			(xy 90.534018 -345.082882) (xy 90.571964 -345.143273) (xy 90.602909 -345.207532) (xy 90.626466 -345.274852)
			(xy 90.642336 -345.344387) (xy 90.650322 -345.415261) (xy 90.650822 -345.450922) (xy 90.650322 -345.486583)
			(xy 92.371918 -345.486583) (xy 92.371918 -345.415261) (xy 92.379904 -345.344387) (xy 92.395774 -345.274852)
			(xy 92.419331 -345.207532) (xy 92.450276 -345.143273) (xy 92.488222 -345.082882) (xy 92.532691 -345.02712)
			(xy 92.583124 -344.976687) (xy 92.638886 -344.932218) (xy 92.699277 -344.894272) (xy 92.763536 -344.863327)
			(xy 92.830856 -344.83977) (xy 92.900391 -344.8239) (xy 92.971265 -344.815914) (xy 93.042587 -344.815914)
			(xy 93.113461 -344.8239) (xy 93.182996 -344.83977) (xy 93.250316 -344.863327) (xy 93.314575 -344.894272)
			(xy 93.374966 -344.932218) (xy 93.430728 -344.976687) (xy 93.481161 -345.02712) (xy 93.52563 -345.082882)
			(xy 93.563576 -345.143273) (xy 93.594521 -345.207532) (xy 93.618078 -345.274852) (xy 93.633948 -345.344387)
			(xy 93.641934 -345.415261) (xy 93.642434 -345.450922) (xy 93.641934 -345.486583) (xy 93.633948 -345.557457)
			(xy 93.618078 -345.626992) (xy 93.594521 -345.694312) (xy 93.563576 -345.758571) (xy 93.52563 -345.818962)
			(xy 93.481161 -345.874724) (xy 93.430728 -345.925157) (xy 93.374966 -345.969626) (xy 93.314575 -346.007572)
			(xy 93.250316 -346.038517) (xy 93.182996 -346.062074) (xy 93.113461 -346.077944) (xy 93.042587 -346.08593)
			(xy 92.971265 -346.08593) (xy 92.900391 -346.077944) (xy 92.830856 -346.062074) (xy 92.763536 -346.038517)
			(xy 92.699277 -346.007572) (xy 92.638886 -345.969626) (xy 92.583124 -345.925157) (xy 92.532691 -345.874724)
			(xy 92.488222 -345.818962) (xy 92.450276 -345.758571) (xy 92.419331 -345.694312) (xy 92.395774 -345.626992)
			(xy 92.379904 -345.557457) (xy 92.371918 -345.486583) (xy 90.650322 -345.486583) (xy 90.642336 -345.557457)
			(xy 90.626466 -345.626992) (xy 90.602909 -345.694312) (xy 90.571964 -345.758571) (xy 90.534018 -345.818962)
			(xy 90.489549 -345.874724) (xy 90.439116 -345.925157) (xy 90.383354 -345.969626) (xy 90.322963 -346.007572)
			(xy 90.258704 -346.038517) (xy 90.191384 -346.062074) (xy 90.121849 -346.077944) (xy 90.050975 -346.08593)
			(xy 89.979653 -346.08593) (xy 89.908779 -346.077944) (xy 89.839244 -346.062074) (xy 89.771924 -346.038517)
			(xy 89.707665 -346.007572) (xy 89.647274 -345.969626) (xy 89.591512 -345.925157) (xy 89.541079 -345.874724)
			(xy 89.49661 -345.818962) (xy 89.458664 -345.758571) (xy 89.427719 -345.694312) (xy 89.404162 -345.626992)
			(xy 89.388292 -345.557457) (xy 89.380306 -345.486583) (xy 80.89458 -345.486583) (xy 80.844073 -345.521671)
			(xy 80.672685 -345.630935) (xy 80.497106 -345.733326) (xy 80.317609 -345.828685) (xy 80.134478 -345.916862)
			(xy 79.947998 -345.997717) (xy 79.758463 -346.071125) (xy 79.56617 -346.136971) (xy 79.37142 -346.19515)
			(xy 79.17452 -346.245573) (xy 78.975777 -346.288158) (xy 78.775504 -346.322841) (xy 78.574014 -346.349567)
			(xy 78.371624 -346.368292) (xy 78.168652 -346.378989) (xy 77.965415 -346.381641) (xy 77.762232 -346.376243)
			(xy 77.559423 -346.362803) (xy 77.357305 -346.341343) (xy 77.156195 -346.311897) (xy 76.956409 -346.27451)
			(xy 76.75826 -346.229242) (xy 76.562059 -346.176162) (xy 76.368113 -346.115356) (xy 76.176728 -346.046917)
			(xy 75.988202 -345.970954) (xy 75.802833 -345.887585) (xy 75.62091 -345.796941) (xy 75.442718 -345.699165)
			(xy 75.268539 -345.594409) (xy 75.098644 -345.482839) (xy 74.9333 -345.364628) (xy 74.772767 -345.239964)
			(xy 74.617296 -345.10904) (xy 74.467131 -344.972062) (xy 74.322508 -344.829246) (xy 74.183654 -344.680815)
			(xy 74.050785 -344.527003) (xy 73.924112 -344.368049) (xy 73.803832 -344.204205) (xy 73.690135 -344.035726)
			(xy 73.583198 -343.862877) (xy 73.483189 -343.685929) (xy 73.390265 -343.50516) (xy 73.304573 -343.320853)
			(xy 73.226245 -343.133298) (xy 73.155406 -342.942788) (xy 73.092166 -342.749622) (xy 73.036624 -342.554104)
			(xy 72.988868 -342.356539) (xy 72.948973 -342.157239) (xy 72.917 -341.956515) (xy 72.893001 -341.754683)
			(xy 72.877013 -341.552058) (xy 72.869061 -341.34896) (xy 72.869157 -341.145706) (xy 72.877301 -340.942615)
			(xy 72.893481 -340.740006) (xy 72.917671 -340.538196) (xy 72.949834 -340.337502) (xy 72.989918 -340.13824)
			(xy 73.03786 -339.940721) (xy 73.093587 -339.745255) (xy 73.124822 -339.648546) (xy 73.131417 -339.626871)
			(xy 73.137697 -339.582007) (xy 73.135923 -339.53674) (xy 73.126152 -339.492505) (xy 73.108693 -339.450703)
			(xy 73.084101 -339.412658) (xy 73.053153 -339.379576) (xy 73.01683 -339.352504) (xy 72.976283 -339.332301)
			(xy 72.932797 -339.319606) (xy 72.887749 -339.314821) (xy 72.842566 -339.318099) (xy 72.79868 -339.329336)
			(xy 72.757481 -339.348174) (xy 72.720275 -339.374018) (xy 72.703944 -339.38972) (xy 64.644169 -347.449495)
			(xy 89.380306 -347.449495) (xy 89.380306 -347.378173) (xy 89.388292 -347.307299) (xy 89.404162 -347.237764)
			(xy 89.427719 -347.170444) (xy 89.458664 -347.106185) (xy 89.49661 -347.045794) (xy 89.541079 -346.990032)
			(xy 89.591512 -346.939599) (xy 89.647274 -346.89513) (xy 89.707665 -346.857184) (xy 89.771924 -346.826239)
			(xy 89.839244 -346.802682) (xy 89.908779 -346.786812) (xy 89.979653 -346.778826) (xy 90.050975 -346.778826)
			(xy 90.121849 -346.786812) (xy 90.191384 -346.802682) (xy 90.258704 -346.826239) (xy 90.322963 -346.857184)
			(xy 90.383354 -346.89513) (xy 90.439116 -346.939599) (xy 90.489549 -346.990032) (xy 90.534018 -347.045794)
			(xy 90.571964 -347.106185) (xy 90.602909 -347.170444) (xy 90.626466 -347.237764) (xy 90.642336 -347.307299)
			(xy 90.650322 -347.378173) (xy 90.650822 -347.413834) (xy 90.650322 -347.449495) (xy 92.371918 -347.449495)
			(xy 92.371918 -347.378173) (xy 92.379904 -347.307299) (xy 92.395774 -347.237764) (xy 92.419331 -347.170444)
			(xy 92.450276 -347.106185) (xy 92.488222 -347.045794) (xy 92.532691 -346.990032) (xy 92.583124 -346.939599)
			(xy 92.638886 -346.89513) (xy 92.699277 -346.857184) (xy 92.763536 -346.826239) (xy 92.830856 -346.802682)
			(xy 92.900391 -346.786812) (xy 92.971265 -346.778826) (xy 93.042587 -346.778826) (xy 93.113461 -346.786812)
			(xy 93.182996 -346.802682) (xy 93.250316 -346.826239) (xy 93.314575 -346.857184) (xy 93.374966 -346.89513)
			(xy 93.430728 -346.939599) (xy 93.481161 -346.990032) (xy 93.52563 -347.045794) (xy 93.563576 -347.106185)
			(xy 93.594521 -347.170444) (xy 93.618078 -347.237764) (xy 93.633948 -347.307299) (xy 93.641934 -347.378173)
			(xy 93.642434 -347.413834) (xy 93.641934 -347.449495) (xy 93.633948 -347.520369) (xy 93.618078 -347.589904)
			(xy 93.594521 -347.657224) (xy 93.563576 -347.721483) (xy 93.52563 -347.781874) (xy 93.481161 -347.837636)
			(xy 93.430728 -347.888069) (xy 93.374966 -347.932538) (xy 93.314575 -347.970484) (xy 93.250316 -348.001429)
			(xy 93.182996 -348.024986) (xy 93.113461 -348.040856) (xy 93.042587 -348.048842) (xy 92.971265 -348.048842)
			(xy 92.900391 -348.040856) (xy 92.830856 -348.024986) (xy 92.763536 -348.001429) (xy 92.699277 -347.970484)
			(xy 92.638886 -347.932538) (xy 92.583124 -347.888069) (xy 92.532691 -347.837636) (xy 92.488222 -347.781874)
			(xy 92.450276 -347.721483) (xy 92.419331 -347.657224) (xy 92.395774 -347.589904) (xy 92.379904 -347.520369)
			(xy 92.371918 -347.449495) (xy 90.650322 -347.449495) (xy 90.642336 -347.520369) (xy 90.626466 -347.589904)
			(xy 90.602909 -347.657224) (xy 90.571964 -347.721483) (xy 90.534018 -347.781874) (xy 90.489549 -347.837636)
			(xy 90.439116 -347.888069) (xy 90.383354 -347.932538) (xy 90.322963 -347.970484) (xy 90.258704 -348.001429)
			(xy 90.191384 -348.024986) (xy 90.121849 -348.040856) (xy 90.050975 -348.048842) (xy 89.979653 -348.048842)
			(xy 89.908779 -348.040856) (xy 89.839244 -348.024986) (xy 89.771924 -348.001429) (xy 89.707665 -347.970484)
			(xy 89.647274 -347.932538) (xy 89.591512 -347.888069) (xy 89.541079 -347.837636) (xy 89.49661 -347.781874)
			(xy 89.458664 -347.721483) (xy 89.427719 -347.657224) (xy 89.404162 -347.589904) (xy 89.388292 -347.520369)
			(xy 89.380306 -347.449495) (xy 64.644169 -347.449495) (xy 62.500663 -349.593001) (xy 89.380306 -349.593001)
			(xy 89.380306 -349.521679) (xy 89.388292 -349.450805) (xy 89.404162 -349.38127) (xy 89.427719 -349.31395)
			(xy 89.458664 -349.249691) (xy 89.49661 -349.1893) (xy 89.541079 -349.133538) (xy 89.591512 -349.083105)
			(xy 89.647274 -349.038636) (xy 89.707665 -349.00069) (xy 89.771924 -348.969745) (xy 89.839244 -348.946188)
			(xy 89.908779 -348.930318) (xy 89.979653 -348.922332) (xy 90.050975 -348.922332) (xy 90.121849 -348.930318)
			(xy 90.191384 -348.946188) (xy 90.258704 -348.969745) (xy 90.322963 -349.00069) (xy 90.383354 -349.038636)
			(xy 90.439116 -349.083105) (xy 90.489549 -349.133538) (xy 90.534018 -349.1893) (xy 90.571964 -349.249691)
			(xy 90.602909 -349.31395) (xy 90.626466 -349.38127) (xy 90.642336 -349.450805) (xy 90.650322 -349.521679)
			(xy 90.650822 -349.55734) (xy 90.650322 -349.593001) (xy 92.371918 -349.593001) (xy 92.371918 -349.521679)
			(xy 92.379904 -349.450805) (xy 92.395774 -349.38127) (xy 92.419331 -349.31395) (xy 92.450276 -349.249691)
			(xy 92.488222 -349.1893) (xy 92.532691 -349.133538) (xy 92.583124 -349.083105) (xy 92.638886 -349.038636)
			(xy 92.699277 -349.00069) (xy 92.763536 -348.969745) (xy 92.830856 -348.946188) (xy 92.900391 -348.930318)
			(xy 92.971265 -348.922332) (xy 93.042587 -348.922332) (xy 93.113461 -348.930318) (xy 93.182996 -348.946188)
			(xy 93.250316 -348.969745) (xy 93.314575 -349.00069) (xy 93.374966 -349.038636) (xy 93.430728 -349.083105)
			(xy 93.481161 -349.133538) (xy 93.52563 -349.1893) (xy 93.563576 -349.249691) (xy 93.594521 -349.31395)
			(xy 93.618078 -349.38127) (xy 93.633948 -349.450805) (xy 93.641934 -349.521679) (xy 93.642434 -349.55734)
			(xy 93.641934 -349.593001) (xy 93.633948 -349.663875) (xy 93.618078 -349.73341) (xy 93.594521 -349.80073)
			(xy 93.563576 -349.864989) (xy 93.52563 -349.92538) (xy 93.481161 -349.981142) (xy 93.430728 -350.031575)
			(xy 93.374966 -350.076044) (xy 93.314575 -350.11399) (xy 93.250316 -350.144935) (xy 93.182996 -350.168492)
			(xy 93.113461 -350.184362) (xy 93.042587 -350.192348) (xy 92.971265 -350.192348) (xy 92.900391 -350.184362)
			(xy 92.830856 -350.168492) (xy 92.763536 -350.144935) (xy 92.699277 -350.11399) (xy 92.638886 -350.076044)
			(xy 92.583124 -350.031575) (xy 92.532691 -349.981142) (xy 92.488222 -349.92538) (xy 92.450276 -349.864989)
			(xy 92.419331 -349.80073) (xy 92.395774 -349.73341) (xy 92.379904 -349.663875) (xy 92.371918 -349.593001)
			(xy 90.650322 -349.593001) (xy 90.642336 -349.663875) (xy 90.626466 -349.73341) (xy 90.602909 -349.80073)
			(xy 90.571964 -349.864989) (xy 90.534018 -349.92538) (xy 90.489549 -349.981142) (xy 90.439116 -350.031575)
			(xy 90.383354 -350.076044) (xy 90.322963 -350.11399) (xy 90.258704 -350.144935) (xy 90.191384 -350.168492)
			(xy 90.121849 -350.184362) (xy 90.050975 -350.192348) (xy 89.979653 -350.192348) (xy 89.908779 -350.184362)
			(xy 89.839244 -350.168492) (xy 89.771924 -350.144935) (xy 89.707665 -350.11399) (xy 89.647274 -350.076044)
			(xy 89.591512 -350.031575) (xy 89.541079 -349.981142) (xy 89.49661 -349.92538) (xy 89.458664 -349.864989)
			(xy 89.427719 -349.80073) (xy 89.404162 -349.73341) (xy 89.388292 -349.663875) (xy 89.380306 -349.593001)
			(xy 62.500663 -349.593001) (xy 59.843416 -352.250248) (xy 29.74975 -352.250248) (xy 29.733131 -352.250782)
			(xy 29.701019 -352.25936) (xy 29.672216 -352.275946) (xy 29.648678 -352.299414) (xy 29.632006 -352.328167)
			(xy 29.623332 -352.360253) (xy 29.623245 -352.393491) (xy 29.631753 -352.425621) (xy 29.648276 -352.454461)
			(xy 29.65958 -352.466656) (xy 29.664406 -352.471482) (xy 29.700728 -352.508058) (xy 29.712896 -352.519543)
			(xy 29.741858 -352.536275) (xy 29.774173 -352.544912) (xy 29.790898 -352.545396) (xy 43.716448 -352.545396)
			(xy 44.136056 -352.965004) (xy 68.345048 -352.965004) (xy 68.349119 -352.909382) (xy 68.361245 -352.854945)
			(xy 68.381168 -352.802854) (xy 68.408464 -352.754219) (xy 68.44255 -352.710076) (xy 68.482699 -352.671367)
			(xy 68.528057 -352.638916) (xy 68.577657 -352.613415) (xy 68.630441 -352.595408) (xy 68.685284 -352.585278)
			(xy 68.741018 -352.583241) (xy 68.796455 -352.589341) (xy 68.850412 -352.603447) (xy 68.901741 -352.625259)
			(xy 68.949347 -352.654313) (xy 68.992215 -352.689988) (xy 69.029432 -352.731525) (xy 69.060205 -352.778038)
			(xy 69.083877 -352.828535) (xy 69.099945 -352.881942) (xy 69.108065 -352.937118) (xy 69.108574 -352.965004)
			(xy 69.108161 -352.98761) (xy 69.48119 -352.98761) (xy 69.485261 -352.931988) (xy 69.497387 -352.877551)
			(xy 69.51731 -352.82546) (xy 69.544606 -352.776825) (xy 69.578692 -352.732682) (xy 69.618841 -352.693973)
			(xy 69.664199 -352.661522) (xy 69.713799 -352.636021) (xy 69.766583 -352.618014) (xy 69.821426 -352.607884)
			(xy 69.87716 -352.605847) (xy 69.932597 -352.611947) (xy 69.986554 -352.626053) (xy 70.037883 -352.647865)
			(xy 70.085489 -352.676919) (xy 70.128357 -352.712594) (xy 70.165574 -352.754131) (xy 70.196347 -352.800644)
			(xy 70.220019 -352.851141) (xy 70.236087 -352.904548) (xy 70.241881 -352.943922) (xy 70.615554 -352.943922)
			(xy 70.619625 -352.8883) (xy 70.631751 -352.833863) (xy 70.651674 -352.781772) (xy 70.67897 -352.733137)
			(xy 70.713056 -352.688994) (xy 70.753205 -352.650285) (xy 70.798563 -352.617834) (xy 70.848163 -352.592333)
			(xy 70.900947 -352.574326) (xy 70.95579 -352.564196) (xy 71.011524 -352.562159) (xy 71.066961 -352.568259)
			(xy 71.120918 -352.582365) (xy 71.172247 -352.604177) (xy 71.219853 -352.633231) (xy 71.262721 -352.668906)
			(xy 71.299938 -352.710443) (xy 71.330711 -352.756956) (xy 71.354383 -352.807453) (xy 71.370451 -352.86086)
			(xy 71.378571 -352.916036) (xy 71.37908 -352.943922) (xy 71.379075 -352.944176) (xy 71.814942 -352.944176)
			(xy 71.819013 -352.888554) (xy 71.831139 -352.834117) (xy 71.851062 -352.782026) (xy 71.878358 -352.733391)
			(xy 71.912444 -352.689248) (xy 71.952593 -352.650539) (xy 71.997951 -352.618088) (xy 72.047551 -352.592587)
			(xy 72.100335 -352.57458) (xy 72.155178 -352.56445) (xy 72.210912 -352.562413) (xy 72.266349 -352.568513)
			(xy 72.320306 -352.582619) (xy 72.371635 -352.604431) (xy 72.419241 -352.633485) (xy 72.462109 -352.66916)
			(xy 72.499326 -352.710697) (xy 72.530099 -352.75721) (xy 72.553771 -352.807707) (xy 72.569839 -352.861114)
			(xy 72.577959 -352.91629) (xy 72.578468 -352.944176) (xy 72.577959 -352.972062) (xy 72.569839 -353.027238)
			(xy 72.553771 -353.080645) (xy 72.530099 -353.131142) (xy 72.499326 -353.177655) (xy 72.462109 -353.219192)
			(xy 72.419241 -353.254867) (xy 72.371635 -353.283921) (xy 72.320306 -353.305733) (xy 72.266349 -353.319839)
			(xy 72.210912 -353.325939) (xy 72.155178 -353.323902) (xy 72.100335 -353.313772) (xy 72.047551 -353.295765)
			(xy 71.997951 -353.270264) (xy 71.952593 -353.237813) (xy 71.912444 -353.199104) (xy 71.878358 -353.154961)
			(xy 71.851062 -353.106326) (xy 71.831139 -353.054235) (xy 71.819013 -352.999798) (xy 71.814942 -352.944176)
			(xy 71.379075 -352.944176) (xy 71.378571 -352.971808) (xy 71.370451 -353.026984) (xy 71.354383 -353.080391)
			(xy 71.330711 -353.130888) (xy 71.299938 -353.177401) (xy 71.262721 -353.218938) (xy 71.219853 -353.254613)
			(xy 71.172247 -353.283667) (xy 71.120918 -353.305479) (xy 71.066961 -353.319585) (xy 71.011524 -353.325685)
			(xy 70.95579 -353.323648) (xy 70.900947 -353.313518) (xy 70.848163 -353.295511) (xy 70.798563 -353.27001)
			(xy 70.753205 -353.237559) (xy 70.713056 -353.19885) (xy 70.67897 -353.154707) (xy 70.651674 -353.106072)
			(xy 70.631751 -353.053981) (xy 70.619625 -352.999544) (xy 70.615554 -352.943922) (xy 70.241881 -352.943922)
			(xy 70.244207 -352.959724) (xy 70.244716 -352.98761) (xy 70.244207 -353.015496) (xy 70.236087 -353.070672)
			(xy 70.220019 -353.124079) (xy 70.196347 -353.174576) (xy 70.165574 -353.221089) (xy 70.128357 -353.262626)
			(xy 70.085489 -353.298301) (xy 70.037883 -353.327355) (xy 69.986554 -353.349167) (xy 69.932597 -353.363273)
			(xy 69.87716 -353.369373) (xy 69.821426 -353.367336) (xy 69.766583 -353.357206) (xy 69.713799 -353.339199)
			(xy 69.664199 -353.313698) (xy 69.618841 -353.281247) (xy 69.578692 -353.242538) (xy 69.544606 -353.198395)
			(xy 69.51731 -353.14976) (xy 69.497387 -353.097669) (xy 69.485261 -353.043232) (xy 69.48119 -352.98761)
			(xy 69.108161 -352.98761) (xy 69.108065 -352.99289) (xy 69.099945 -353.048066) (xy 69.083877 -353.101473)
			(xy 69.060205 -353.15197) (xy 69.029432 -353.198483) (xy 68.992215 -353.24002) (xy 68.949347 -353.275695)
			(xy 68.901741 -353.304749) (xy 68.850412 -353.326561) (xy 68.796455 -353.340667) (xy 68.741018 -353.346767)
			(xy 68.685284 -353.34473) (xy 68.630441 -353.3346) (xy 68.577657 -353.316593) (xy 68.528057 -353.291092)
			(xy 68.482699 -353.258641) (xy 68.44255 -353.219932) (xy 68.408464 -353.175789) (xy 68.381168 -353.127154)
			(xy 68.361245 -353.075063) (xy 68.349119 -353.020626) (xy 68.345048 -352.965004) (xy 44.136056 -352.965004)
			(xy 46.031404 -354.860352) (xy 81.68132 -354.860352) (xy 81.974436 -355.153214) (xy 82.011266 -355.190044)
			(xy 82.02702 -355.205188) (xy 82.062721 -355.230381) (xy 82.102207 -355.249092) (xy 82.144313 -355.260771)
			(xy 82.187795 -355.265071) (xy 82.231373 -355.261868) (xy 82.273759 -355.251254) (xy 82.313704 -355.233543)
			(xy 82.350029 -355.209257) (xy 82.381662 -355.179114) (xy 82.39506 -355.16185) (xy 82.410592 -355.139624)
			(xy 82.44693 -355.099379) (xy 82.488602 -355.064687) (xy 82.534766 -355.036246) (xy 82.584494 -355.014629)
			(xy 82.636781 -355.000273) (xy 82.690574 -354.993466) (xy 82.74479 -354.994346) (xy 82.798334 -355.002895)
			(xy 82.850128 -355.01894) (xy 82.899127 -355.04216) (xy 82.944345 -355.072084) (xy 82.984869 -355.10811)
			(xy 83.019882 -355.149513) (xy 83.034632 -355.172264) (xy 83.047488 -355.190747) (xy 83.078608 -355.223276)
			(xy 83.114969 -355.249819) (xy 83.155434 -355.269547) (xy 83.19874 -355.281844) (xy 83.243534 -355.286326)
			(xy 83.288418 -355.282853) (xy 83.331989 -355.271534) (xy 83.372888 -355.252721) (xy 83.409836 -355.227003)
			(xy 83.426046 -355.21138) (xy 83.465416 -355.172264) (xy 83.777328 -354.860352) (xy 86.694518 -354.860352)
			(xy 87.394796 -355.560376) (xy 87.48268 -355.64826) (xy 87.514176 -355.657404) (xy 87.540576 -355.665481)
			(xy 87.590897 -355.688187) (xy 87.637421 -355.717908) (xy 87.679177 -355.754023) (xy 87.715292 -355.795779)
			(xy 87.745013 -355.842303) (xy 87.767719 -355.892624) (xy 87.775796 -355.919024) (xy 87.78494 -355.95052)
			(xy 88.279986 -356.445566) (xy 88.296086 -356.461003) (xy 88.332646 -356.486547) (xy 88.373104 -356.505317)
			(xy 88.416217 -356.516739) (xy 88.460661 -356.520461) (xy 88.505073 -356.516368) (xy 88.548089 -356.504588)
			(xy 88.588389 -356.485481) (xy 88.624735 -356.459633) (xy 88.656013 -356.427839) (xy 88.681261 -356.391074)
			(xy 88.699706 -356.350467) (xy 88.70569 -356.32898) (xy 88.71305 -356.302258) (xy 88.734433 -356.251123)
			(xy 88.762989 -356.20362) (xy 88.798118 -356.160749) (xy 88.83908 -356.123411) (xy 88.885013 -356.092393)
			(xy 88.934951 -356.068348) (xy 88.987842 -356.05178) (xy 89.042574 -356.04304) (xy 89.097995 -356.04231)
			(xy 89.152938 -356.049607) (xy 89.206247 -356.064776) (xy 89.256801 -356.087499) (xy 89.303534 -356.117298)
			(xy 89.345465 -356.153544) (xy 89.38171 -356.195476) (xy 89.411507 -356.242211) (xy 89.434228 -356.292765)
			(xy 89.449396 -356.346075) (xy 89.456691 -356.401018) (xy 89.455959 -356.456439) (xy 89.447217 -356.51117)
			(xy 89.430648 -356.564061) (xy 89.4066 -356.613998) (xy 89.375581 -356.65993) (xy 89.338242 -356.700891)
			(xy 89.295369 -356.736018) (xy 89.247865 -356.764573) (xy 89.19673 -356.785954) (xy 89.170002 -356.793292)
			(xy 89.14851 -356.799268) (xy 89.107888 -356.817695) (xy 89.071108 -356.842933) (xy 89.039301 -356.874206)
			(xy 89.013444 -356.910553) (xy 88.994332 -356.950857) (xy 88.982553 -356.993879) (xy 88.978468 -357.038298)
			(xy 88.982203 -357.082747) (xy 88.993643 -357.125861) (xy 89.012436 -357.166315) (xy 89.038006 -357.202864)
			(xy 89.053416 -357.218996) (xy 91.71178 -359.87736) (xy 91.723481 -359.888434) (xy 91.751207 -359.90482)
			(xy 91.782157 -359.913724) (xy 91.814352 -359.914577) (xy 91.830144 -359.911396) (xy 91.866724 -359.903451)
			(xy 91.941031 -359.894375) (xy 92.015881 -359.89315) (xy 92.090445 -359.899788) (xy 92.163902 -359.914215)
			(xy 92.235438 -359.936273) (xy 92.304263 -359.965717) (xy 92.369618 -360.002224) (xy 92.43078 -360.045388)
			(xy 92.487074 -360.094733) (xy 92.537877 -360.149715) (xy 92.582628 -360.209725) (xy 92.620834 -360.274102)
			(xy 92.652071 -360.342132) (xy 92.675995 -360.413066) (xy 92.692342 -360.486119) (xy 92.700931 -360.560484)
			(xy 92.701666 -360.63534) (xy 92.69454 -360.70986) (xy 92.679632 -360.78322) (xy 92.657107 -360.85461)
			(xy 92.627212 -360.923241) (xy 92.590279 -360.988356) (xy 92.546715 -361.049234) (xy 92.497002 -361.105203)
			(xy 92.441689 -361.155645) (xy 92.381387 -361.200003) (xy 92.316762 -361.237786) (xy 92.248528 -361.268577)
			(xy 92.177439 -361.292037) (xy 92.104281 -361.307905) (xy 92.067126 -361.31246) (xy 92.067126 -362.43768)
			(xy 92.105123 -362.442338) (xy 92.179896 -362.458768) (xy 92.252474 -362.483129) (xy 92.322017 -362.51514)
			(xy 92.387722 -362.554432) (xy 92.448829 -362.60055) (xy 92.504633 -362.652961) (xy 92.554488 -362.711059)
			(xy 92.597818 -362.774173) (xy 92.634123 -362.841574) (xy 92.662983 -362.912483) (xy 92.684064 -362.98608)
			(xy 92.697123 -363.061515) (xy 92.702009 -363.137916) (xy 92.698665 -363.2144) (xy 92.687131 -363.290083)
			(xy 92.667539 -363.36409) (xy 92.640115 -363.435567) (xy 92.605178 -363.503687) (xy 92.563129 -363.567662)
			(xy 92.514457 -363.626755) (xy 92.459722 -363.680281) (xy 92.399557 -363.727622) (xy 92.367354 -363.74832)
			(xy 92.35396 -363.757253) (xy 92.331812 -363.780607) (xy 92.316216 -363.808761) (xy 92.308163 -363.839923)
			(xy 92.307664 -363.856016) (xy 92.307664 -363.86008) (xy 93.154506 -363.86008) (xy 93.158522 -363.74381)
			(xy 93.170549 -363.628095) (xy 93.190531 -363.513485) (xy 93.218373 -363.400526) (xy 93.253942 -363.289758)
			(xy 93.297068 -363.181707) (xy 93.347545 -363.076889) (xy 93.405134 -362.975804) (xy 93.46956 -362.878932)
			(xy 93.540515 -362.786736) (xy 93.617662 -362.699655) (xy 93.700633 -362.618104) (xy 93.789033 -362.542472)
			(xy 93.88244 -362.473118) (xy 93.980409 -362.410375) (xy 94.082473 -362.354539) (xy 94.188147 -362.305878)
			(xy 94.296926 -362.264624) (xy 94.408291 -362.230973) (xy 94.521714 -362.205085) (xy 94.636651 -362.187084)
			(xy 94.752557 -362.177055) (xy 94.868879 -362.175047) (xy 94.985062 -362.181069) (xy 95.100553 -362.195092)
			(xy 95.214801 -362.21705) (xy 95.327262 -362.246837) (xy 95.4374 -362.284312) (xy 95.54469 -362.329297)
			(xy 95.648621 -362.381576) (xy 95.748697 -362.440901) (xy 95.844443 -362.506989) (xy 95.9354 -362.579525)
			(xy 96.021136 -362.658164) (xy 96.101243 -362.74253) (xy 96.175339 -362.832222) (xy 96.243069 -362.926812)
			(xy 96.304113 -363.02585) (xy 96.358178 -363.128863) (xy 96.405008 -363.23536) (xy 96.444379 -363.344835)
			(xy 96.476103 -363.456765) (xy 96.500029 -363.570617) (xy 96.516043 -363.685849) (xy 96.52407 -363.801911)
			(xy 96.524572 -363.86008) (xy 96.52407 -363.918249) (xy 96.516043 -364.034311) (xy 96.500029 -364.149543)
			(xy 96.476103 -364.263395) (xy 96.444379 -364.375325) (xy 96.405008 -364.4848) (xy 96.358178 -364.591297)
			(xy 96.304113 -364.69431) (xy 96.243069 -364.793348) (xy 96.175339 -364.887938) (xy 96.101243 -364.97763)
			(xy 96.021136 -365.061996) (xy 95.9354 -365.140635) (xy 95.844443 -365.213171) (xy 95.748697 -365.279259)
			(xy 95.648621 -365.338584) (xy 95.54469 -365.390863) (xy 95.4374 -365.435848) (xy 95.327262 -365.473323)
			(xy 95.214801 -365.50311) (xy 95.100553 -365.525068) (xy 94.985062 -365.539091) (xy 94.868879 -365.545113)
			(xy 94.752557 -365.543105) (xy 94.636651 -365.533076) (xy 94.521714 -365.515075) (xy 94.408291 -365.489187)
			(xy 94.296926 -365.455536) (xy 94.188147 -365.414282) (xy 94.082473 -365.365621) (xy 93.980409 -365.309785)
			(xy 93.88244 -365.247042) (xy 93.789033 -365.177688) (xy 93.700633 -365.102056) (xy 93.617662 -365.020505)
			(xy 93.540515 -364.933424) (xy 93.46956 -364.841228) (xy 93.405134 -364.744356) (xy 93.347545 -364.643271)
			(xy 93.297068 -364.538453) (xy 93.253942 -364.430402) (xy 93.218373 -364.319634) (xy 93.190531 -364.206675)
			(xy 93.170549 -364.092065) (xy 93.158522 -363.97635) (xy 93.154506 -363.86008) (xy 92.307664 -363.86008)
			(xy 92.307664 -364.712758) (xy 91.005406 -366.01527) (xy 90.841576 -366.1791) (xy 84.953602 -366.1791)
			(xy 83.398868 -364.624366) (xy 83.398868 -360.547666) (xy 82.513678 -359.662476) (xy 44.042076 -359.662476)
			(xy 40.215312 -355.835712) (xy 40.183816 -355.826568) (xy 40.157417 -355.81849) (xy 40.107098 -355.795782)
			(xy 40.060577 -355.76606) (xy 40.018825 -355.729944) (xy 39.982713 -355.688187) (xy 39.952997 -355.641662)
			(xy 39.930295 -355.591341) (xy 39.922196 -355.564948) (xy 39.913052 -355.533452) (xy 39.606728 -355.227128)
			(xy 39.584884 -355.227128) (xy 39.27094 -354.913184) (xy 39.183564 -354.913184) (xy 39.161202 -354.914373)
			(xy 39.117391 -354.923623) (xy 39.075877 -354.940404) (xy 39.037944 -354.964196) (xy 39.004764 -354.994265)
			(xy 38.977364 -355.02968) (xy 38.956591 -355.069347) (xy 38.943086 -355.112039) (xy 38.937268 -355.156436)
			(xy 38.939316 -355.201167) (xy 38.949166 -355.244847) (xy 38.966515 -355.286126) (xy 38.990826 -355.323729)
			(xy 39.005764 -355.340412) (xy 39.744142 -356.079044) (xy 39.836344 -356.170992) (xy 39.836344 -361.184698)
			(xy 39.836854 -361.207932) (xy 39.845287 -361.253627) (xy 39.861892 -361.297026) (xy 39.886113 -361.336681)
			(xy 39.917143 -361.371268) (xy 39.953946 -361.399635) (xy 39.995295 -361.420835) (xy 40.03981 -361.43416)
			(xy 40.086007 -361.439165) (xy 40.132343 -361.435685) (xy 40.177274 -361.423835) (xy 40.219299 -361.404009)
			(xy 40.257017 -361.376871) (xy 40.273478 -361.360466) (xy 40.313707 -361.318279) (xy 40.399141 -361.238953)
			(xy 40.489867 -361.165738) (xy 40.585448 -361.098987) (xy 40.685425 -361.039019) (xy 40.789317 -360.986123)
			(xy 40.896626 -360.940554) (xy 41.006833 -360.902531) (xy 41.119411 -360.872236) (xy 41.233818 -360.849815)
			(xy 41.349503 -360.835377) (xy 41.465911 -360.828989) (xy 41.582481 -360.830684) (xy 41.698654 -360.840453)
			(xy 41.813871 -360.858248) (xy 41.927577 -360.883985) (xy 42.039227 -360.91754) (xy 42.148283 -360.958751)
			(xy 42.254221 -361.00742) (xy 42.356532 -361.063313) (xy 42.454723 -361.126162) (xy 42.500375 -361.16006)
			(xy 43.327577 -361.16006) (xy 43.331612 -361.084356) (xy 43.343671 -361.009511) (xy 43.363617 -360.93637)
			(xy 43.391224 -360.865765) (xy 43.42618 -360.798494) (xy 43.468088 -360.735319) (xy 43.516474 -360.676957)
			(xy 43.57079 -360.624069) (xy 43.630419 -360.577254) (xy 43.694687 -360.537042) (xy 43.762864 -360.50389)
			(xy 43.83418 -360.478172) (xy 43.907825 -360.46018) (xy 43.982965 -360.450118) (xy 44.058749 -360.448099)
			(xy 44.134319 -360.454148) (xy 44.208817 -360.468195) (xy 44.2814 -360.490081) (xy 44.351246 -360.519558)
			(xy 44.417563 -360.556293) (xy 44.479599 -360.599868) (xy 44.536652 -360.64979) (xy 44.588076 -360.705494)
			(xy 44.633287 -360.766349) (xy 44.671774 -360.831664) (xy 44.7031 -360.9007) (xy 44.72691 -360.972675)
			(xy 44.742935 -361.046773) (xy 44.750994 -361.122154) (xy 44.751498 -361.16006) (xy 45.867577 -361.16006)
			(xy 45.871612 -361.084356) (xy 45.883671 -361.009511) (xy 45.903617 -360.93637) (xy 45.931224 -360.865765)
			(xy 45.96618 -360.798494) (xy 46.008088 -360.735319) (xy 46.056474 -360.676957) (xy 46.11079 -360.624069)
			(xy 46.170419 -360.577254) (xy 46.234687 -360.537042) (xy 46.302864 -360.50389) (xy 46.37418 -360.478172)
			(xy 46.447825 -360.46018) (xy 46.522965 -360.450118) (xy 46.598749 -360.448099) (xy 46.674319 -360.454148)
			(xy 46.748817 -360.468195) (xy 46.8214 -360.490081) (xy 46.891246 -360.519558) (xy 46.957563 -360.556293)
			(xy 47.019599 -360.599868) (xy 47.076652 -360.64979) (xy 47.128076 -360.705494) (xy 47.173287 -360.766349)
			(xy 47.211774 -360.831664) (xy 47.2431 -360.9007) (xy 47.26691 -360.972675) (xy 47.282935 -361.046773)
			(xy 47.290994 -361.122154) (xy 47.291498 -361.16006) (xy 48.407577 -361.16006) (xy 48.411612 -361.084356)
			(xy 48.423671 -361.009511) (xy 48.443617 -360.93637) (xy 48.471224 -360.865765) (xy 48.50618 -360.798494)
			(xy 48.548088 -360.735319) (xy 48.596474 -360.676957) (xy 48.65079 -360.624069) (xy 48.710419 -360.577254)
			(xy 48.774687 -360.537042) (xy 48.842864 -360.50389) (xy 48.91418 -360.478172) (xy 48.987825 -360.46018)
			(xy 49.062965 -360.450118) (xy 49.138749 -360.448099) (xy 49.214319 -360.454148) (xy 49.288817 -360.468195)
			(xy 49.3614 -360.490081) (xy 49.431246 -360.519558) (xy 49.497563 -360.556293) (xy 49.559599 -360.599868)
			(xy 49.616652 -360.64979) (xy 49.668076 -360.705494) (xy 49.713287 -360.766349) (xy 49.751774 -360.831664)
			(xy 49.7831 -360.9007) (xy 49.80691 -360.972675) (xy 49.822935 -361.046773) (xy 49.830994 -361.122154)
			(xy 49.831498 -361.16006) (xy 50.947577 -361.16006) (xy 50.951612 -361.084356) (xy 50.963671 -361.009511)
			(xy 50.983617 -360.93637) (xy 51.011224 -360.865765) (xy 51.04618 -360.798494) (xy 51.088088 -360.735319)
			(xy 51.136474 -360.676957) (xy 51.19079 -360.624069) (xy 51.250419 -360.577254) (xy 51.314687 -360.537042)
			(xy 51.382864 -360.50389) (xy 51.45418 -360.478172) (xy 51.527825 -360.46018) (xy 51.602965 -360.450118)
			(xy 51.678749 -360.448099) (xy 51.754319 -360.454148) (xy 51.828817 -360.468195) (xy 51.9014 -360.490081)
			(xy 51.971246 -360.519558) (xy 52.037563 -360.556293) (xy 52.099599 -360.599868) (xy 52.156652 -360.64979)
			(xy 52.208076 -360.705494) (xy 52.253287 -360.766349) (xy 52.291774 -360.831664) (xy 52.3231 -360.9007)
			(xy 52.34691 -360.972675) (xy 52.362935 -361.046773) (xy 52.370994 -361.122154) (xy 52.371498 -361.16006)
			(xy 53.487577 -361.16006) (xy 53.491612 -361.084356) (xy 53.503671 -361.009511) (xy 53.523617 -360.93637)
			(xy 53.551224 -360.865765) (xy 53.58618 -360.798494) (xy 53.628088 -360.735319) (xy 53.676474 -360.676957)
			(xy 53.73079 -360.624069) (xy 53.790419 -360.577254) (xy 53.854687 -360.537042) (xy 53.922864 -360.50389)
			(xy 53.99418 -360.478172) (xy 54.067825 -360.46018) (xy 54.142965 -360.450118) (xy 54.218749 -360.448099)
			(xy 54.294319 -360.454148) (xy 54.368817 -360.468195) (xy 54.4414 -360.490081) (xy 54.511246 -360.519558)
			(xy 54.577563 -360.556293) (xy 54.639599 -360.599868) (xy 54.696652 -360.64979) (xy 54.748076 -360.705494)
			(xy 54.793287 -360.766349) (xy 54.831774 -360.831664) (xy 54.8631 -360.9007) (xy 54.88691 -360.972675)
			(xy 54.902935 -361.046773) (xy 54.910994 -361.122154) (xy 54.911498 -361.16006) (xy 56.027577 -361.16006)
			(xy 56.031612 -361.084356) (xy 56.043671 -361.009511) (xy 56.063617 -360.93637) (xy 56.091224 -360.865765)
			(xy 56.12618 -360.798494) (xy 56.168088 -360.735319) (xy 56.216474 -360.676957) (xy 56.27079 -360.624069)
			(xy 56.330419 -360.577254) (xy 56.394687 -360.537042) (xy 56.462864 -360.50389) (xy 56.53418 -360.478172)
			(xy 56.607825 -360.46018) (xy 56.682965 -360.450118) (xy 56.758749 -360.448099) (xy 56.834319 -360.454148)
			(xy 56.908817 -360.468195) (xy 56.9814 -360.490081) (xy 57.051246 -360.519558) (xy 57.117563 -360.556293)
			(xy 57.179599 -360.599868) (xy 57.236652 -360.64979) (xy 57.288076 -360.705494) (xy 57.333287 -360.766349)
			(xy 57.371774 -360.831664) (xy 57.4031 -360.9007) (xy 57.42691 -360.972675) (xy 57.442935 -361.046773)
			(xy 57.450994 -361.122154) (xy 57.451498 -361.16006) (xy 58.567577 -361.16006) (xy 58.571612 -361.084356)
			(xy 58.583671 -361.009511) (xy 58.603617 -360.93637) (xy 58.631224 -360.865765) (xy 58.66618 -360.798494)
			(xy 58.708088 -360.735319) (xy 58.756474 -360.676957) (xy 58.81079 -360.624069) (xy 58.870419 -360.577254)
			(xy 58.934687 -360.537042) (xy 59.002864 -360.50389) (xy 59.07418 -360.478172) (xy 59.147825 -360.46018)
			(xy 59.222965 -360.450118) (xy 59.298749 -360.448099) (xy 59.374319 -360.454148) (xy 59.448817 -360.468195)
			(xy 59.5214 -360.490081) (xy 59.591246 -360.519558) (xy 59.657563 -360.556293) (xy 59.719599 -360.599868)
			(xy 59.776652 -360.64979) (xy 59.828076 -360.705494) (xy 59.873287 -360.766349) (xy 59.911774 -360.831664)
			(xy 59.9431 -360.9007) (xy 59.96691 -360.972675) (xy 59.982935 -361.046773) (xy 59.990994 -361.122154)
			(xy 59.991498 -361.16006) (xy 61.107577 -361.16006) (xy 61.111612 -361.084356) (xy 61.123671 -361.009511)
			(xy 61.143617 -360.93637) (xy 61.171224 -360.865765) (xy 61.20618 -360.798494) (xy 61.248088 -360.735319)
			(xy 61.296474 -360.676957) (xy 61.35079 -360.624069) (xy 61.410419 -360.577254) (xy 61.474687 -360.537042)
			(xy 61.542864 -360.50389) (xy 61.61418 -360.478172) (xy 61.687825 -360.46018) (xy 61.762965 -360.450118)
			(xy 61.838749 -360.448099) (xy 61.914319 -360.454148) (xy 61.988817 -360.468195) (xy 62.0614 -360.490081)
			(xy 62.131246 -360.519558) (xy 62.197563 -360.556293) (xy 62.259599 -360.599868) (xy 62.316652 -360.64979)
			(xy 62.368076 -360.705494) (xy 62.413287 -360.766349) (xy 62.451774 -360.831664) (xy 62.4831 -360.9007)
			(xy 62.50691 -360.972675) (xy 62.522935 -361.046773) (xy 62.530994 -361.122154) (xy 62.531498 -361.16006)
			(xy 62.530994 -361.197966) (xy 62.522935 -361.273347) (xy 62.50691 -361.347445) (xy 62.4831 -361.41942)
			(xy 62.451774 -361.488456) (xy 62.413287 -361.553771) (xy 62.368076 -361.614626) (xy 62.316652 -361.67033)
			(xy 62.259599 -361.720252) (xy 62.197563 -361.763827) (xy 62.131246 -361.800562) (xy 62.0614 -361.830039)
			(xy 61.988817 -361.851925) (xy 61.914319 -361.865972) (xy 61.838749 -361.872021) (xy 61.762965 -361.870002)
			(xy 61.687825 -361.85994) (xy 61.61418 -361.841948) (xy 61.542864 -361.81623) (xy 61.474687 -361.783078)
			(xy 61.410419 -361.742866) (xy 61.35079 -361.696051) (xy 61.296474 -361.643163) (xy 61.248088 -361.584801)
			(xy 61.20618 -361.521626) (xy 61.171224 -361.454355) (xy 61.143617 -361.38375) (xy 61.123671 -361.310609)
			(xy 61.111612 -361.235764) (xy 61.107577 -361.16006) (xy 59.991498 -361.16006) (xy 59.990994 -361.197966)
			(xy 59.982935 -361.273347) (xy 59.96691 -361.347445) (xy 59.9431 -361.41942) (xy 59.911774 -361.488456)
			(xy 59.873287 -361.553771) (xy 59.828076 -361.614626) (xy 59.776652 -361.67033) (xy 59.719599 -361.720252)
			(xy 59.657563 -361.763827) (xy 59.591246 -361.800562) (xy 59.5214 -361.830039) (xy 59.448817 -361.851925)
			(xy 59.374319 -361.865972) (xy 59.298749 -361.872021) (xy 59.222965 -361.870002) (xy 59.147825 -361.85994)
			(xy 59.07418 -361.841948) (xy 59.002864 -361.81623) (xy 58.934687 -361.783078) (xy 58.870419 -361.742866)
			(xy 58.81079 -361.696051) (xy 58.756474 -361.643163) (xy 58.708088 -361.584801) (xy 58.66618 -361.521626)
			(xy 58.631224 -361.454355) (xy 58.603617 -361.38375) (xy 58.583671 -361.310609) (xy 58.571612 -361.235764)
			(xy 58.567577 -361.16006) (xy 57.451498 -361.16006) (xy 57.450994 -361.197966) (xy 57.442935 -361.273347)
			(xy 57.42691 -361.347445) (xy 57.4031 -361.41942) (xy 57.371774 -361.488456) (xy 57.333287 -361.553771)
			(xy 57.288076 -361.614626) (xy 57.236652 -361.67033) (xy 57.179599 -361.720252) (xy 57.117563 -361.763827)
			(xy 57.051246 -361.800562) (xy 56.9814 -361.830039) (xy 56.908817 -361.851925) (xy 56.834319 -361.865972)
			(xy 56.758749 -361.872021) (xy 56.682965 -361.870002) (xy 56.607825 -361.85994) (xy 56.53418 -361.841948)
			(xy 56.462864 -361.81623) (xy 56.394687 -361.783078) (xy 56.330419 -361.742866) (xy 56.27079 -361.696051)
			(xy 56.216474 -361.643163) (xy 56.168088 -361.584801) (xy 56.12618 -361.521626) (xy 56.091224 -361.454355)
			(xy 56.063617 -361.38375) (xy 56.043671 -361.310609) (xy 56.031612 -361.235764) (xy 56.027577 -361.16006)
			(xy 54.911498 -361.16006) (xy 54.910994 -361.197966) (xy 54.902935 -361.273347) (xy 54.88691 -361.347445)
			(xy 54.8631 -361.41942) (xy 54.831774 -361.488456) (xy 54.793287 -361.553771) (xy 54.748076 -361.614626)
			(xy 54.696652 -361.67033) (xy 54.639599 -361.720252) (xy 54.577563 -361.763827) (xy 54.511246 -361.800562)
			(xy 54.4414 -361.830039) (xy 54.368817 -361.851925) (xy 54.294319 -361.865972) (xy 54.218749 -361.872021)
			(xy 54.142965 -361.870002) (xy 54.067825 -361.85994) (xy 53.99418 -361.841948) (xy 53.922864 -361.81623)
			(xy 53.854687 -361.783078) (xy 53.790419 -361.742866) (xy 53.73079 -361.696051) (xy 53.676474 -361.643163)
			(xy 53.628088 -361.584801) (xy 53.58618 -361.521626) (xy 53.551224 -361.454355) (xy 53.523617 -361.38375)
			(xy 53.503671 -361.310609) (xy 53.491612 -361.235764) (xy 53.487577 -361.16006) (xy 52.371498 -361.16006)
			(xy 52.370994 -361.197966) (xy 52.362935 -361.273347) (xy 52.34691 -361.347445) (xy 52.3231 -361.41942)
			(xy 52.291774 -361.488456) (xy 52.253287 -361.553771) (xy 52.208076 -361.614626) (xy 52.156652 -361.67033)
			(xy 52.099599 -361.720252) (xy 52.037563 -361.763827) (xy 51.971246 -361.800562) (xy 51.9014 -361.830039)
			(xy 51.828817 -361.851925) (xy 51.754319 -361.865972) (xy 51.678749 -361.872021) (xy 51.602965 -361.870002)
			(xy 51.527825 -361.85994) (xy 51.45418 -361.841948) (xy 51.382864 -361.81623) (xy 51.314687 -361.783078)
			(xy 51.250419 -361.742866) (xy 51.19079 -361.696051) (xy 51.136474 -361.643163) (xy 51.088088 -361.584801)
			(xy 51.04618 -361.521626) (xy 51.011224 -361.454355) (xy 50.983617 -361.38375) (xy 50.963671 -361.310609)
			(xy 50.951612 -361.235764) (xy 50.947577 -361.16006) (xy 49.831498 -361.16006) (xy 49.830994 -361.197966)
			(xy 49.822935 -361.273347) (xy 49.80691 -361.347445) (xy 49.7831 -361.41942) (xy 49.751774 -361.488456)
			(xy 49.713287 -361.553771) (xy 49.668076 -361.614626) (xy 49.616652 -361.67033) (xy 49.559599 -361.720252)
			(xy 49.497563 -361.763827) (xy 49.431246 -361.800562) (xy 49.3614 -361.830039) (xy 49.288817 -361.851925)
			(xy 49.214319 -361.865972) (xy 49.138749 -361.872021) (xy 49.062965 -361.870002) (xy 48.987825 -361.85994)
			(xy 48.91418 -361.841948) (xy 48.842864 -361.81623) (xy 48.774687 -361.783078) (xy 48.710419 -361.742866)
			(xy 48.65079 -361.696051) (xy 48.596474 -361.643163) (xy 48.548088 -361.584801) (xy 48.50618 -361.521626)
			(xy 48.471224 -361.454355) (xy 48.443617 -361.38375) (xy 48.423671 -361.310609) (xy 48.411612 -361.235764)
			(xy 48.407577 -361.16006) (xy 47.291498 -361.16006) (xy 47.290994 -361.197966) (xy 47.282935 -361.273347)
			(xy 47.26691 -361.347445) (xy 47.2431 -361.41942) (xy 47.211774 -361.488456) (xy 47.173287 -361.553771)
			(xy 47.128076 -361.614626) (xy 47.076652 -361.67033) (xy 47.019599 -361.720252) (xy 46.957563 -361.763827)
			(xy 46.891246 -361.800562) (xy 46.8214 -361.830039) (xy 46.748817 -361.851925) (xy 46.674319 -361.865972)
			(xy 46.598749 -361.872021) (xy 46.522965 -361.870002) (xy 46.447825 -361.85994) (xy 46.37418 -361.841948)
			(xy 46.302864 -361.81623) (xy 46.234687 -361.783078) (xy 46.170419 -361.742866) (xy 46.11079 -361.696051)
			(xy 46.056474 -361.643163) (xy 46.008088 -361.584801) (xy 45.96618 -361.521626) (xy 45.931224 -361.454355)
			(xy 45.903617 -361.38375) (xy 45.883671 -361.310609) (xy 45.871612 -361.235764) (xy 45.867577 -361.16006)
			(xy 44.751498 -361.16006) (xy 44.750994 -361.197966) (xy 44.742935 -361.273347) (xy 44.72691 -361.347445)
			(xy 44.7031 -361.41942) (xy 44.671774 -361.488456) (xy 44.633287 -361.553771) (xy 44.588076 -361.614626)
			(xy 44.536652 -361.67033) (xy 44.479599 -361.720252) (xy 44.417563 -361.763827) (xy 44.351246 -361.800562)
			(xy 44.2814 -361.830039) (xy 44.208817 -361.851925) (xy 44.134319 -361.865972) (xy 44.058749 -361.872021)
			(xy 43.982965 -361.870002) (xy 43.907825 -361.85994) (xy 43.83418 -361.841948) (xy 43.762864 -361.81623)
			(xy 43.694687 -361.783078) (xy 43.630419 -361.742866) (xy 43.57079 -361.696051) (xy 43.516474 -361.643163)
			(xy 43.468088 -361.584801) (xy 43.42618 -361.521626) (xy 43.391224 -361.454355) (xy 43.363617 -361.38375)
			(xy 43.343671 -361.310609) (xy 43.331612 -361.235764) (xy 43.327577 -361.16006) (xy 42.500375 -361.16006)
			(xy 42.548324 -361.195664) (xy 42.636883 -361.271485) (xy 42.719975 -361.353261) (xy 42.7972 -361.440599)
			(xy 42.868187 -361.533078) (xy 42.932596 -361.630253) (xy 42.990115 -361.731659) (xy 43.040469 -361.836806)
			(xy 43.062398 -361.890818) (xy 43.083282 -361.944867) (xy 43.118452 -362.055283) (xy 43.145933 -362.167859)
			(xy 43.165595 -362.282061) (xy 43.177344 -362.397346) (xy 43.181124 -362.513166) (xy 43.176918 -362.628972)
			(xy 43.164744 -362.744213) (xy 43.144662 -362.858341) (xy 43.116766 -362.970815) (xy 43.081189 -363.081101)
			(xy 43.0381 -363.188674) (xy 42.987704 -363.293024) (xy 42.93024 -363.393655) (xy 42.865981 -363.490088)
			(xy 42.795232 -363.581866) (xy 42.71833 -363.668553) (xy 42.635639 -363.749737) (xy 42.547552 -363.825033)
			(xy 42.500316 -363.86008) (xy 43.327577 -363.86008) (xy 43.331612 -363.784376) (xy 43.343671 -363.709531)
			(xy 43.363617 -363.63639) (xy 43.391224 -363.565785) (xy 43.42618 -363.498514) (xy 43.468088 -363.435339)
			(xy 43.516474 -363.376977) (xy 43.57079 -363.324089) (xy 43.630419 -363.277274) (xy 43.694687 -363.237062)
			(xy 43.762864 -363.20391) (xy 43.83418 -363.178192) (xy 43.907825 -363.1602) (xy 43.982965 -363.150138)
			(xy 44.058749 -363.148119) (xy 44.134319 -363.154168) (xy 44.208817 -363.168215) (xy 44.2814 -363.190101)
			(xy 44.351246 -363.219578) (xy 44.417563 -363.256313) (xy 44.479599 -363.299888) (xy 44.536652 -363.34981)
			(xy 44.588076 -363.405514) (xy 44.633287 -363.466369) (xy 44.671774 -363.531684) (xy 44.7031 -363.60072)
			(xy 44.72691 -363.672695) (xy 44.742935 -363.746793) (xy 44.750994 -363.822174) (xy 44.751498 -363.86008)
			(xy 45.867577 -363.86008) (xy 45.871612 -363.784376) (xy 45.883671 -363.709531) (xy 45.903617 -363.63639)
			(xy 45.931224 -363.565785) (xy 45.96618 -363.498514) (xy 46.008088 -363.435339) (xy 46.056474 -363.376977)
			(xy 46.11079 -363.324089) (xy 46.170419 -363.277274) (xy 46.234687 -363.237062) (xy 46.302864 -363.20391)
			(xy 46.37418 -363.178192) (xy 46.447825 -363.1602) (xy 46.522965 -363.150138) (xy 46.598749 -363.148119)
			(xy 46.674319 -363.154168) (xy 46.748817 -363.168215) (xy 46.8214 -363.190101) (xy 46.891246 -363.219578)
			(xy 46.957563 -363.256313) (xy 47.019599 -363.299888) (xy 47.076652 -363.34981) (xy 47.128076 -363.405514)
			(xy 47.173287 -363.466369) (xy 47.211774 -363.531684) (xy 47.2431 -363.60072) (xy 47.26691 -363.672695)
			(xy 47.282935 -363.746793) (xy 47.290994 -363.822174) (xy 47.291498 -363.86008) (xy 48.407577 -363.86008)
			(xy 48.411612 -363.784376) (xy 48.423671 -363.709531) (xy 48.443617 -363.63639) (xy 48.471224 -363.565785)
			(xy 48.50618 -363.498514) (xy 48.548088 -363.435339) (xy 48.596474 -363.376977) (xy 48.65079 -363.324089)
			(xy 48.710419 -363.277274) (xy 48.774687 -363.237062) (xy 48.842864 -363.20391) (xy 48.91418 -363.178192)
			(xy 48.987825 -363.1602) (xy 49.062965 -363.150138) (xy 49.138749 -363.148119) (xy 49.214319 -363.154168)
			(xy 49.288817 -363.168215) (xy 49.3614 -363.190101) (xy 49.431246 -363.219578) (xy 49.497563 -363.256313)
			(xy 49.559599 -363.299888) (xy 49.616652 -363.34981) (xy 49.668076 -363.405514) (xy 49.713287 -363.466369)
			(xy 49.751774 -363.531684) (xy 49.7831 -363.60072) (xy 49.80691 -363.672695) (xy 49.822935 -363.746793)
			(xy 49.830994 -363.822174) (xy 49.831498 -363.86008) (xy 50.947577 -363.86008) (xy 50.951612 -363.784376)
			(xy 50.963671 -363.709531) (xy 50.983617 -363.63639) (xy 51.011224 -363.565785) (xy 51.04618 -363.498514)
			(xy 51.088088 -363.435339) (xy 51.136474 -363.376977) (xy 51.19079 -363.324089) (xy 51.250419 -363.277274)
			(xy 51.314687 -363.237062) (xy 51.382864 -363.20391) (xy 51.45418 -363.178192) (xy 51.527825 -363.1602)
			(xy 51.602965 -363.150138) (xy 51.678749 -363.148119) (xy 51.754319 -363.154168) (xy 51.828817 -363.168215)
			(xy 51.9014 -363.190101) (xy 51.971246 -363.219578) (xy 52.037563 -363.256313) (xy 52.099599 -363.299888)
			(xy 52.156652 -363.34981) (xy 52.208076 -363.405514) (xy 52.253287 -363.466369) (xy 52.291774 -363.531684)
			(xy 52.3231 -363.60072) (xy 52.34691 -363.672695) (xy 52.362935 -363.746793) (xy 52.370994 -363.822174)
			(xy 52.371498 -363.86008) (xy 53.487577 -363.86008) (xy 53.491612 -363.784376) (xy 53.503671 -363.709531)
			(xy 53.523617 -363.63639) (xy 53.551224 -363.565785) (xy 53.58618 -363.498514) (xy 53.628088 -363.435339)
			(xy 53.676474 -363.376977) (xy 53.73079 -363.324089) (xy 53.790419 -363.277274) (xy 53.854687 -363.237062)
			(xy 53.922864 -363.20391) (xy 53.99418 -363.178192) (xy 54.067825 -363.1602) (xy 54.142965 -363.150138)
			(xy 54.218749 -363.148119) (xy 54.294319 -363.154168) (xy 54.368817 -363.168215) (xy 54.4414 -363.190101)
			(xy 54.511246 -363.219578) (xy 54.577563 -363.256313) (xy 54.639599 -363.299888) (xy 54.696652 -363.34981)
			(xy 54.748076 -363.405514) (xy 54.793287 -363.466369) (xy 54.831774 -363.531684) (xy 54.8631 -363.60072)
			(xy 54.88691 -363.672695) (xy 54.902935 -363.746793) (xy 54.910994 -363.822174) (xy 54.911498 -363.86008)
			(xy 56.027577 -363.86008) (xy 56.031612 -363.784376) (xy 56.043671 -363.709531) (xy 56.063617 -363.63639)
			(xy 56.091224 -363.565785) (xy 56.12618 -363.498514) (xy 56.168088 -363.435339) (xy 56.216474 -363.376977)
			(xy 56.27079 -363.324089) (xy 56.330419 -363.277274) (xy 56.394687 -363.237062) (xy 56.462864 -363.20391)
			(xy 56.53418 -363.178192) (xy 56.607825 -363.1602) (xy 56.682965 -363.150138) (xy 56.758749 -363.148119)
			(xy 56.834319 -363.154168) (xy 56.908817 -363.168215) (xy 56.9814 -363.190101) (xy 57.051246 -363.219578)
			(xy 57.117563 -363.256313) (xy 57.179599 -363.299888) (xy 57.236652 -363.34981) (xy 57.288076 -363.405514)
			(xy 57.333287 -363.466369) (xy 57.371774 -363.531684) (xy 57.4031 -363.60072) (xy 57.42691 -363.672695)
			(xy 57.442935 -363.746793) (xy 57.450994 -363.822174) (xy 57.451498 -363.86008) (xy 58.567577 -363.86008)
			(xy 58.571612 -363.784376) (xy 58.583671 -363.709531) (xy 58.603617 -363.63639) (xy 58.631224 -363.565785)
			(xy 58.66618 -363.498514) (xy 58.708088 -363.435339) (xy 58.756474 -363.376977) (xy 58.81079 -363.324089)
			(xy 58.870419 -363.277274) (xy 58.934687 -363.237062) (xy 59.002864 -363.20391) (xy 59.07418 -363.178192)
			(xy 59.147825 -363.1602) (xy 59.222965 -363.150138) (xy 59.298749 -363.148119) (xy 59.374319 -363.154168)
			(xy 59.448817 -363.168215) (xy 59.5214 -363.190101) (xy 59.591246 -363.219578) (xy 59.657563 -363.256313)
			(xy 59.719599 -363.299888) (xy 59.776652 -363.34981) (xy 59.828076 -363.405514) (xy 59.873287 -363.466369)
			(xy 59.911774 -363.531684) (xy 59.9431 -363.60072) (xy 59.96691 -363.672695) (xy 59.982935 -363.746793)
			(xy 59.990994 -363.822174) (xy 59.991498 -363.86008) (xy 61.107577 -363.86008) (xy 61.111612 -363.784376)
			(xy 61.123671 -363.709531) (xy 61.143617 -363.63639) (xy 61.171224 -363.565785) (xy 61.20618 -363.498514)
			(xy 61.248088 -363.435339) (xy 61.296474 -363.376977) (xy 61.35079 -363.324089) (xy 61.410419 -363.277274)
			(xy 61.474687 -363.237062) (xy 61.542864 -363.20391) (xy 61.61418 -363.178192) (xy 61.687825 -363.1602)
			(xy 61.762965 -363.150138) (xy 61.838749 -363.148119) (xy 61.914319 -363.154168) (xy 61.988817 -363.168215)
			(xy 62.0614 -363.190101) (xy 62.131246 -363.219578) (xy 62.197563 -363.256313) (xy 62.259599 -363.299888)
			(xy 62.316652 -363.34981) (xy 62.368076 -363.405514) (xy 62.413287 -363.466369) (xy 62.451774 -363.531684)
			(xy 62.4831 -363.60072) (xy 62.50691 -363.672695) (xy 62.522935 -363.746793) (xy 62.530994 -363.822174)
			(xy 62.531498 -363.86008) (xy 62.530994 -363.897986) (xy 62.522935 -363.973367) (xy 62.50691 -364.047465)
			(xy 62.4831 -364.11944) (xy 62.451774 -364.188476) (xy 62.413287 -364.253791) (xy 62.368076 -364.314646)
			(xy 62.316652 -364.37035) (xy 62.259599 -364.420272) (xy 62.197563 -364.463847) (xy 62.131246 -364.500582)
			(xy 62.0614 -364.530059) (xy 61.988817 -364.551945) (xy 61.914319 -364.565992) (xy 61.838749 -364.572041)
			(xy 61.762965 -364.570022) (xy 61.687825 -364.55996) (xy 61.61418 -364.541968) (xy 61.542864 -364.51625)
			(xy 61.474687 -364.483098) (xy 61.410419 -364.442886) (xy 61.35079 -364.396071) (xy 61.296474 -364.343183)
			(xy 61.248088 -364.284821) (xy 61.20618 -364.221646) (xy 61.171224 -364.154375) (xy 61.143617 -364.08377)
			(xy 61.123671 -364.010629) (xy 61.111612 -363.935784) (xy 61.107577 -363.86008) (xy 59.991498 -363.86008)
			(xy 59.990994 -363.897986) (xy 59.982935 -363.973367) (xy 59.96691 -364.047465) (xy 59.9431 -364.11944)
			(xy 59.911774 -364.188476) (xy 59.873287 -364.253791) (xy 59.828076 -364.314646) (xy 59.776652 -364.37035)
			(xy 59.719599 -364.420272) (xy 59.657563 -364.463847) (xy 59.591246 -364.500582) (xy 59.5214 -364.530059)
			(xy 59.448817 -364.551945) (xy 59.374319 -364.565992) (xy 59.298749 -364.572041) (xy 59.222965 -364.570022)
			(xy 59.147825 -364.55996) (xy 59.07418 -364.541968) (xy 59.002864 -364.51625) (xy 58.934687 -364.483098)
			(xy 58.870419 -364.442886) (xy 58.81079 -364.396071) (xy 58.756474 -364.343183) (xy 58.708088 -364.284821)
			(xy 58.66618 -364.221646) (xy 58.631224 -364.154375) (xy 58.603617 -364.08377) (xy 58.583671 -364.010629)
			(xy 58.571612 -363.935784) (xy 58.567577 -363.86008) (xy 57.451498 -363.86008) (xy 57.450994 -363.897986)
			(xy 57.442935 -363.973367) (xy 57.42691 -364.047465) (xy 57.4031 -364.11944) (xy 57.371774 -364.188476)
			(xy 57.333287 -364.253791) (xy 57.288076 -364.314646) (xy 57.236652 -364.37035) (xy 57.179599 -364.420272)
			(xy 57.117563 -364.463847) (xy 57.051246 -364.500582) (xy 56.9814 -364.530059) (xy 56.908817 -364.551945)
			(xy 56.834319 -364.565992) (xy 56.758749 -364.572041) (xy 56.682965 -364.570022) (xy 56.607825 -364.55996)
			(xy 56.53418 -364.541968) (xy 56.462864 -364.51625) (xy 56.394687 -364.483098) (xy 56.330419 -364.442886)
			(xy 56.27079 -364.396071) (xy 56.216474 -364.343183) (xy 56.168088 -364.284821) (xy 56.12618 -364.221646)
			(xy 56.091224 -364.154375) (xy 56.063617 -364.08377) (xy 56.043671 -364.010629) (xy 56.031612 -363.935784)
			(xy 56.027577 -363.86008) (xy 54.911498 -363.86008) (xy 54.910994 -363.897986) (xy 54.902935 -363.973367)
			(xy 54.88691 -364.047465) (xy 54.8631 -364.11944) (xy 54.831774 -364.188476) (xy 54.793287 -364.253791)
			(xy 54.748076 -364.314646) (xy 54.696652 -364.37035) (xy 54.639599 -364.420272) (xy 54.577563 -364.463847)
			(xy 54.511246 -364.500582) (xy 54.4414 -364.530059) (xy 54.368817 -364.551945) (xy 54.294319 -364.565992)
			(xy 54.218749 -364.572041) (xy 54.142965 -364.570022) (xy 54.067825 -364.55996) (xy 53.99418 -364.541968)
			(xy 53.922864 -364.51625) (xy 53.854687 -364.483098) (xy 53.790419 -364.442886) (xy 53.73079 -364.396071)
			(xy 53.676474 -364.343183) (xy 53.628088 -364.284821) (xy 53.58618 -364.221646) (xy 53.551224 -364.154375)
			(xy 53.523617 -364.08377) (xy 53.503671 -364.010629) (xy 53.491612 -363.935784) (xy 53.487577 -363.86008)
			(xy 52.371498 -363.86008) (xy 52.370994 -363.897986) (xy 52.362935 -363.973367) (xy 52.34691 -364.047465)
			(xy 52.3231 -364.11944) (xy 52.291774 -364.188476) (xy 52.253287 -364.253791) (xy 52.208076 -364.314646)
			(xy 52.156652 -364.37035) (xy 52.099599 -364.420272) (xy 52.037563 -364.463847) (xy 51.971246 -364.500582)
			(xy 51.9014 -364.530059) (xy 51.828817 -364.551945) (xy 51.754319 -364.565992) (xy 51.678749 -364.572041)
			(xy 51.602965 -364.570022) (xy 51.527825 -364.55996) (xy 51.45418 -364.541968) (xy 51.382864 -364.51625)
			(xy 51.314687 -364.483098) (xy 51.250419 -364.442886) (xy 51.19079 -364.396071) (xy 51.136474 -364.343183)
			(xy 51.088088 -364.284821) (xy 51.04618 -364.221646) (xy 51.011224 -364.154375) (xy 50.983617 -364.08377)
			(xy 50.963671 -364.010629) (xy 50.951612 -363.935784) (xy 50.947577 -363.86008) (xy 49.831498 -363.86008)
			(xy 49.830994 -363.897986) (xy 49.822935 -363.973367) (xy 49.80691 -364.047465) (xy 49.7831 -364.11944)
			(xy 49.751774 -364.188476) (xy 49.713287 -364.253791) (xy 49.668076 -364.314646) (xy 49.616652 -364.37035)
			(xy 49.559599 -364.420272) (xy 49.497563 -364.463847) (xy 49.431246 -364.500582) (xy 49.3614 -364.530059)
			(xy 49.288817 -364.551945) (xy 49.214319 -364.565992) (xy 49.138749 -364.572041) (xy 49.062965 -364.570022)
			(xy 48.987825 -364.55996) (xy 48.91418 -364.541968) (xy 48.842864 -364.51625) (xy 48.774687 -364.483098)
			(xy 48.710419 -364.442886) (xy 48.65079 -364.396071) (xy 48.596474 -364.343183) (xy 48.548088 -364.284821)
			(xy 48.50618 -364.221646) (xy 48.471224 -364.154375) (xy 48.443617 -364.08377) (xy 48.423671 -364.010629)
			(xy 48.411612 -363.935784) (xy 48.407577 -363.86008) (xy 47.291498 -363.86008) (xy 47.290994 -363.897986)
			(xy 47.282935 -363.973367) (xy 47.26691 -364.047465) (xy 47.2431 -364.11944) (xy 47.211774 -364.188476)
			(xy 47.173287 -364.253791) (xy 47.128076 -364.314646) (xy 47.076652 -364.37035) (xy 47.019599 -364.420272)
			(xy 46.957563 -364.463847) (xy 46.891246 -364.500582) (xy 46.8214 -364.530059) (xy 46.748817 -364.551945)
			(xy 46.674319 -364.565992) (xy 46.598749 -364.572041) (xy 46.522965 -364.570022) (xy 46.447825 -364.55996)
			(xy 46.37418 -364.541968) (xy 46.302864 -364.51625) (xy 46.234687 -364.483098) (xy 46.170419 -364.442886)
			(xy 46.11079 -364.396071) (xy 46.056474 -364.343183) (xy 46.008088 -364.284821) (xy 45.96618 -364.221646)
			(xy 45.931224 -364.154375) (xy 45.903617 -364.08377) (xy 45.883671 -364.010629) (xy 45.871612 -363.935784)
			(xy 45.867577 -363.86008) (xy 44.751498 -363.86008) (xy 44.750994 -363.897986) (xy 44.742935 -363.973367)
			(xy 44.72691 -364.047465) (xy 44.7031 -364.11944) (xy 44.671774 -364.188476) (xy 44.633287 -364.253791)
			(xy 44.588076 -364.314646) (xy 44.536652 -364.37035) (xy 44.479599 -364.420272) (xy 44.417563 -364.463847)
			(xy 44.351246 -364.500582) (xy 44.2814 -364.530059) (xy 44.208817 -364.551945) (xy 44.134319 -364.565992)
			(xy 44.058749 -364.572041) (xy 43.982965 -364.570022) (xy 43.907825 -364.55996) (xy 43.83418 -364.541968)
			(xy 43.762864 -364.51625) (xy 43.694687 -364.483098) (xy 43.630419 -364.442886) (xy 43.57079 -364.396071)
			(xy 43.516474 -364.343183) (xy 43.468088 -364.284821) (xy 43.42618 -364.221646) (xy 43.391224 -364.154375)
			(xy 43.363617 -364.08377) (xy 43.343671 -364.010629) (xy 43.331612 -363.935784) (xy 43.327577 -363.86008)
			(xy 42.500316 -363.86008) (xy 42.454488 -363.894082) (xy 42.35689 -363.956557) (xy 42.255219 -364.012161)
			(xy 42.149961 -364.060629) (xy 42.041613 -364.101733) (xy 41.930692 -364.135275) (xy 41.817724 -364.161098)
			(xy 41.703245 -364.179078) (xy 41.5878 -364.18913) (xy 41.471936 -364.191207) (xy 41.356205 -364.185297)
			(xy 41.298622 -364.17885) (xy 41.276242 -364.176626) (xy 41.231344 -364.179164) (xy 41.187593 -364.189565)
			(xy 41.146356 -364.207503) (xy 41.10892 -364.23242) (xy 41.076454 -364.263536) (xy 41.049971 -364.299881)
			(xy 41.030299 -364.34032) (xy 41.018051 -364.383589) (xy 41.01361 -364.428339) (xy 41.017114 -364.473172)
			(xy 41.028455 -364.516689) (xy 41.047278 -364.55753) (xy 41.072995 -364.594421) (xy 41.088564 -364.61065)
			(xy 46.390052 -369.912392) (xy 46.390052 -371.96649) (xy 69.600316 -371.96649) (xy 69.604387 -371.910868)
			(xy 69.616513 -371.856431) (xy 69.636436 -371.80434) (xy 69.663732 -371.755705) (xy 69.697818 -371.711562)
			(xy 69.737967 -371.672853) (xy 69.783325 -371.640402) (xy 69.832925 -371.614901) (xy 69.885709 -371.596894)
			(xy 69.940552 -371.586764) (xy 69.996286 -371.584727) (xy 70.051723 -371.590827) (xy 70.10568 -371.604933)
			(xy 70.157009 -371.626745) (xy 70.204615 -371.655799) (xy 70.247483 -371.691474) (xy 70.2847 -371.733011)
			(xy 70.315473 -371.779524) (xy 70.339145 -371.830021) (xy 70.355213 -371.883428) (xy 70.363333 -371.938604)
			(xy 70.363842 -371.96649) (xy 70.735442 -371.96649) (xy 70.739513 -371.910868) (xy 70.751639 -371.856431)
			(xy 70.771562 -371.80434) (xy 70.798858 -371.755705) (xy 70.832944 -371.711562) (xy 70.873093 -371.672853)
			(xy 70.918451 -371.640402) (xy 70.968051 -371.614901) (xy 71.020835 -371.596894) (xy 71.075678 -371.586764)
			(xy 71.131412 -371.584727) (xy 71.186849 -371.590827) (xy 71.240806 -371.604933) (xy 71.292135 -371.626745)
			(xy 71.339741 -371.655799) (xy 71.382609 -371.691474) (xy 71.419826 -371.733011) (xy 71.450599 -371.779524)
			(xy 71.474271 -371.830021) (xy 71.490339 -371.883428) (xy 71.498459 -371.938604) (xy 71.498968 -371.96649)
			(xy 71.498459 -371.994376) (xy 71.490339 -372.049552) (xy 71.474271 -372.102959) (xy 71.450599 -372.153456)
			(xy 71.419826 -372.199969) (xy 71.382609 -372.241506) (xy 71.339741 -372.277181) (xy 71.292135 -372.306235)
			(xy 71.240806 -372.328047) (xy 71.186849 -372.342153) (xy 71.131412 -372.348253) (xy 71.075678 -372.346216)
			(xy 71.020835 -372.336086) (xy 70.968051 -372.318079) (xy 70.918451 -372.292578) (xy 70.873093 -372.260127)
			(xy 70.832944 -372.221418) (xy 70.798858 -372.177275) (xy 70.771562 -372.12864) (xy 70.751639 -372.076549)
			(xy 70.739513 -372.022112) (xy 70.735442 -371.96649) (xy 70.363842 -371.96649) (xy 70.363333 -371.994376)
			(xy 70.355213 -372.049552) (xy 70.339145 -372.102959) (xy 70.315473 -372.153456) (xy 70.2847 -372.199969)
			(xy 70.247483 -372.241506) (xy 70.204615 -372.277181) (xy 70.157009 -372.306235) (xy 70.10568 -372.328047)
			(xy 70.051723 -372.342153) (xy 69.996286 -372.348253) (xy 69.940552 -372.346216) (xy 69.885709 -372.336086)
			(xy 69.832925 -372.318079) (xy 69.783325 -372.292578) (xy 69.737967 -372.260127) (xy 69.697818 -372.221418)
			(xy 69.663732 -372.177275) (xy 69.636436 -372.12864) (xy 69.616513 -372.076549) (xy 69.604387 -372.022112)
			(xy 69.600316 -371.96649) (xy 46.390052 -371.96649) (xy 46.390052 -372.81104) (xy 68.257418 -372.81104)
			(xy 68.261489 -372.755418) (xy 68.273615 -372.700981) (xy 68.293538 -372.64889) (xy 68.320834 -372.600255)
			(xy 68.35492 -372.556112) (xy 68.395069 -372.517403) (xy 68.440427 -372.484952) (xy 68.490027 -372.459451)
			(xy 68.542811 -372.441444) (xy 68.597654 -372.431314) (xy 68.653388 -372.429277) (xy 68.708825 -372.435377)
			(xy 68.762782 -372.449483) (xy 68.814111 -372.471295) (xy 68.861717 -372.500349) (xy 68.904585 -372.536024)
			(xy 68.941802 -372.577561) (xy 68.972575 -372.624074) (xy 68.996247 -372.674571) (xy 69.012315 -372.727978)
			(xy 69.020435 -372.783154) (xy 69.020944 -372.81104) (xy 69.020435 -372.838926) (xy 69.012315 -372.894102)
			(xy 68.996247 -372.947509) (xy 68.972575 -372.998006) (xy 68.941802 -373.044519) (xy 68.904585 -373.086056)
			(xy 68.861717 -373.121731) (xy 68.814111 -373.150785) (xy 68.762782 -373.172597) (xy 68.708825 -373.186703)
			(xy 68.653388 -373.192803) (xy 68.597654 -373.190766) (xy 68.542811 -373.180636) (xy 68.490027 -373.162629)
			(xy 68.440427 -373.137128) (xy 68.395069 -373.104677) (xy 68.35492 -373.065968) (xy 68.320834 -373.021825)
			(xy 68.293538 -372.97319) (xy 68.273615 -372.921099) (xy 68.261489 -372.866662) (xy 68.257418 -372.81104)
			(xy 46.390052 -372.81104) (xy 46.390052 -374.477703) (xy 47.298092 -374.477703) (xy 47.298092 -374.396593)
			(xy 47.306042 -374.315874) (xy 47.321865 -374.236323) (xy 47.34541 -374.158707) (xy 47.376449 -374.083771)
			(xy 47.414684 -374.012239) (xy 47.459746 -373.944799) (xy 47.511201 -373.8821) (xy 47.568554 -373.824747)
			(xy 47.631253 -373.773292) (xy 47.698693 -373.72823) (xy 47.770225 -373.689995) (xy 47.845161 -373.658956)
			(xy 47.922777 -373.635411) (xy 48.002328 -373.619588) (xy 48.083047 -373.611638) (xy 48.164157 -373.611638)
			(xy 48.244876 -373.619588) (xy 48.324427 -373.635411) (xy 48.402043 -373.658956) (xy 48.476979 -373.689995)
			(xy 48.548511 -373.72823) (xy 48.615951 -373.773292) (xy 48.67865 -373.824747) (xy 48.736003 -373.8821)
			(xy 48.787458 -373.944799) (xy 48.83252 -374.012239) (xy 48.870755 -374.083771) (xy 48.901794 -374.158707)
			(xy 48.925339 -374.236323) (xy 48.941162 -374.315874) (xy 48.949112 -374.396593) (xy 48.94961 -374.437148)
			(xy 48.949112 -374.477703) (xy 48.941162 -374.558422) (xy 48.925339 -374.637973) (xy 48.901794 -374.715589)
			(xy 48.870755 -374.790525) (xy 48.83252 -374.862057) (xy 48.787458 -374.929497) (xy 48.736003 -374.992196)
			(xy 48.67865 -375.049549) (xy 48.615951 -375.101004) (xy 48.548511 -375.146066) (xy 48.476979 -375.184301)
			(xy 48.402043 -375.21534) (xy 48.324427 -375.238885) (xy 48.244876 -375.254708) (xy 48.164157 -375.262658)
			(xy 48.083047 -375.262658) (xy 48.002328 -375.254708) (xy 47.922777 -375.238885) (xy 47.845161 -375.21534)
			(xy 47.770225 -375.184301) (xy 47.698693 -375.146066) (xy 47.631253 -375.101004) (xy 47.568554 -375.049549)
			(xy 47.511201 -374.992196) (xy 47.459746 -374.929497) (xy 47.414684 -374.862057) (xy 47.376449 -374.790525)
			(xy 47.34541 -374.715589) (xy 47.321865 -374.637973) (xy 47.306042 -374.558422) (xy 47.298092 -374.477703)
			(xy 46.390052 -374.477703) (xy 46.390052 -375.140728) (xy 46.859444 -375.61012) (xy 86.877404 -375.61012)
			(xy 86.881424 -375.419469) (xy 86.893478 -375.229156) (xy 86.913544 -375.039521) (xy 86.941587 -374.8509)
			(xy 86.977556 -374.66363) (xy 87.021388 -374.478042) (xy 87.073005 -374.294467) (xy 87.132315 -374.113231)
			(xy 87.199213 -373.934656) (xy 87.273579 -373.759061) (xy 87.355281 -373.586756) (xy 87.444175 -373.418049)
			(xy 87.540101 -373.253239) (xy 87.64289 -373.09262) (xy 87.752359 -372.936477) (xy 87.868313 -372.785088)
			(xy 87.990547 -372.638721) (xy 88.118841 -372.497637) (xy 88.252969 -372.362088) (xy 88.392693 -372.232313)
			(xy 88.537763 -372.108543) (xy 88.687921 -371.991) (xy 88.842902 -371.879891) (xy 89.002429 -371.775414)
			(xy 89.166218 -371.677755) (xy 89.333978 -371.587088) (xy 89.505412 -371.503574) (xy 89.680214 -371.427361)
			(xy 89.858073 -371.358585) (xy 90.038674 -371.297367) (xy 90.221694 -371.243818) (xy 90.40681 -371.198032)
			(xy 90.593691 -371.16009) (xy 90.782006 -371.130061) (xy 90.971419 -371.107996) (xy 91.161593 -371.093937)
			(xy 91.352192 -371.087907) (xy 91.542875 -371.089917) (xy 91.733304 -371.099964) (xy 91.92314 -371.11803)
			(xy 92.112046 -371.144083) (xy 92.299685 -371.178076) (xy 92.485725 -371.219949) (xy 92.669834 -371.269628)
			(xy 92.851685 -371.327024) (xy 93.030955 -371.392035) (xy 93.207325 -371.464546) (xy 93.380481 -371.544427)
			(xy 93.550116 -371.631537) (xy 93.715928 -371.725721) (xy 93.877622 -371.826812) (xy 94.03491 -371.934628)
			(xy 94.187513 -372.04898) (xy 94.335161 -372.169663) (xy 94.477589 -372.296464) (xy 94.614545 -372.429155)
			(xy 94.745786 -372.567503) (xy 94.871078 -372.71126) (xy 94.990198 -372.860171) (xy 95.102934 -373.013972)
			(xy 95.209087 -373.172388) (xy 95.308467 -373.335139) (xy 95.400897 -373.501934) (xy 95.486214 -373.672478)
			(xy 95.564266 -373.846466) (xy 95.634913 -374.023591) (xy 95.698031 -374.203536) (xy 95.753507 -374.385982)
			(xy 95.801242 -374.570605) (xy 95.841152 -374.757075) (xy 95.873165 -374.945063) (xy 95.897225 -375.134233)
			(xy 95.913288 -375.324249) (xy 95.921327 -375.514773) (xy 95.92183 -375.61012) (xy 95.921327 -375.705467)
			(xy 95.913288 -375.895991) (xy 95.897225 -376.086007) (xy 95.873165 -376.275177) (xy 95.841152 -376.463165)
			(xy 95.801242 -376.649635) (xy 95.753507 -376.834258) (xy 95.698031 -377.016704) (xy 95.634913 -377.196649)
			(xy 95.564266 -377.373774) (xy 95.486214 -377.547762) (xy 95.400897 -377.718306) (xy 95.308467 -377.885101)
			(xy 95.209087 -378.047852) (xy 95.102934 -378.206268) (xy 94.990198 -378.360069) (xy 94.871078 -378.50898)
			(xy 94.745786 -378.652737) (xy 94.614545 -378.791085) (xy 94.477589 -378.923776) (xy 94.335161 -379.050577)
			(xy 94.187513 -379.17126) (xy 94.03491 -379.285612) (xy 93.877622 -379.393428) (xy 93.715928 -379.494519)
			(xy 93.550116 -379.588703) (xy 93.380481 -379.675813) (xy 93.207325 -379.755694) (xy 93.030955 -379.828205)
			(xy 92.851685 -379.893216) (xy 92.669834 -379.950612) (xy 92.485725 -380.000291) (xy 92.299685 -380.042164)
			(xy 92.112046 -380.076157) (xy 91.92314 -380.10221) (xy 91.733304 -380.120276) (xy 91.542875 -380.130323)
			(xy 91.352192 -380.132333) (xy 91.161593 -380.126303) (xy 90.971419 -380.112244) (xy 90.782006 -380.090179)
			(xy 90.593691 -380.06015) (xy 90.40681 -380.022208) (xy 90.221694 -379.976422) (xy 90.038674 -379.922873)
			(xy 89.858073 -379.861655) (xy 89.680214 -379.792879) (xy 89.505412 -379.716666) (xy 89.333978 -379.633152)
			(xy 89.166218 -379.542485) (xy 89.002429 -379.444826) (xy 88.842902 -379.340349) (xy 88.687921 -379.22924)
			(xy 88.537763 -379.111697) (xy 88.392693 -378.987927) (xy 88.252969 -378.858152) (xy 88.118841 -378.722603)
			(xy 87.990547 -378.581519) (xy 87.868313 -378.435152) (xy 87.752359 -378.283763) (xy 87.64289 -378.12762)
			(xy 87.540101 -377.967001) (xy 87.444175 -377.802191) (xy 87.355281 -377.633484) (xy 87.273579 -377.461179)
			(xy 87.199213 -377.285584) (xy 87.132315 -377.107009) (xy 87.073005 -376.925773) (xy 87.021388 -376.742198)
			(xy 86.977556 -376.55661) (xy 86.941587 -376.36934) (xy 86.913544 -376.180719) (xy 86.893478 -375.991084)
			(xy 86.881424 -375.800771) (xy 86.877404 -375.61012) (xy 46.859444 -375.61012) (xy 55.775606 -384.526282)
			(xy 76.258418 -384.526282) (xy 76.262489 -384.47066) (xy 76.274615 -384.416223) (xy 76.294538 -384.364132)
			(xy 76.321834 -384.315497) (xy 76.35592 -384.271354) (xy 76.396069 -384.232645) (xy 76.441427 -384.200194)
			(xy 76.491027 -384.174693) (xy 76.543811 -384.156686) (xy 76.598654 -384.146556) (xy 76.654388 -384.144519)
			(xy 76.709825 -384.150619) (xy 76.763782 -384.164725) (xy 76.815111 -384.186537) (xy 76.862717 -384.215591)
			(xy 76.905585 -384.251266) (xy 76.942802 -384.292803) (xy 76.973575 -384.339316) (xy 76.997247 -384.389813)
			(xy 77.013315 -384.44322) (xy 77.021435 -384.498396) (xy 77.021944 -384.526282) (xy 79.347058 -384.526282)
			(xy 79.351129 -384.47066) (xy 79.363255 -384.416223) (xy 79.383178 -384.364132) (xy 79.410474 -384.315497)
			(xy 79.44456 -384.271354) (xy 79.484709 -384.232645) (xy 79.530067 -384.200194) (xy 79.579667 -384.174693)
			(xy 79.632451 -384.156686) (xy 79.687294 -384.146556) (xy 79.743028 -384.144519) (xy 79.798465 -384.150619)
			(xy 79.852422 -384.164725) (xy 79.903751 -384.186537) (xy 79.951357 -384.215591) (xy 79.994225 -384.251266)
			(xy 80.031442 -384.292803) (xy 80.062215 -384.339316) (xy 80.085887 -384.389813) (xy 80.101955 -384.44322)
			(xy 80.110075 -384.498396) (xy 80.110584 -384.526282) (xy 80.110075 -384.554168) (xy 80.101955 -384.609344)
			(xy 80.085887 -384.662751) (xy 80.062215 -384.713248) (xy 80.031442 -384.759761) (xy 79.994225 -384.801298)
			(xy 79.951357 -384.836973) (xy 79.903751 -384.866027) (xy 79.852422 -384.887839) (xy 79.798465 -384.901945)
			(xy 79.743028 -384.908045) (xy 79.687294 -384.906008) (xy 79.632451 -384.895878) (xy 79.579667 -384.877871)
			(xy 79.530067 -384.85237) (xy 79.484709 -384.819919) (xy 79.44456 -384.78121) (xy 79.410474 -384.737067)
			(xy 79.383178 -384.688432) (xy 79.363255 -384.636341) (xy 79.351129 -384.581904) (xy 79.347058 -384.526282)
			(xy 77.021944 -384.526282) (xy 77.021435 -384.554168) (xy 77.013315 -384.609344) (xy 76.997247 -384.662751)
			(xy 76.973575 -384.713248) (xy 76.942802 -384.759761) (xy 76.905585 -384.801298) (xy 76.862717 -384.836973)
			(xy 76.815111 -384.866027) (xy 76.763782 -384.887839) (xy 76.709825 -384.901945) (xy 76.654388 -384.908045)
			(xy 76.598654 -384.906008) (xy 76.543811 -384.895878) (xy 76.491027 -384.877871) (xy 76.441427 -384.85237)
			(xy 76.396069 -384.819919) (xy 76.35592 -384.78121) (xy 76.321834 -384.737067) (xy 76.294538 -384.688432)
			(xy 76.274615 -384.636341) (xy 76.262489 -384.581904) (xy 76.258418 -384.526282) (xy 55.775606 -384.526282)
			(xy 58.447178 -387.197854) (xy 76.3938 -387.197854) (xy 76.397871 -387.142232) (xy 76.409997 -387.087795)
			(xy 76.42992 -387.035704) (xy 76.457216 -386.987069) (xy 76.491302 -386.942926) (xy 76.531451 -386.904217)
			(xy 76.576809 -386.871766) (xy 76.626409 -386.846265) (xy 76.679193 -386.828258) (xy 76.734036 -386.818128)
			(xy 76.78977 -386.816091) (xy 76.845207 -386.822191) (xy 76.899164 -386.836297) (xy 76.950493 -386.858109)
			(xy 76.998099 -386.887163) (xy 77.040967 -386.922838) (xy 77.078184 -386.964375) (xy 77.108957 -387.010888)
			(xy 77.132629 -387.061385) (xy 77.148697 -387.114792) (xy 77.156817 -387.169968) (xy 77.157326 -387.197854)
			(xy 77.156817 -387.22574) (xy 77.148697 -387.280916) (xy 77.132629 -387.334323) (xy 77.108957 -387.38482)
			(xy 77.078184 -387.431333) (xy 77.040967 -387.47287) (xy 76.998099 -387.508545) (xy 76.950493 -387.537599)
			(xy 76.899164 -387.559411) (xy 76.845207 -387.573517) (xy 76.78977 -387.579617) (xy 76.734036 -387.57758)
			(xy 76.679193 -387.56745) (xy 76.626409 -387.549443) (xy 76.576809 -387.523942) (xy 76.531451 -387.491491)
			(xy 76.491302 -387.452782) (xy 76.457216 -387.408639) (xy 76.42992 -387.360004) (xy 76.409997 -387.307913)
			(xy 76.397871 -387.253476) (xy 76.3938 -387.197854) (xy 58.447178 -387.197854) (xy 67.190112 -395.940788)
			(xy 71.783956 -395.940788) (xy 71.805912 -395.939624) (xy 71.848957 -395.930685) (xy 71.889821 -395.914468)
			(xy 71.927282 -395.891458) (xy 71.960223 -395.862342) (xy 71.987659 -395.82799) (xy 72.00877 -395.789427)
			(xy 72.022927 -395.747805) (xy 72.02678 -395.726158) (xy 72.031447 -395.699562) (xy 72.047292 -395.647943)
			(xy 72.070256 -395.599073) (xy 72.09988 -395.553928) (xy 72.135572 -395.51341) (xy 72.176619 -395.478328)
			(xy 72.222202 -395.449382) (xy 72.27141 -395.427152) (xy 72.32326 -395.41208) (xy 72.376718 -395.404468)
			(xy 72.430714 -395.404468) (xy 72.484172 -395.41208) (xy 72.536022 -395.427152) (xy 72.58523 -395.449382)
			(xy 72.630813 -395.478328) (xy 72.67186 -395.51341) (xy 72.707552 -395.553928) (xy 72.737176 -395.599073)
			(xy 72.76014 -395.647943) (xy 72.775985 -395.699562) (xy 72.780652 -395.726158) (xy 72.784522 -395.747797)
			(xy 72.798707 -395.789399) (xy 72.819833 -395.827942) (xy 72.847271 -395.86228) (xy 72.880204 -395.89139)
			(xy 72.917651 -395.914405) (xy 72.958497 -395.930639) (xy 73.001526 -395.939609) (xy 73.023476 -395.940788)
			(xy 73.069704 -395.940788) (xy 73.086358 -395.940293) (xy 73.11853 -395.931671) (xy 73.147375 -395.915016)
			(xy 73.170925 -395.891462) (xy 73.187577 -395.862615) (xy 73.196195 -395.830442) (xy 73.196704 -395.813788)
			(xy 73.196704 -395.810232) (xy 73.19645 -395.806676) (xy 73.195413 -395.779052) (xy 73.200356 -395.723994)
			(xy 73.21319 -395.670225) (xy 73.233647 -395.618871) (xy 73.2613 -395.571006) (xy 73.295569 -395.527631)
			(xy 73.335738 -395.489654) (xy 73.380965 -395.45787) (xy 73.430305 -395.432943) (xy 73.482725 -395.415396)
			(xy 73.537129 -395.405596) (xy 73.592377 -395.403747) (xy 73.647314 -395.409888) (xy 73.700789 -395.423892)
			(xy 73.751686 -395.445464) (xy 73.798937 -395.474153) (xy 73.841554 -395.50936) (xy 73.878647 -395.550347)
			(xy 73.909437 -395.596257) (xy 73.933282 -395.646129) (xy 73.949682 -395.698919) (xy 73.954386 -395.726158)
			(xy 73.958255 -395.747799) (xy 73.972439 -395.789406) (xy 73.993564 -395.827955) (xy 74.021 -395.8623)
			(xy 74.053932 -395.891418) (xy 74.091378 -395.914441) (xy 74.132225 -395.930685) (xy 74.175256 -395.939666)
			(xy 74.19721 -395.940788) (xy 74.267822 -395.940788) (xy 74.284468 -395.940242) (xy 74.316624 -395.93162)
			(xy 74.345453 -395.91497) (xy 74.368991 -395.891426) (xy 74.385633 -395.862592) (xy 74.394247 -395.830434)
			(xy 74.394822 -395.813788) (xy 74.394822 -395.810232) (xy 74.394568 -395.806676) (xy 74.393531 -395.779053)
			(xy 74.398473 -395.723998) (xy 74.411307 -395.670231) (xy 74.431763 -395.618879) (xy 74.459415 -395.571016)
			(xy 74.493682 -395.527643) (xy 74.533849 -395.489668) (xy 74.579075 -395.457885) (xy 74.628413 -395.432959)
			(xy 74.680831 -395.415413) (xy 74.735231 -395.405613) (xy 74.790477 -395.403765) (xy 74.845411 -395.409906)
			(xy 74.898885 -395.423909) (xy 74.949779 -395.445481) (xy 74.997028 -395.474169) (xy 75.039643 -395.509374)
			(xy 75.076734 -395.55036) (xy 75.107523 -395.596268) (xy 75.131366 -395.646137) (xy 75.147765 -395.698925)
			(xy 75.152504 -395.726158) (xy 75.156373 -395.747798) (xy 75.170557 -395.789404) (xy 75.191683 -395.827952)
			(xy 75.219119 -395.862295) (xy 75.252051 -395.89141) (xy 75.289498 -395.914431) (xy 75.330345 -395.930672)
			(xy 75.373375 -395.93965) (xy 75.395328 -395.940788) (xy 75.405234 -395.940788) (xy 75.421879 -395.940241)
			(xy 75.454032 -395.931617) (xy 75.482859 -395.914966) (xy 75.506394 -395.891422) (xy 75.523035 -395.86259)
			(xy 75.531647 -395.830433) (xy 75.532234 -395.813788) (xy 75.532234 -395.810232) (xy 75.53198 -395.806676)
			(xy 75.530943 -395.779054) (xy 75.535885 -395.724) (xy 75.548718 -395.670235) (xy 75.569174 -395.618885)
			(xy 75.596824 -395.571023) (xy 75.631091 -395.527651) (xy 75.671257 -395.489677) (xy 75.716481 -395.457895)
			(xy 75.765818 -395.43297) (xy 75.818234 -395.415425) (xy 75.872633 -395.405625) (xy 75.927877 -395.403777)
			(xy 75.98281 -395.409918) (xy 76.036282 -395.423921) (xy 76.087174 -395.445492) (xy 76.134422 -395.47418)
			(xy 76.177036 -395.509384) (xy 76.214125 -395.550368) (xy 76.244913 -395.596275) (xy 76.268756 -395.646143)
			(xy 76.285154 -395.69893) (xy 76.289916 -395.726158) (xy 76.293785 -395.747798) (xy 76.30797 -395.789402)
			(xy 76.329095 -395.827949) (xy 76.356532 -395.862291) (xy 76.389465 -395.891405) (xy 76.426911 -395.914424)
			(xy 76.467758 -395.930664) (xy 76.510788 -395.93964) (xy 76.53274 -395.940788) (xy 83.154266 -395.940788)
			(xy 84.595208 -397.381476) (xy 84.776056 -397.562324) (xy 84.807552 -397.571468) (xy 84.833951 -397.579546)
			(xy 84.884271 -397.602251) (xy 84.930793 -397.631973) (xy 84.972546 -397.668089) (xy 85.008657 -397.709846)
			(xy 85.038372 -397.756372) (xy 85.054187 -397.791432) (xy 93.046548 -397.791432) (xy 93.050619 -397.73581)
			(xy 93.062745 -397.681373) (xy 93.082668 -397.629282) (xy 93.109964 -397.580647) (xy 93.14405 -397.536504)
			(xy 93.184199 -397.497795) (xy 93.229557 -397.465344) (xy 93.279157 -397.439843) (xy 93.331941 -397.421836)
			(xy 93.386784 -397.411706) (xy 93.442518 -397.409669) (xy 93.497955 -397.415769) (xy 93.551912 -397.429875)
			(xy 93.603241 -397.451687) (xy 93.650847 -397.480741) (xy 93.693715 -397.516416) (xy 93.730932 -397.557953)
			(xy 93.761705 -397.604466) (xy 93.785377 -397.654963) (xy 93.801445 -397.70837) (xy 93.809565 -397.763546)
			(xy 93.810074 -397.791432) (xy 93.809565 -397.819318) (xy 93.801445 -397.874494) (xy 93.785377 -397.927901)
			(xy 93.761705 -397.978398) (xy 93.730932 -398.024911) (xy 93.693715 -398.066448) (xy 93.650847 -398.102123)
			(xy 93.603241 -398.131177) (xy 93.551912 -398.152989) (xy 93.497955 -398.167095) (xy 93.442518 -398.173195)
			(xy 93.386784 -398.171158) (xy 93.331941 -398.161028) (xy 93.279157 -398.143021) (xy 93.229557 -398.11752)
			(xy 93.184199 -398.085069) (xy 93.14405 -398.04636) (xy 93.109964 -398.002217) (xy 93.082668 -397.953582)
			(xy 93.062745 -397.901491) (xy 93.050619 -397.847054) (xy 93.046548 -397.791432) (xy 85.054187 -397.791432)
			(xy 85.061072 -397.806695) (xy 85.069172 -397.833088) (xy 85.078316 -397.864584) (xy 86.04123 -398.827498)
			(xy 88.190322 -398.827498) (xy 88.194393 -398.771876) (xy 88.206519 -398.717439) (xy 88.226442 -398.665348)
			(xy 88.253738 -398.616713) (xy 88.287824 -398.57257) (xy 88.327973 -398.533861) (xy 88.373331 -398.50141)
			(xy 88.422931 -398.475909) (xy 88.475715 -398.457902) (xy 88.530558 -398.447772) (xy 88.586292 -398.445735)
			(xy 88.641729 -398.451835) (xy 88.695686 -398.465941) (xy 88.747015 -398.487753) (xy 88.763903 -398.49806)
			(xy 91.314776 -398.49806) (xy 91.318847 -398.442438) (xy 91.330973 -398.388001) (xy 91.350896 -398.33591)
			(xy 91.378192 -398.287275) (xy 91.412278 -398.243132) (xy 91.452427 -398.204423) (xy 91.497785 -398.171972)
			(xy 91.547385 -398.146471) (xy 91.600169 -398.128464) (xy 91.655012 -398.118334) (xy 91.710746 -398.116297)
			(xy 91.766183 -398.122397) (xy 91.82014 -398.136503) (xy 91.871469 -398.158315) (xy 91.919075 -398.187369)
			(xy 91.961943 -398.223044) (xy 91.99916 -398.264581) (xy 92.029933 -398.311094) (xy 92.053605 -398.361591)
			(xy 92.069673 -398.414998) (xy 92.077793 -398.470174) (xy 92.078302 -398.49806) (xy 92.077793 -398.525946)
			(xy 92.069673 -398.581122) (xy 92.053605 -398.634529) (xy 92.029933 -398.685026) (xy 91.99916 -398.731539)
			(xy 91.961943 -398.773076) (xy 91.919075 -398.808751) (xy 91.871469 -398.837805) (xy 91.82014 -398.859617)
			(xy 91.766183 -398.873723) (xy 91.710746 -398.879823) (xy 91.655012 -398.877786) (xy 91.600169 -398.867656)
			(xy 91.547385 -398.849649) (xy 91.497785 -398.824148) (xy 91.452427 -398.791697) (xy 91.412278 -398.752988)
			(xy 91.378192 -398.708845) (xy 91.350896 -398.66021) (xy 91.330973 -398.608119) (xy 91.318847 -398.553682)
			(xy 91.314776 -398.49806) (xy 88.763903 -398.49806) (xy 88.794621 -398.516807) (xy 88.837489 -398.552482)
			(xy 88.874706 -398.594019) (xy 88.905479 -398.640532) (xy 88.929151 -398.691029) (xy 88.945219 -398.744436)
			(xy 88.953339 -398.799612) (xy 88.953848 -398.827498) (xy 88.953339 -398.855384) (xy 88.945219 -398.91056)
			(xy 88.929151 -398.963967) (xy 88.905479 -399.014464) (xy 88.894234 -399.03146) (xy 89.880438 -399.03146)
			(xy 89.884509 -398.975838) (xy 89.896635 -398.921401) (xy 89.916558 -398.86931) (xy 89.943854 -398.820675)
			(xy 89.97794 -398.776532) (xy 90.018089 -398.737823) (xy 90.063447 -398.705372) (xy 90.113047 -398.679871)
			(xy 90.165831 -398.661864) (xy 90.220674 -398.651734) (xy 90.276408 -398.649697) (xy 90.331845 -398.655797)
			(xy 90.385802 -398.669903) (xy 90.437131 -398.691715) (xy 90.484737 -398.720769) (xy 90.527605 -398.756444)
			(xy 90.564822 -398.797981) (xy 90.595595 -398.844494) (xy 90.619267 -398.894991) (xy 90.635335 -398.948398)
			(xy 90.643455 -399.003574) (xy 90.643964 -399.03146) (xy 90.643455 -399.059346) (xy 90.635335 -399.114522)
			(xy 90.619267 -399.167929) (xy 90.595595 -399.218426) (xy 90.564822 -399.264939) (xy 90.527605 -399.306476)
			(xy 90.484737 -399.342151) (xy 90.437131 -399.371205) (xy 90.385802 -399.393017) (xy 90.331845 -399.407123)
			(xy 90.276408 -399.413223) (xy 90.220674 -399.411186) (xy 90.165831 -399.401056) (xy 90.113047 -399.383049)
			(xy 90.063447 -399.357548) (xy 90.018089 -399.325097) (xy 89.97794 -399.286388) (xy 89.943854 -399.242245)
			(xy 89.916558 -399.19361) (xy 89.896635 -399.141519) (xy 89.884509 -399.087082) (xy 89.880438 -399.03146)
			(xy 88.894234 -399.03146) (xy 88.874706 -399.060977) (xy 88.837489 -399.102514) (xy 88.794621 -399.138189)
			(xy 88.747015 -399.167243) (xy 88.695686 -399.189055) (xy 88.641729 -399.203161) (xy 88.586292 -399.209261)
			(xy 88.530558 -399.207224) (xy 88.475715 -399.197094) (xy 88.422931 -399.179087) (xy 88.373331 -399.153586)
			(xy 88.327973 -399.121135) (xy 88.287824 -399.082426) (xy 88.253738 -399.038283) (xy 88.226442 -398.989648)
			(xy 88.206519 -398.937557) (xy 88.194393 -398.88312) (xy 88.190322 -398.827498) (xy 86.04123 -398.827498)
			(xy 86.45779 -399.244058) (xy 86.474171 -399.259738) (xy 86.511412 -399.285602) (xy 86.552653 -399.304443)
			(xy 86.596584 -399.315662) (xy 86.641809 -399.318902) (xy 86.68689 -399.31406) (xy 86.730396 -399.301291)
			(xy 86.770943 -399.281001) (xy 86.807243 -399.253833) (xy 86.838143 -399.220651) (xy 86.86266 -399.18251)
			(xy 86.87181 -399.161762) (xy 86.882923 -399.136342) (xy 86.911423 -399.088745) (xy 86.946515 -399.045777)
			(xy 86.987461 -399.008345) (xy 87.033395 -398.977236) (xy 87.083351 -398.953108) (xy 87.136274 -398.936469)
			(xy 87.191049 -398.92767) (xy 87.24652 -398.926896) (xy 87.301519 -398.934164) (xy 87.354886 -398.94932)
			(xy 87.405495 -398.972045) (xy 87.45228 -399.00186) (xy 87.494253 -399.038136) (xy 87.530531 -399.080108)
			(xy 87.560347 -399.126891) (xy 87.583075 -399.1775) (xy 87.598233 -399.230866) (xy 87.605503 -399.285864)
			(xy 87.604731 -399.341336) (xy 87.595934 -399.396111) (xy 87.579297 -399.449035) (xy 87.555171 -399.498992)
			(xy 87.524065 -399.544928) (xy 87.486634 -399.585874) (xy 87.443667 -399.620969) (xy 87.396072 -399.64947)
			(xy 87.370666 -399.660618) (xy 87.349925 -399.669772) (xy 87.31181 -399.694311) (xy 87.278652 -399.725222)
			(xy 87.251504 -399.761524) (xy 87.231226 -399.802067) (xy 87.218461 -399.845564) (xy 87.213615 -399.890636)
			(xy 87.216842 -399.935852) (xy 87.228038 -399.979779) (xy 87.246849 -400.021023) (xy 87.272679 -400.058276)
			(xy 87.28837 -400.074638) (xy 87.324944 -400.111214) (xy 88.072212 -400.111214) (xy 88.076283 -400.055592)
			(xy 88.088409 -400.001155) (xy 88.108332 -399.949064) (xy 88.135628 -399.900429) (xy 88.169714 -399.856286)
			(xy 88.209863 -399.817577) (xy 88.255221 -399.785126) (xy 88.304821 -399.759625) (xy 88.357605 -399.741618)
			(xy 88.412448 -399.731488) (xy 88.468182 -399.729451) (xy 88.523619 -399.735551) (xy 88.577576 -399.749657)
			(xy 88.628905 -399.771469) (xy 88.676511 -399.800523) (xy 88.719379 -399.836198) (xy 88.756596 -399.877735)
			(xy 88.787369 -399.924248) (xy 88.811041 -399.974745) (xy 88.827109 -400.028152) (xy 88.835229 -400.083328)
			(xy 88.835738 -400.111214) (xy 88.835229 -400.1391) (xy 88.827109 -400.194276) (xy 88.811041 -400.247683)
			(xy 88.787369 -400.29818) (xy 88.756596 -400.344693) (xy 88.719379 -400.38623) (xy 88.676511 -400.421905)
			(xy 88.628905 -400.450959) (xy 88.577576 -400.472771) (xy 88.523619 -400.486877) (xy 88.468182 -400.492977)
			(xy 88.412448 -400.49094) (xy 88.357605 -400.48081) (xy 88.304821 -400.462803) (xy 88.255221 -400.437302)
			(xy 88.209863 -400.404851) (xy 88.169714 -400.366142) (xy 88.135628 -400.321999) (xy 88.108332 -400.273364)
			(xy 88.088409 -400.221273) (xy 88.076283 -400.166836) (xy 88.072212 -400.111214) (xy 87.324944 -400.111214)
			(xy 91.41206 -404.198582) (xy 91.41206 -404.34768) (xy 91.4125 -404.36279) (xy 91.419625 -404.392158)
			(xy 91.433456 -404.419027) (xy 91.453218 -404.44189) (xy 91.477802 -404.459465) (xy 91.505829 -404.470766)
			(xy 91.535728 -404.47516) (xy 91.565821 -404.472399) (xy 91.594422 -404.46264) (xy 91.607386 -404.454868)
			(xy 91.640961 -404.434086) (xy 91.711828 -404.399254) (xy 91.786116 -404.372482) (xy 91.862912 -404.354101)
			(xy 91.902026 -404.348696) (xy 91.93922 -404.344545) (xy 92.014052 -404.343139) (xy 92.088618 -404.349594)
			(xy 92.162094 -404.363838) (xy 92.23367 -404.385716) (xy 92.302554 -404.414984) (xy 92.367987 -404.45132)
			(xy 92.429245 -404.494323) (xy 92.485651 -404.543517) (xy 92.536583 -404.598359) (xy 92.581478 -404.658243)
			(xy 92.61984 -404.722509) (xy 92.651246 -404.790445) (xy 92.675349 -404.861303) (xy 92.691882 -404.934299)
			(xy 92.700663 -405.008626) (xy 92.701594 -405.083465) (xy 92.694667 -405.157989) (xy 92.679956 -405.231373)
			(xy 92.657625 -405.302809) (xy 92.627921 -405.371506) (xy 92.609924 -405.40432) (xy 92.590859 -405.437183)
			(xy 92.546743 -405.499044) (xy 92.496288 -405.555852) (xy 92.440068 -405.606962) (xy 92.378722 -405.651792)
			(xy 92.31295 -405.689831) (xy 92.2435 -405.720646) (xy 92.171162 -405.743887) (xy 92.09676 -405.75929)
			(xy 92.058998 -405.763476) (xy 92.035757 -405.766283) (xy 91.990792 -405.779288) (xy 91.948968 -405.800305)
			(xy 91.911698 -405.828624) (xy 91.880244 -405.863288) (xy 91.855669 -405.903125) (xy 91.838802 -405.946789)
			(xy 91.830215 -405.992802) (xy 91.829636 -406.016206) (xy 91.829636 -406.633934) (xy 91.830165 -406.657344)
			(xy 91.838733 -406.703374) (xy 91.855592 -406.747055) (xy 91.880169 -406.786906) (xy 91.911634 -406.821578)
			(xy 91.948919 -406.849897) (xy 91.990763 -406.870903) (xy 92.035747 -406.883886) (xy 92.058998 -406.886664)
			(xy 92.096445 -406.8908) (xy 92.170243 -406.905973) (xy 92.242026 -406.928856) (xy 92.310991 -406.959194)
			(xy 92.376365 -406.996646) (xy 92.437417 -407.040794) (xy 92.493465 -407.091144) (xy 92.54388 -407.147132)
			(xy 92.5881 -407.208133) (xy 92.625629 -407.273463) (xy 92.656048 -407.342392) (xy 92.679015 -407.414148)
			(xy 92.694275 -407.487928) (xy 92.701656 -407.562908) (xy 92.701075 -407.638248) (xy 92.69254 -407.713105)
			(xy 92.676146 -407.786642) (xy 92.652076 -407.858036) (xy 92.620599 -407.926488) (xy 92.582069 -407.991232)
			(xy 92.536915 -408.051544) (xy 92.485642 -408.10675) (xy 92.428826 -408.15623) (xy 92.367101 -408.199433)
			(xy 92.301158 -408.235874) (xy 92.231734 -408.265145) (xy 92.159607 -408.28692) (xy 92.085584 -408.300954)
			(xy 92.048076 -408.304492) (xy 92.024556 -408.306958) (xy 92.013201 -408.31008) (xy 93.154506 -408.31008)
			(xy 93.158522 -408.19381) (xy 93.170549 -408.078095) (xy 93.190531 -407.963485) (xy 93.218373 -407.850526)
			(xy 93.253942 -407.739758) (xy 93.297068 -407.631707) (xy 93.347545 -407.526889) (xy 93.405134 -407.425804)
			(xy 93.46956 -407.328932) (xy 93.540515 -407.236736) (xy 93.617662 -407.149655) (xy 93.700633 -407.068104)
			(xy 93.789033 -406.992472) (xy 93.88244 -406.923118) (xy 93.980409 -406.860375) (xy 94.082473 -406.804539)
			(xy 94.188147 -406.755878) (xy 94.296926 -406.714624) (xy 94.408291 -406.680973) (xy 94.521714 -406.655085)
			(xy 94.636651 -406.637084) (xy 94.752557 -406.627055) (xy 94.868879 -406.625047) (xy 94.985062 -406.631069)
			(xy 95.100553 -406.645092) (xy 95.214801 -406.66705) (xy 95.327262 -406.696837) (xy 95.4374 -406.734312)
			(xy 95.54469 -406.779297) (xy 95.648621 -406.831576) (xy 95.748697 -406.890901) (xy 95.844443 -406.956989)
			(xy 95.9354 -407.029525) (xy 96.021136 -407.108164) (xy 96.101243 -407.19253) (xy 96.175339 -407.282222)
			(xy 96.243069 -407.376812) (xy 96.304113 -407.47585) (xy 96.358178 -407.578863) (xy 96.405008 -407.68536)
			(xy 96.444379 -407.794835) (xy 96.476103 -407.906765) (xy 96.500029 -408.020617) (xy 96.516043 -408.135849)
			(xy 96.52407 -408.251911) (xy 96.524572 -408.31008) (xy 96.52407 -408.368249) (xy 96.516043 -408.484311)
			(xy 96.500029 -408.599543) (xy 96.476103 -408.713395) (xy 96.444379 -408.825325) (xy 96.405008 -408.9348)
			(xy 96.358178 -409.041297) (xy 96.304113 -409.14431) (xy 96.243069 -409.243348) (xy 96.175339 -409.337938)
			(xy 96.101243 -409.42763) (xy 96.021136 -409.511996) (xy 95.9354 -409.590635) (xy 95.844443 -409.663171)
			(xy 95.748697 -409.729259) (xy 95.648621 -409.788584) (xy 95.54469 -409.840863) (xy 95.4374 -409.885848)
			(xy 95.327262 -409.923323) (xy 95.214801 -409.95311) (xy 95.100553 -409.975068) (xy 94.985062 -409.989091)
			(xy 94.868879 -409.995113) (xy 94.752557 -409.993105) (xy 94.636651 -409.983076) (xy 94.521714 -409.965075)
			(xy 94.408291 -409.939187) (xy 94.296926 -409.905536) (xy 94.188147 -409.864282) (xy 94.082473 -409.815621)
			(xy 93.980409 -409.759785) (xy 93.88244 -409.697042) (xy 93.789033 -409.627688) (xy 93.700633 -409.552056)
			(xy 93.617662 -409.470505) (xy 93.540515 -409.383424) (xy 93.46956 -409.291228) (xy 93.405134 -409.194356)
			(xy 93.347545 -409.093271) (xy 93.297068 -408.988453) (xy 93.253942 -408.880402) (xy 93.218373 -408.769634)
			(xy 93.190531 -408.656675) (xy 93.170549 -408.542065) (xy 93.158522 -408.42635) (xy 93.154506 -408.31008)
			(xy 92.013201 -408.31008) (xy 91.978961 -408.319494) (xy 91.936469 -408.34024) (xy 91.898542 -408.368482)
			(xy 91.866489 -408.403248) (xy 91.841414 -408.443338) (xy 91.82418 -408.487372) (xy 91.815381 -408.533833)
			(xy 91.814904 -408.557476) (xy 91.814904 -409.522676) (xy 91.750896 -409.586684) (xy 91.241626 -410.0957)
			(xy 86.421214 -410.0957) (xy 85.91804 -409.59278) (xy 85.906338 -409.581709) (xy 85.878611 -409.565326)
			(xy 85.847661 -409.556422) (xy 85.815468 -409.555564) (xy 85.799676 -409.558744) (xy 85.763051 -409.566704)
			(xy 85.68865 -409.575794) (xy 85.613706 -409.577014) (xy 85.539049 -409.570351) (xy 85.465506 -409.555879)
			(xy 85.39389 -409.533757) (xy 85.324997 -409.504231) (xy 85.259588 -409.467628) (xy 85.198389 -409.424353)
			(xy 85.142076 -409.374886) (xy 85.091274 -409.319774) (xy 85.046546 -409.259629) (xy 85.008387 -409.195115)
			(xy 84.97722 -409.126949) (xy 84.953389 -409.055884) (xy 84.937159 -408.982708) (xy 84.92871 -408.908232)
			(xy 84.928135 -408.83328) (xy 84.93544 -408.758683) (xy 84.950546 -408.685267) (xy 84.973283 -408.613845)
			(xy 85.003401 -408.545208) (xy 85.040566 -408.480117) (xy 85.084366 -408.419292) (xy 85.134316 -408.363408)
			(xy 85.189863 -408.313082) (xy 85.219794 -408.290522) (xy 85.239217 -408.276579) (xy 85.279637 -408.251028)
			(xy 85.300566 -408.239468) (xy 85.320756 -408.227515) (xy 85.356757 -408.197435) (xy 85.386632 -408.161264)
			(xy 85.409368 -408.120228) (xy 85.424195 -408.075719) (xy 85.430609 -408.029246) (xy 85.428392 -407.982385)
			(xy 85.417621 -407.936724) (xy 85.39866 -407.893813) (xy 85.372152 -407.855106) (xy 85.355938 -407.838148)
			(xy 83.856068 -406.338278) (xy 83.856068 -405.309324) (xy 79.193898 -400.647154) (xy 79.162402 -400.63801)
			(xy 79.136003 -400.629931) (xy 79.085683 -400.607224) (xy 79.03916 -400.577503) (xy 78.997406 -400.541387)
			(xy 78.961292 -400.499632) (xy 78.931571 -400.453108) (xy 78.908865 -400.402788) (xy 78.900782 -400.37639)
			(xy 78.891638 -400.344894) (xy 78.55204 -400.005296) (xy 67.58051 -400.005296) (xy 43.792648 -376.217434)
			(xy 43.792648 -370.989098) (xy 37.512752 -364.709202) (xy 37.512752 -357.357426) (xy 37.512222 -357.340788)
			(xy 37.503537 -357.308662) (xy 37.486832 -357.27988) (xy 37.475414 -357.267764) (xy 37.15639 -356.94874)
			(xy 24.901906 -356.94874) (xy 22.020276 -354.06711) (xy 22.003574 -354.052188) (xy 21.965973 -354.027864)
			(xy 21.924693 -354.010503) (xy 21.881009 -354.000642) (xy 21.836273 -353.998587) (xy 21.791869 -354.004401)
			(xy 21.749171 -354.017904) (xy 21.709498 -354.038678) (xy 21.674078 -354.066081) (xy 21.644006 -354.099265)
			(xy 21.620213 -354.137205) (xy 21.603434 -354.178725) (xy 21.594189 -354.222544) (xy 21.593048 -354.24491)
			(xy 21.593048 -358.233488) (xy 29.519874 -358.233488) (xy 29.519874 -358.146588) (xy 29.527892 -358.060059)
			(xy 29.54386 -357.974639) (xy 29.567641 -357.891057) (xy 29.599033 -357.810025) (xy 29.637767 -357.732236)
			(xy 29.683514 -357.658352) (xy 29.735883 -357.589005) (xy 29.794427 -357.524785) (xy 29.858647 -357.466241)
			(xy 29.927994 -357.413872) (xy 30.001878 -357.368125) (xy 30.079667 -357.329391) (xy 30.160699 -357.297999)
			(xy 30.244281 -357.274218) (xy 30.329701 -357.25825) (xy 30.41623 -357.250232) (xy 30.50313 -357.250232)
			(xy 30.589659 -357.25825) (xy 30.675079 -357.274218) (xy 30.758661 -357.297999) (xy 30.839693 -357.329391)
			(xy 30.917482 -357.368125) (xy 30.991366 -357.413872) (xy 31.060713 -357.466241) (xy 31.124933 -357.524785)
			(xy 31.183477 -357.589005) (xy 31.235846 -357.658352) (xy 31.281593 -357.732236) (xy 31.320327 -357.810025)
			(xy 31.351719 -357.891057) (xy 31.3755 -357.974639) (xy 31.391468 -358.060059) (xy 31.399486 -358.146588)
			(xy 31.399988 -358.190038) (xy 31.399486 -358.233488) (xy 34.599874 -358.233488) (xy 34.599874 -358.146588)
			(xy 34.607892 -358.060059) (xy 34.62386 -357.974639) (xy 34.647641 -357.891057) (xy 34.679033 -357.810025)
			(xy 34.717767 -357.732236) (xy 34.763514 -357.658352) (xy 34.815883 -357.589005) (xy 34.874427 -357.524785)
			(xy 34.938647 -357.466241) (xy 35.007994 -357.413872) (xy 35.081878 -357.368125) (xy 35.159667 -357.329391)
			(xy 35.240699 -357.297999) (xy 35.324281 -357.274218) (xy 35.409701 -357.25825) (xy 35.49623 -357.250232)
			(xy 35.58313 -357.250232) (xy 35.669659 -357.25825) (xy 35.755079 -357.274218) (xy 35.838661 -357.297999)
			(xy 35.919693 -357.329391) (xy 35.997482 -357.368125) (xy 36.071366 -357.413872) (xy 36.140713 -357.466241)
			(xy 36.204933 -357.524785) (xy 36.263477 -357.589005) (xy 36.315846 -357.658352) (xy 36.361593 -357.732236)
			(xy 36.400327 -357.810025) (xy 36.431719 -357.891057) (xy 36.4555 -357.974639) (xy 36.471468 -358.060059)
			(xy 36.479486 -358.146588) (xy 36.479988 -358.190038) (xy 36.479486 -358.233488) (xy 36.471468 -358.320017)
			(xy 36.4555 -358.405437) (xy 36.431719 -358.489019) (xy 36.400327 -358.570051) (xy 36.361593 -358.64784)
			(xy 36.315846 -358.721724) (xy 36.263477 -358.791071) (xy 36.204933 -358.855291) (xy 36.140713 -358.913835)
			(xy 36.071366 -358.966204) (xy 35.997482 -359.011951) (xy 35.919693 -359.050685) (xy 35.838661 -359.082077)
			(xy 35.755079 -359.105858) (xy 35.669659 -359.121826) (xy 35.58313 -359.129844) (xy 35.49623 -359.129844)
			(xy 35.409701 -359.121826) (xy 35.324281 -359.105858) (xy 35.240699 -359.082077) (xy 35.159667 -359.050685)
			(xy 35.081878 -359.011951) (xy 35.007994 -358.966204) (xy 34.938647 -358.913835) (xy 34.874427 -358.855291)
			(xy 34.815883 -358.791071) (xy 34.763514 -358.721724) (xy 34.717767 -358.64784) (xy 34.679033 -358.570051)
			(xy 34.647641 -358.489019) (xy 34.62386 -358.405437) (xy 34.607892 -358.320017) (xy 34.599874 -358.233488)
			(xy 31.399486 -358.233488) (xy 31.391468 -358.320017) (xy 31.3755 -358.405437) (xy 31.351719 -358.489019)
			(xy 31.320327 -358.570051) (xy 31.281593 -358.64784) (xy 31.235846 -358.721724) (xy 31.183477 -358.791071)
			(xy 31.124933 -358.855291) (xy 31.060713 -358.913835) (xy 30.991366 -358.966204) (xy 30.917482 -359.011951)
			(xy 30.839693 -359.050685) (xy 30.758661 -359.082077) (xy 30.675079 -359.105858) (xy 30.589659 -359.121826)
			(xy 30.50313 -359.129844) (xy 30.41623 -359.129844) (xy 30.329701 -359.121826) (xy 30.244281 -359.105858)
			(xy 30.160699 -359.082077) (xy 30.079667 -359.050685) (xy 30.001878 -359.011951) (xy 29.927994 -358.966204)
			(xy 29.858647 -358.913835) (xy 29.794427 -358.855291) (xy 29.735883 -358.791071) (xy 29.683514 -358.721724)
			(xy 29.637767 -358.64784) (xy 29.599033 -358.570051) (xy 29.567641 -358.489019) (xy 29.54386 -358.405437)
			(xy 29.527892 -358.320017) (xy 29.519874 -358.233488) (xy 21.593048 -358.233488) (xy 21.593048 -360.550968)
			(xy 24.465532 -360.550968) (xy 24.469603 -360.495346) (xy 24.481729 -360.440909) (xy 24.501652 -360.388818)
			(xy 24.528948 -360.340183) (xy 24.563034 -360.29604) (xy 24.603183 -360.257331) (xy 24.648541 -360.22488)
			(xy 24.698141 -360.199379) (xy 24.750925 -360.181372) (xy 24.805768 -360.171242) (xy 24.861502 -360.169205)
			(xy 24.916939 -360.175305) (xy 24.970896 -360.189411) (xy 25.022225 -360.211223) (xy 25.069831 -360.240277)
			(xy 25.112699 -360.275952) (xy 25.149916 -360.317489) (xy 25.180689 -360.364002) (xy 25.204361 -360.414499)
			(xy 25.220429 -360.467906) (xy 25.228549 -360.523082) (xy 25.229058 -360.550968) (xy 26.775916 -360.550968)
			(xy 26.779987 -360.495346) (xy 26.792113 -360.440909) (xy 26.812036 -360.388818) (xy 26.839332 -360.340183)
			(xy 26.873418 -360.29604) (xy 26.913567 -360.257331) (xy 26.958925 -360.22488) (xy 27.008525 -360.199379)
			(xy 27.061309 -360.181372) (xy 27.116152 -360.171242) (xy 27.171886 -360.169205) (xy 27.227323 -360.175305)
			(xy 27.28128 -360.189411) (xy 27.332609 -360.211223) (xy 27.380215 -360.240277) (xy 27.423083 -360.275952)
			(xy 27.4603 -360.317489) (xy 27.491073 -360.364002) (xy 27.514745 -360.414499) (xy 27.530813 -360.467906)
			(xy 27.538933 -360.523082) (xy 27.539442 -360.550968) (xy 27.538933 -360.578854) (xy 27.530813 -360.63403)
			(xy 27.514745 -360.687437) (xy 27.491073 -360.737934) (xy 27.46755 -360.773488) (xy 29.519874 -360.773488)
			(xy 29.519874 -360.686588) (xy 29.527892 -360.600059) (xy 29.54386 -360.514639) (xy 29.567641 -360.431057)
			(xy 29.599033 -360.350025) (xy 29.637767 -360.272236) (xy 29.683514 -360.198352) (xy 29.735883 -360.129005)
			(xy 29.794427 -360.064785) (xy 29.858647 -360.006241) (xy 29.927994 -359.953872) (xy 30.001878 -359.908125)
			(xy 30.079667 -359.869391) (xy 30.160699 -359.837999) (xy 30.244281 -359.814218) (xy 30.329701 -359.79825)
			(xy 30.41623 -359.790232) (xy 30.50313 -359.790232) (xy 30.589659 -359.79825) (xy 30.675079 -359.814218)
			(xy 30.758661 -359.837999) (xy 30.839693 -359.869391) (xy 30.917482 -359.908125) (xy 30.991366 -359.953872)
			(xy 31.060713 -360.006241) (xy 31.124933 -360.064785) (xy 31.183477 -360.129005) (xy 31.235846 -360.198352)
			(xy 31.281593 -360.272236) (xy 31.320327 -360.350025) (xy 31.351719 -360.431057) (xy 31.3755 -360.514639)
			(xy 31.391468 -360.600059) (xy 31.399486 -360.686588) (xy 31.399988 -360.730038) (xy 31.399486 -360.773488)
			(xy 34.599874 -360.773488) (xy 34.599874 -360.686588) (xy 34.607892 -360.600059) (xy 34.62386 -360.514639)
			(xy 34.647641 -360.431057) (xy 34.679033 -360.350025) (xy 34.717767 -360.272236) (xy 34.763514 -360.198352)
			(xy 34.815883 -360.129005) (xy 34.874427 -360.064785) (xy 34.938647 -360.006241) (xy 35.007994 -359.953872)
			(xy 35.081878 -359.908125) (xy 35.159667 -359.869391) (xy 35.240699 -359.837999) (xy 35.324281 -359.814218)
			(xy 35.409701 -359.79825) (xy 35.49623 -359.790232) (xy 35.58313 -359.790232) (xy 35.669659 -359.79825)
			(xy 35.755079 -359.814218) (xy 35.838661 -359.837999) (xy 35.919693 -359.869391) (xy 35.997482 -359.908125)
			(xy 36.071366 -359.953872) (xy 36.140713 -360.006241) (xy 36.204933 -360.064785) (xy 36.263477 -360.129005)
			(xy 36.315846 -360.198352) (xy 36.361593 -360.272236) (xy 36.400327 -360.350025) (xy 36.431719 -360.431057)
			(xy 36.4555 -360.514639) (xy 36.471468 -360.600059) (xy 36.479486 -360.686588) (xy 36.479988 -360.730038)
			(xy 36.479486 -360.773488) (xy 36.471468 -360.860017) (xy 36.4555 -360.945437) (xy 36.431719 -361.029019)
			(xy 36.400327 -361.110051) (xy 36.361593 -361.18784) (xy 36.315846 -361.261724) (xy 36.263477 -361.331071)
			(xy 36.204933 -361.395291) (xy 36.140713 -361.453835) (xy 36.071366 -361.506204) (xy 35.997482 -361.551951)
			(xy 35.919693 -361.590685) (xy 35.838661 -361.622077) (xy 35.755079 -361.645858) (xy 35.669659 -361.661826)
			(xy 35.58313 -361.669844) (xy 35.49623 -361.669844) (xy 35.409701 -361.661826) (xy 35.324281 -361.645858)
			(xy 35.240699 -361.622077) (xy 35.159667 -361.590685) (xy 35.081878 -361.551951) (xy 35.007994 -361.506204)
			(xy 34.938647 -361.453835) (xy 34.874427 -361.395291) (xy 34.815883 -361.331071) (xy 34.763514 -361.261724)
			(xy 34.717767 -361.18784) (xy 34.679033 -361.110051) (xy 34.647641 -361.029019) (xy 34.62386 -360.945437)
			(xy 34.607892 -360.860017) (xy 34.599874 -360.773488) (xy 31.399486 -360.773488) (xy 31.391468 -360.860017)
			(xy 31.3755 -360.945437) (xy 31.351719 -361.029019) (xy 31.320327 -361.110051) (xy 31.281593 -361.18784)
			(xy 31.235846 -361.261724) (xy 31.183477 -361.331071) (xy 31.124933 -361.395291) (xy 31.060713 -361.453835)
			(xy 30.991366 -361.506204) (xy 30.917482 -361.551951) (xy 30.839693 -361.590685) (xy 30.758661 -361.622077)
			(xy 30.675079 -361.645858) (xy 30.589659 -361.661826) (xy 30.50313 -361.669844) (xy 30.41623 -361.669844)
			(xy 30.329701 -361.661826) (xy 30.244281 -361.645858) (xy 30.160699 -361.622077) (xy 30.079667 -361.590685)
			(xy 30.001878 -361.551951) (xy 29.927994 -361.506204) (xy 29.858647 -361.453835) (xy 29.794427 -361.395291)
			(xy 29.735883 -361.331071) (xy 29.683514 -361.261724) (xy 29.637767 -361.18784) (xy 29.599033 -361.110051)
			(xy 29.567641 -361.029019) (xy 29.54386 -360.945437) (xy 29.527892 -360.860017) (xy 29.519874 -360.773488)
			(xy 27.46755 -360.773488) (xy 27.4603 -360.784447) (xy 27.423083 -360.825984) (xy 27.380215 -360.861659)
			(xy 27.332609 -360.890713) (xy 27.28128 -360.912525) (xy 27.227323 -360.926631) (xy 27.171886 -360.932731)
			(xy 27.116152 -360.930694) (xy 27.061309 -360.920564) (xy 27.008525 -360.902557) (xy 26.958925 -360.877056)
			(xy 26.913567 -360.844605) (xy 26.873418 -360.805896) (xy 26.839332 -360.761753) (xy 26.812036 -360.713118)
			(xy 26.792113 -360.661027) (xy 26.779987 -360.60659) (xy 26.775916 -360.550968) (xy 25.229058 -360.550968)
			(xy 25.228549 -360.578854) (xy 25.220429 -360.63403) (xy 25.204361 -360.687437) (xy 25.180689 -360.737934)
			(xy 25.149916 -360.784447) (xy 25.112699 -360.825984) (xy 25.069831 -360.861659) (xy 25.022225 -360.890713)
			(xy 24.970896 -360.912525) (xy 24.916939 -360.926631) (xy 24.861502 -360.932731) (xy 24.805768 -360.930694)
			(xy 24.750925 -360.920564) (xy 24.698141 -360.902557) (xy 24.648541 -360.877056) (xy 24.603183 -360.844605)
			(xy 24.563034 -360.805896) (xy 24.528948 -360.761753) (xy 24.501652 -360.713118) (xy 24.481729 -360.661027)
			(xy 24.469603 -360.60659) (xy 24.465532 -360.550968) (xy 21.593048 -360.550968) (xy 21.593048 -361.78236)
			(xy 24.358344 -361.78236) (xy 24.362415 -361.726738) (xy 24.374541 -361.672301) (xy 24.394464 -361.62021)
			(xy 24.42176 -361.571575) (xy 24.455846 -361.527432) (xy 24.495995 -361.488723) (xy 24.541353 -361.456272)
			(xy 24.590953 -361.430771) (xy 24.643737 -361.412764) (xy 24.69858 -361.402634) (xy 24.754314 -361.400597)
			(xy 24.809751 -361.406697) (xy 24.863708 -361.420803) (xy 24.915037 -361.442615) (xy 24.962643 -361.471669)
			(xy 25.005511 -361.507344) (xy 25.042728 -361.548881) (xy 25.073501 -361.595394) (xy 25.097173 -361.645891)
			(xy 25.113241 -361.699298) (xy 25.121361 -361.754474) (xy 25.12187 -361.78236) (xy 25.121361 -361.810246)
			(xy 25.113241 -361.865422) (xy 25.097173 -361.918829) (xy 25.073501 -361.969326) (xy 25.042728 -362.015839)
			(xy 25.005511 -362.057376) (xy 24.962643 -362.093051) (xy 24.915037 -362.122105) (xy 24.863708 -362.143917)
			(xy 24.809751 -362.158023) (xy 24.754314 -362.164123) (xy 24.69858 -362.162086) (xy 24.643737 -362.151956)
			(xy 24.590953 -362.133949) (xy 24.541353 -362.108448) (xy 24.495995 -362.075997) (xy 24.455846 -362.037288)
			(xy 24.42176 -361.993145) (xy 24.394464 -361.94451) (xy 24.374541 -361.892419) (xy 24.362415 -361.837982)
			(xy 24.358344 -361.78236) (xy 21.593048 -361.78236) (xy 21.593048 -363.313488) (xy 29.519874 -363.313488)
			(xy 29.519874 -363.226588) (xy 29.527892 -363.140059) (xy 29.54386 -363.054639) (xy 29.567641 -362.971057)
			(xy 29.599033 -362.890025) (xy 29.637767 -362.812236) (xy 29.683514 -362.738352) (xy 29.735883 -362.669005)
			(xy 29.794427 -362.604785) (xy 29.858647 -362.546241) (xy 29.927994 -362.493872) (xy 30.001878 -362.448125)
			(xy 30.079667 -362.409391) (xy 30.160699 -362.377999) (xy 30.244281 -362.354218) (xy 30.329701 -362.33825)
			(xy 30.41623 -362.330232) (xy 30.50313 -362.330232) (xy 30.589659 -362.33825) (xy 30.675079 -362.354218)
			(xy 30.758661 -362.377999) (xy 30.839693 -362.409391) (xy 30.917482 -362.448125) (xy 30.991366 -362.493872)
			(xy 31.060713 -362.546241) (xy 31.124933 -362.604785) (xy 31.183477 -362.669005) (xy 31.235846 -362.738352)
			(xy 31.281593 -362.812236) (xy 31.320327 -362.890025) (xy 31.351719 -362.971057) (xy 31.3755 -363.054639)
			(xy 31.391468 -363.140059) (xy 31.399486 -363.226588) (xy 31.399988 -363.270038) (xy 31.399486 -363.313488)
			(xy 34.599874 -363.313488) (xy 34.599874 -363.226588) (xy 34.607892 -363.140059) (xy 34.62386 -363.054639)
			(xy 34.647641 -362.971057) (xy 34.679033 -362.890025) (xy 34.717767 -362.812236) (xy 34.763514 -362.738352)
			(xy 34.815883 -362.669005) (xy 34.874427 -362.604785) (xy 34.938647 -362.546241) (xy 35.007994 -362.493872)
			(xy 35.081878 -362.448125) (xy 35.159667 -362.409391) (xy 35.240699 -362.377999) (xy 35.324281 -362.354218)
			(xy 35.409701 -362.33825) (xy 35.49623 -362.330232) (xy 35.58313 -362.330232) (xy 35.669659 -362.33825)
			(xy 35.755079 -362.354218) (xy 35.838661 -362.377999) (xy 35.919693 -362.409391) (xy 35.997482 -362.448125)
			(xy 36.071366 -362.493872) (xy 36.140713 -362.546241) (xy 36.204933 -362.604785) (xy 36.263477 -362.669005)
			(xy 36.315846 -362.738352) (xy 36.361593 -362.812236) (xy 36.400327 -362.890025) (xy 36.431719 -362.971057)
			(xy 36.4555 -363.054639) (xy 36.471468 -363.140059) (xy 36.479486 -363.226588) (xy 36.479988 -363.270038)
			(xy 36.479486 -363.313488) (xy 36.471468 -363.400017) (xy 36.4555 -363.485437) (xy 36.431719 -363.569019)
			(xy 36.400327 -363.650051) (xy 36.361593 -363.72784) (xy 36.315846 -363.801724) (xy 36.263477 -363.871071)
			(xy 36.204933 -363.935291) (xy 36.140713 -363.993835) (xy 36.071366 -364.046204) (xy 35.997482 -364.091951)
			(xy 35.919693 -364.130685) (xy 35.838661 -364.162077) (xy 35.755079 -364.185858) (xy 35.669659 -364.201826)
			(xy 35.58313 -364.209844) (xy 35.49623 -364.209844) (xy 35.409701 -364.201826) (xy 35.324281 -364.185858)
			(xy 35.240699 -364.162077) (xy 35.159667 -364.130685) (xy 35.081878 -364.091951) (xy 35.007994 -364.046204)
			(xy 34.938647 -363.993835) (xy 34.874427 -363.935291) (xy 34.815883 -363.871071) (xy 34.763514 -363.801724)
			(xy 34.717767 -363.72784) (xy 34.679033 -363.650051) (xy 34.647641 -363.569019) (xy 34.62386 -363.485437)
			(xy 34.607892 -363.400017) (xy 34.599874 -363.313488) (xy 31.399486 -363.313488) (xy 31.391468 -363.400017)
			(xy 31.3755 -363.485437) (xy 31.351719 -363.569019) (xy 31.320327 -363.650051) (xy 31.281593 -363.72784)
			(xy 31.235846 -363.801724) (xy 31.183477 -363.871071) (xy 31.124933 -363.935291) (xy 31.060713 -363.993835)
			(xy 30.991366 -364.046204) (xy 30.917482 -364.091951) (xy 30.839693 -364.130685) (xy 30.758661 -364.162077)
			(xy 30.675079 -364.185858) (xy 30.589659 -364.201826) (xy 30.50313 -364.209844) (xy 30.41623 -364.209844)
			(xy 30.329701 -364.201826) (xy 30.244281 -364.185858) (xy 30.160699 -364.162077) (xy 30.079667 -364.130685)
			(xy 30.001878 -364.091951) (xy 29.927994 -364.046204) (xy 29.858647 -363.993835) (xy 29.794427 -363.935291)
			(xy 29.735883 -363.871071) (xy 29.683514 -363.801724) (xy 29.637767 -363.72784) (xy 29.599033 -363.650051)
			(xy 29.567641 -363.569019) (xy 29.54386 -363.485437) (xy 29.527892 -363.400017) (xy 29.519874 -363.313488)
			(xy 21.593048 -363.313488) (xy 21.593048 -364.246414) (xy 26.78633 -364.246414) (xy 26.790401 -364.190792)
			(xy 26.802527 -364.136355) (xy 26.82245 -364.084264) (xy 26.849746 -364.035629) (xy 26.883832 -363.991486)
			(xy 26.923981 -363.952777) (xy 26.969339 -363.920326) (xy 27.018939 -363.894825) (xy 27.071723 -363.876818)
			(xy 27.126566 -363.866688) (xy 27.1823 -363.864651) (xy 27.237737 -363.870751) (xy 27.291694 -363.884857)
			(xy 27.343023 -363.906669) (xy 27.390629 -363.935723) (xy 27.433497 -363.971398) (xy 27.470714 -364.012935)
			(xy 27.501487 -364.059448) (xy 27.525159 -364.109945) (xy 27.541227 -364.163352) (xy 27.549347 -364.218528)
			(xy 27.549856 -364.246414) (xy 27.549347 -364.2743) (xy 27.541227 -364.329476) (xy 27.525159 -364.382883)
			(xy 27.501487 -364.43338) (xy 27.470714 -364.479893) (xy 27.433497 -364.52143) (xy 27.390629 -364.557105)
			(xy 27.343023 -364.586159) (xy 27.291694 -364.607971) (xy 27.237737 -364.622077) (xy 27.1823 -364.628177)
			(xy 27.126566 -364.62614) (xy 27.071723 -364.61601) (xy 27.018939 -364.598003) (xy 26.969339 -364.572502)
			(xy 26.923981 -364.540051) (xy 26.883832 -364.501342) (xy 26.849746 -364.457199) (xy 26.82245 -364.408564)
			(xy 26.802527 -364.356473) (xy 26.790401 -364.302036) (xy 26.78633 -364.246414) (xy 21.593048 -364.246414)
			(xy 21.593048 -365.50092) (xy 24.254966 -365.50092) (xy 24.259037 -365.445298) (xy 24.271163 -365.390861)
			(xy 24.291086 -365.33877) (xy 24.318382 -365.290135) (xy 24.352468 -365.245992) (xy 24.392617 -365.207283)
			(xy 24.437975 -365.174832) (xy 24.487575 -365.149331) (xy 24.540359 -365.131324) (xy 24.595202 -365.121194)
			(xy 24.650936 -365.119157) (xy 24.706373 -365.125257) (xy 24.76033 -365.139363) (xy 24.811659 -365.161175)
			(xy 24.859265 -365.190229) (xy 24.902133 -365.225904) (xy 24.93935 -365.267441) (xy 24.970123 -365.313954)
			(xy 24.993795 -365.364451) (xy 25.009863 -365.417858) (xy 25.017983 -365.473034) (xy 25.018492 -365.50092)
			(xy 25.017983 -365.528806) (xy 25.009863 -365.583982) (xy 24.993795 -365.637389) (xy 24.970123 -365.687886)
			(xy 24.93935 -365.734399) (xy 24.902133 -365.775936) (xy 24.859265 -365.811611) (xy 24.811659 -365.840665)
			(xy 24.781483 -365.853488) (xy 29.519874 -365.853488) (xy 29.519874 -365.766588) (xy 29.527892 -365.680059)
			(xy 29.54386 -365.594639) (xy 29.567641 -365.511057) (xy 29.599033 -365.430025) (xy 29.637767 -365.352236)
			(xy 29.683514 -365.278352) (xy 29.735883 -365.209005) (xy 29.794427 -365.144785) (xy 29.858647 -365.086241)
			(xy 29.927994 -365.033872) (xy 30.001878 -364.988125) (xy 30.079667 -364.949391) (xy 30.160699 -364.917999)
			(xy 30.244281 -364.894218) (xy 30.329701 -364.87825) (xy 30.41623 -364.870232) (xy 30.50313 -364.870232)
			(xy 30.589659 -364.87825) (xy 30.675079 -364.894218) (xy 30.758661 -364.917999) (xy 30.839693 -364.949391)
			(xy 30.917482 -364.988125) (xy 30.991366 -365.033872) (xy 31.060713 -365.086241) (xy 31.124933 -365.144785)
			(xy 31.183477 -365.209005) (xy 31.235846 -365.278352) (xy 31.281593 -365.352236) (xy 31.320327 -365.430025)
			(xy 31.351719 -365.511057) (xy 31.3755 -365.594639) (xy 31.391468 -365.680059) (xy 31.399486 -365.766588)
			(xy 31.399988 -365.810038) (xy 31.399486 -365.853488) (xy 34.599874 -365.853488) (xy 34.599874 -365.766588)
			(xy 34.607892 -365.680059) (xy 34.62386 -365.594639) (xy 34.647641 -365.511057) (xy 34.679033 -365.430025)
			(xy 34.717767 -365.352236) (xy 34.763514 -365.278352) (xy 34.815883 -365.209005) (xy 34.874427 -365.144785)
			(xy 34.938647 -365.086241) (xy 35.007994 -365.033872) (xy 35.081878 -364.988125) (xy 35.159667 -364.949391)
			(xy 35.240699 -364.917999) (xy 35.324281 -364.894218) (xy 35.409701 -364.87825) (xy 35.49623 -364.870232)
			(xy 35.58313 -364.870232) (xy 35.669659 -364.87825) (xy 35.755079 -364.894218) (xy 35.838661 -364.917999)
			(xy 35.919693 -364.949391) (xy 35.997482 -364.988125) (xy 36.071366 -365.033872) (xy 36.140713 -365.086241)
			(xy 36.204933 -365.144785) (xy 36.263477 -365.209005) (xy 36.315846 -365.278352) (xy 36.361593 -365.352236)
			(xy 36.400327 -365.430025) (xy 36.431719 -365.511057) (xy 36.4555 -365.594639) (xy 36.471468 -365.680059)
			(xy 36.479486 -365.766588) (xy 36.479988 -365.810038) (xy 36.479486 -365.853488) (xy 36.471468 -365.940017)
			(xy 36.4555 -366.025437) (xy 36.431719 -366.109019) (xy 36.400327 -366.190051) (xy 36.361593 -366.26784)
			(xy 36.315846 -366.341724) (xy 36.263477 -366.411071) (xy 36.204933 -366.475291) (xy 36.140713 -366.533835)
			(xy 36.071366 -366.586204) (xy 35.997482 -366.631951) (xy 35.919693 -366.670685) (xy 35.838661 -366.702077)
			(xy 35.755079 -366.725858) (xy 35.669659 -366.741826) (xy 35.58313 -366.749844) (xy 35.49623 -366.749844)
			(xy 35.409701 -366.741826) (xy 35.324281 -366.725858) (xy 35.240699 -366.702077) (xy 35.159667 -366.670685)
			(xy 35.081878 -366.631951) (xy 35.007994 -366.586204) (xy 34.938647 -366.533835) (xy 34.874427 -366.475291)
			(xy 34.815883 -366.411071) (xy 34.763514 -366.341724) (xy 34.717767 -366.26784) (xy 34.679033 -366.190051)
			(xy 34.647641 -366.109019) (xy 34.62386 -366.025437) (xy 34.607892 -365.940017) (xy 34.599874 -365.853488)
			(xy 31.399486 -365.853488) (xy 31.391468 -365.940017) (xy 31.3755 -366.025437) (xy 31.351719 -366.109019)
			(xy 31.320327 -366.190051) (xy 31.281593 -366.26784) (xy 31.235846 -366.341724) (xy 31.183477 -366.411071)
			(xy 31.124933 -366.475291) (xy 31.060713 -366.533835) (xy 30.991366 -366.586204) (xy 30.917482 -366.631951)
			(xy 30.839693 -366.670685) (xy 30.758661 -366.702077) (xy 30.675079 -366.725858) (xy 30.589659 -366.741826)
			(xy 30.50313 -366.749844) (xy 30.41623 -366.749844) (xy 30.329701 -366.741826) (xy 30.244281 -366.725858)
			(xy 30.160699 -366.702077) (xy 30.079667 -366.670685) (xy 30.001878 -366.631951) (xy 29.927994 -366.586204)
			(xy 29.858647 -366.533835) (xy 29.794427 -366.475291) (xy 29.735883 -366.411071) (xy 29.683514 -366.341724)
			(xy 29.637767 -366.26784) (xy 29.599033 -366.190051) (xy 29.567641 -366.109019) (xy 29.54386 -366.025437)
			(xy 29.527892 -365.940017) (xy 29.519874 -365.853488) (xy 24.781483 -365.853488) (xy 24.76033 -365.862477)
			(xy 24.706373 -365.876583) (xy 24.650936 -365.882683) (xy 24.595202 -365.880646) (xy 24.540359 -365.870516)
			(xy 24.487575 -365.852509) (xy 24.437975 -365.827008) (xy 24.392617 -365.794557) (xy 24.352468 -365.755848)
			(xy 24.318382 -365.711705) (xy 24.291086 -365.66307) (xy 24.271163 -365.610979) (xy 24.259037 -365.556542)
			(xy 24.254966 -365.50092) (xy 21.593048 -365.50092) (xy 21.593048 -366.710722) (xy 24.254204 -366.710722)
			(xy 24.258275 -366.6551) (xy 24.270401 -366.600663) (xy 24.290324 -366.548572) (xy 24.31762 -366.499937)
			(xy 24.351706 -366.455794) (xy 24.391855 -366.417085) (xy 24.437213 -366.384634) (xy 24.486813 -366.359133)
			(xy 24.539597 -366.341126) (xy 24.59444 -366.330996) (xy 24.650174 -366.328959) (xy 24.705611 -366.335059)
			(xy 24.759568 -366.349165) (xy 24.810897 -366.370977) (xy 24.858503 -366.400031) (xy 24.901371 -366.435706)
			(xy 24.938588 -366.477243) (xy 24.969361 -366.523756) (xy 24.993033 -366.574253) (xy 25.009101 -366.62766)
			(xy 25.017221 -366.682836) (xy 25.01773 -366.710722) (xy 25.017221 -366.738608) (xy 25.009101 -366.793784)
			(xy 24.993033 -366.847191) (xy 24.969361 -366.897688) (xy 24.94921 -366.928146) (xy 26.735784 -366.928146)
			(xy 26.739855 -366.872524) (xy 26.751981 -366.818087) (xy 26.771904 -366.765996) (xy 26.7992 -366.717361)
			(xy 26.833286 -366.673218) (xy 26.873435 -366.634509) (xy 26.918793 -366.602058) (xy 26.968393 -366.576557)
			(xy 27.021177 -366.55855) (xy 27.07602 -366.54842) (xy 27.131754 -366.546383) (xy 27.187191 -366.552483)
			(xy 27.241148 -366.566589) (xy 27.292477 -366.588401) (xy 27.340083 -366.617455) (xy 27.382951 -366.65313)
			(xy 27.420168 -366.694667) (xy 27.450941 -366.74118) (xy 27.474613 -366.791677) (xy 27.490681 -366.845084)
			(xy 27.498801 -366.90026) (xy 27.49931 -366.928146) (xy 27.498801 -366.956032) (xy 27.490681 -367.011208)
			(xy 27.474613 -367.064615) (xy 27.450941 -367.115112) (xy 27.420168 -367.161625) (xy 27.382951 -367.203162)
			(xy 27.340083 -367.238837) (xy 27.292477 -367.267891) (xy 27.241148 -367.289703) (xy 27.187191 -367.303809)
			(xy 27.131754 -367.309909) (xy 27.07602 -367.307872) (xy 27.021177 -367.297742) (xy 26.968393 -367.279735)
			(xy 26.918793 -367.254234) (xy 26.873435 -367.221783) (xy 26.833286 -367.183074) (xy 26.7992 -367.138931)
			(xy 26.771904 -367.090296) (xy 26.751981 -367.038205) (xy 26.739855 -366.983768) (xy 26.735784 -366.928146)
			(xy 24.94921 -366.928146) (xy 24.938588 -366.944201) (xy 24.901371 -366.985738) (xy 24.858503 -367.021413)
			(xy 24.810897 -367.050467) (xy 24.759568 -367.072279) (xy 24.705611 -367.086385) (xy 24.650174 -367.092485)
			(xy 24.59444 -367.090448) (xy 24.539597 -367.080318) (xy 24.486813 -367.062311) (xy 24.437213 -367.03681)
			(xy 24.391855 -367.004359) (xy 24.351706 -366.96565) (xy 24.31762 -366.921507) (xy 24.290324 -366.872872)
			(xy 24.270401 -366.820781) (xy 24.258275 -366.766344) (xy 24.254204 -366.710722) (xy 21.593048 -366.710722)
			(xy 21.593048 -367.771426) (xy 24.374092 -367.771426) (xy 24.378163 -367.715804) (xy 24.390289 -367.661367)
			(xy 24.410212 -367.609276) (xy 24.437508 -367.560641) (xy 24.471594 -367.516498) (xy 24.511743 -367.477789)
			(xy 24.557101 -367.445338) (xy 24.606701 -367.419837) (xy 24.659485 -367.40183) (xy 24.714328 -367.3917)
			(xy 24.770062 -367.389663) (xy 24.825499 -367.395763) (xy 24.879456 -367.409869) (xy 24.930785 -367.431681)
			(xy 24.978391 -367.460735) (xy 25.021259 -367.49641) (xy 25.058476 -367.537947) (xy 25.089249 -367.58446)
			(xy 25.112921 -367.634957) (xy 25.128989 -367.688364) (xy 25.137109 -367.74354) (xy 25.137618 -367.771426)
			(xy 25.137109 -367.799312) (xy 25.128989 -367.854488) (xy 25.112921 -367.907895) (xy 25.089249 -367.958392)
			(xy 25.058476 -368.004905) (xy 25.021259 -368.046442) (xy 24.978391 -368.082117) (xy 24.930785 -368.111171)
			(xy 24.879456 -368.132983) (xy 24.825499 -368.147089) (xy 24.770062 -368.153189) (xy 24.714328 -368.151152)
			(xy 24.659485 -368.141022) (xy 24.606701 -368.123015) (xy 24.557101 -368.097514) (xy 24.511743 -368.065063)
			(xy 24.471594 -368.026354) (xy 24.437508 -367.982211) (xy 24.410212 -367.933576) (xy 24.390289 -367.881485)
			(xy 24.378163 -367.827048) (xy 24.374092 -367.771426) (xy 21.593048 -367.771426) (xy 21.593048 -368.393488)
			(xy 29.519874 -368.393488) (xy 29.519874 -368.306588) (xy 29.527892 -368.220059) (xy 29.54386 -368.134639)
			(xy 29.567641 -368.051057) (xy 29.599033 -367.970025) (xy 29.637767 -367.892236) (xy 29.683514 -367.818352)
			(xy 29.735883 -367.749005) (xy 29.794427 -367.684785) (xy 29.858647 -367.626241) (xy 29.927994 -367.573872)
			(xy 30.001878 -367.528125) (xy 30.079667 -367.489391) (xy 30.160699 -367.457999) (xy 30.244281 -367.434218)
			(xy 30.329701 -367.41825) (xy 30.41623 -367.410232) (xy 30.50313 -367.410232) (xy 30.589659 -367.41825)
			(xy 30.675079 -367.434218) (xy 30.758661 -367.457999) (xy 30.839693 -367.489391) (xy 30.917482 -367.528125)
			(xy 30.991366 -367.573872) (xy 31.060713 -367.626241) (xy 31.124933 -367.684785) (xy 31.183477 -367.749005)
			(xy 31.235846 -367.818352) (xy 31.281593 -367.892236) (xy 31.320327 -367.970025) (xy 31.351719 -368.051057)
			(xy 31.3755 -368.134639) (xy 31.391468 -368.220059) (xy 31.399486 -368.306588) (xy 31.399988 -368.350038)
			(xy 31.399486 -368.393488) (xy 34.599874 -368.393488) (xy 34.599874 -368.306588) (xy 34.607892 -368.220059)
			(xy 34.62386 -368.134639) (xy 34.647641 -368.051057) (xy 34.679033 -367.970025) (xy 34.717767 -367.892236)
			(xy 34.763514 -367.818352) (xy 34.815883 -367.749005) (xy 34.874427 -367.684785) (xy 34.938647 -367.626241)
			(xy 35.007994 -367.573872) (xy 35.081878 -367.528125) (xy 35.159667 -367.489391) (xy 35.240699 -367.457999)
			(xy 35.324281 -367.434218) (xy 35.409701 -367.41825) (xy 35.49623 -367.410232) (xy 35.58313 -367.410232)
			(xy 35.669659 -367.41825) (xy 35.755079 -367.434218) (xy 35.838661 -367.457999) (xy 35.919693 -367.489391)
			(xy 35.997482 -367.528125) (xy 36.071366 -367.573872) (xy 36.140713 -367.626241) (xy 36.204933 -367.684785)
			(xy 36.263477 -367.749005) (xy 36.315846 -367.818352) (xy 36.361593 -367.892236) (xy 36.400327 -367.970025)
			(xy 36.431719 -368.051057) (xy 36.4555 -368.134639) (xy 36.471468 -368.220059) (xy 36.479486 -368.306588)
			(xy 36.479988 -368.350038) (xy 36.479486 -368.393488) (xy 36.471468 -368.480017) (xy 36.4555 -368.565437)
			(xy 36.451166 -368.58067) (xy 40.05275 -368.58067) (xy 40.056821 -368.525048) (xy 40.068947 -368.470611)
			(xy 40.08887 -368.41852) (xy 40.116166 -368.369885) (xy 40.150252 -368.325742) (xy 40.190401 -368.287033)
			(xy 40.235759 -368.254582) (xy 40.285359 -368.229081) (xy 40.338143 -368.211074) (xy 40.392986 -368.200944)
			(xy 40.44872 -368.198907) (xy 40.504157 -368.205007) (xy 40.558114 -368.219113) (xy 40.609443 -368.240925)
			(xy 40.657049 -368.269979) (xy 40.699917 -368.305654) (xy 40.737134 -368.347191) (xy 40.767907 -368.393704)
			(xy 40.791579 -368.444201) (xy 40.807647 -368.497608) (xy 40.815767 -368.552784) (xy 40.816276 -368.58067)
			(xy 40.815767 -368.608556) (xy 40.807647 -368.663732) (xy 40.791579 -368.717139) (xy 40.767907 -368.767636)
			(xy 40.737134 -368.814149) (xy 40.699917 -368.855686) (xy 40.657049 -368.891361) (xy 40.609443 -368.920415)
			(xy 40.558114 -368.942227) (xy 40.504157 -368.956333) (xy 40.44872 -368.962433) (xy 40.392986 -368.960396)
			(xy 40.338143 -368.950266) (xy 40.285359 -368.932259) (xy 40.235759 -368.906758) (xy 40.190401 -368.874307)
			(xy 40.150252 -368.835598) (xy 40.116166 -368.791455) (xy 40.08887 -368.74282) (xy 40.068947 -368.690729)
			(xy 40.056821 -368.636292) (xy 40.05275 -368.58067) (xy 36.451166 -368.58067) (xy 36.431719 -368.649019)
			(xy 36.400327 -368.730051) (xy 36.361593 -368.80784) (xy 36.315846 -368.881724) (xy 36.263477 -368.951071)
			(xy 36.204933 -369.015291) (xy 36.140713 -369.073835) (xy 36.071366 -369.126204) (xy 35.997482 -369.171951)
			(xy 35.919693 -369.210685) (xy 35.838661 -369.242077) (xy 35.755079 -369.265858) (xy 35.669659 -369.281826)
			(xy 35.58313 -369.289844) (xy 35.49623 -369.289844) (xy 35.409701 -369.281826) (xy 35.324281 -369.265858)
			(xy 35.240699 -369.242077) (xy 35.159667 -369.210685) (xy 35.081878 -369.171951) (xy 35.007994 -369.126204)
			(xy 34.938647 -369.073835) (xy 34.874427 -369.015291) (xy 34.815883 -368.951071) (xy 34.763514 -368.881724)
			(xy 34.717767 -368.80784) (xy 34.679033 -368.730051) (xy 34.647641 -368.649019) (xy 34.62386 -368.565437)
			(xy 34.607892 -368.480017) (xy 34.599874 -368.393488) (xy 31.399486 -368.393488) (xy 31.391468 -368.480017)
			(xy 31.3755 -368.565437) (xy 31.351719 -368.649019) (xy 31.320327 -368.730051) (xy 31.281593 -368.80784)
			(xy 31.235846 -368.881724) (xy 31.183477 -368.951071) (xy 31.124933 -369.015291) (xy 31.060713 -369.073835)
			(xy 30.991366 -369.126204) (xy 30.917482 -369.171951) (xy 30.839693 -369.210685) (xy 30.758661 -369.242077)
			(xy 30.675079 -369.265858) (xy 30.589659 -369.281826) (xy 30.50313 -369.289844) (xy 30.41623 -369.289844)
			(xy 30.329701 -369.281826) (xy 30.244281 -369.265858) (xy 30.160699 -369.242077) (xy 30.079667 -369.210685)
			(xy 30.001878 -369.171951) (xy 29.927994 -369.126204) (xy 29.858647 -369.073835) (xy 29.794427 -369.015291)
			(xy 29.735883 -368.951071) (xy 29.683514 -368.881724) (xy 29.637767 -368.80784) (xy 29.599033 -368.730051)
			(xy 29.567641 -368.649019) (xy 29.54386 -368.565437) (xy 29.527892 -368.480017) (xy 29.519874 -368.393488)
			(xy 21.593048 -368.393488) (xy 21.593048 -369.143534) (xy 23.807926 -369.143534) (xy 23.811997 -369.087912)
			(xy 23.824123 -369.033475) (xy 23.844046 -368.981384) (xy 23.871342 -368.932749) (xy 23.905428 -368.888606)
			(xy 23.945577 -368.849897) (xy 23.990935 -368.817446) (xy 24.040535 -368.791945) (xy 24.093319 -368.773938)
			(xy 24.148162 -368.763808) (xy 24.203896 -368.761771) (xy 24.259333 -368.767871) (xy 24.31329 -368.781977)
			(xy 24.364619 -368.803789) (xy 24.412225 -368.832843) (xy 24.455093 -368.868518) (xy 24.49231 -368.910055)
			(xy 24.523083 -368.956568) (xy 24.530952 -368.973354) (xy 26.797506 -368.973354) (xy 26.801577 -368.917732)
			(xy 26.813703 -368.863295) (xy 26.833626 -368.811204) (xy 26.860922 -368.762569) (xy 26.895008 -368.718426)
			(xy 26.935157 -368.679717) (xy 26.980515 -368.647266) (xy 27.030115 -368.621765) (xy 27.082899 -368.603758)
			(xy 27.137742 -368.593628) (xy 27.193476 -368.591591) (xy 27.248913 -368.597691) (xy 27.30287 -368.611797)
			(xy 27.354199 -368.633609) (xy 27.401805 -368.662663) (xy 27.444673 -368.698338) (xy 27.48189 -368.739875)
			(xy 27.512663 -368.786388) (xy 27.536335 -368.836885) (xy 27.552403 -368.890292) (xy 27.560523 -368.945468)
			(xy 27.561032 -368.973354) (xy 27.560523 -369.00124) (xy 27.552403 -369.056416) (xy 27.536335 -369.109823)
			(xy 27.512663 -369.16032) (xy 27.48189 -369.206833) (xy 27.444673 -369.24837) (xy 27.401805 -369.284045)
			(xy 27.354199 -369.313099) (xy 27.30287 -369.334911) (xy 27.248913 -369.349017) (xy 27.193476 -369.355117)
			(xy 27.137742 -369.35308) (xy 27.082899 -369.34295) (xy 27.030115 -369.324943) (xy 26.980515 -369.299442)
			(xy 26.935157 -369.266991) (xy 26.895008 -369.228282) (xy 26.860922 -369.184139) (xy 26.833626 -369.135504)
			(xy 26.813703 -369.083413) (xy 26.801577 -369.028976) (xy 26.797506 -368.973354) (xy 24.530952 -368.973354)
			(xy 24.546755 -369.007065) (xy 24.562823 -369.060472) (xy 24.570943 -369.115648) (xy 24.571452 -369.143534)
			(xy 24.570943 -369.17142) (xy 24.562823 -369.226596) (xy 24.546755 -369.280003) (xy 24.523083 -369.3305)
			(xy 24.49231 -369.377013) (xy 24.455093 -369.41855) (xy 24.412225 -369.454225) (xy 24.364619 -369.483279)
			(xy 24.31329 -369.505091) (xy 24.259333 -369.519197) (xy 24.203896 -369.525297) (xy 24.148162 -369.52326)
			(xy 24.093319 -369.51313) (xy 24.040535 -369.495123) (xy 23.990935 -369.469622) (xy 23.945577 -369.437171)
			(xy 23.905428 -369.398462) (xy 23.871342 -369.354319) (xy 23.844046 -369.305684) (xy 23.824123 -369.253593)
			(xy 23.811997 -369.199156) (xy 23.807926 -369.143534) (xy 21.593048 -369.143534) (xy 21.593048 -370.933488)
			(xy 29.519874 -370.933488) (xy 29.519874 -370.846588) (xy 29.527892 -370.760059) (xy 29.54386 -370.674639)
			(xy 29.567641 -370.591057) (xy 29.599033 -370.510025) (xy 29.637767 -370.432236) (xy 29.683514 -370.358352)
			(xy 29.735883 -370.289005) (xy 29.794427 -370.224785) (xy 29.858647 -370.166241) (xy 29.927994 -370.113872)
			(xy 30.001878 -370.068125) (xy 30.079667 -370.029391) (xy 30.160699 -369.997999) (xy 30.244281 -369.974218)
			(xy 30.329701 -369.95825) (xy 30.41623 -369.950232) (xy 30.50313 -369.950232) (xy 30.589659 -369.95825)
			(xy 30.675079 -369.974218) (xy 30.758661 -369.997999) (xy 30.839693 -370.029391) (xy 30.917482 -370.068125)
			(xy 30.991366 -370.113872) (xy 31.060713 -370.166241) (xy 31.124933 -370.224785) (xy 31.183477 -370.289005)
			(xy 31.235846 -370.358352) (xy 31.281593 -370.432236) (xy 31.320327 -370.510025) (xy 31.351719 -370.591057)
			(xy 31.3755 -370.674639) (xy 31.391468 -370.760059) (xy 31.399486 -370.846588) (xy 31.399988 -370.890038)
			(xy 31.399486 -370.933488) (xy 34.599874 -370.933488) (xy 34.599874 -370.846588) (xy 34.607892 -370.760059)
			(xy 34.62386 -370.674639) (xy 34.647641 -370.591057) (xy 34.679033 -370.510025) (xy 34.717767 -370.432236)
			(xy 34.763514 -370.358352) (xy 34.815883 -370.289005) (xy 34.874427 -370.224785) (xy 34.938647 -370.166241)
			(xy 35.007994 -370.113872) (xy 35.081878 -370.068125) (xy 35.159667 -370.029391) (xy 35.240699 -369.997999)
			(xy 35.324281 -369.974218) (xy 35.409701 -369.95825) (xy 35.49623 -369.950232) (xy 35.58313 -369.950232)
			(xy 35.669659 -369.95825) (xy 35.755079 -369.974218) (xy 35.838661 -369.997999) (xy 35.919693 -370.029391)
			(xy 35.997482 -370.068125) (xy 36.04789 -370.099336) (xy 41.045128 -370.099336) (xy 41.049199 -370.043714)
			(xy 41.061325 -369.989277) (xy 41.081248 -369.937186) (xy 41.108544 -369.888551) (xy 41.14263 -369.844408)
			(xy 41.182779 -369.805699) (xy 41.228137 -369.773248) (xy 41.277737 -369.747747) (xy 41.330521 -369.72974)
			(xy 41.385364 -369.71961) (xy 41.441098 -369.717573) (xy 41.496535 -369.723673) (xy 41.550492 -369.737779)
			(xy 41.601821 -369.759591) (xy 41.649427 -369.788645) (xy 41.692295 -369.82432) (xy 41.729512 -369.865857)
			(xy 41.760285 -369.91237) (xy 41.783957 -369.962867) (xy 41.800025 -370.016274) (xy 41.808145 -370.07145)
			(xy 41.808654 -370.099336) (xy 41.808145 -370.127222) (xy 41.800025 -370.182398) (xy 41.783957 -370.235805)
			(xy 41.760285 -370.286302) (xy 41.729512 -370.332815) (xy 41.692295 -370.374352) (xy 41.649427 -370.410027)
			(xy 41.601821 -370.439081) (xy 41.550492 -370.460893) (xy 41.496535 -370.474999) (xy 41.441098 -370.481099)
			(xy 41.385364 -370.479062) (xy 41.330521 -370.468932) (xy 41.277737 -370.450925) (xy 41.228137 -370.425424)
			(xy 41.182779 -370.392973) (xy 41.14263 -370.354264) (xy 41.108544 -370.310121) (xy 41.081248 -370.261486)
			(xy 41.061325 -370.209395) (xy 41.049199 -370.154958) (xy 41.045128 -370.099336) (xy 36.04789 -370.099336)
			(xy 36.071366 -370.113872) (xy 36.140713 -370.166241) (xy 36.204933 -370.224785) (xy 36.263477 -370.289005)
			(xy 36.315846 -370.358352) (xy 36.361593 -370.432236) (xy 36.400327 -370.510025) (xy 36.431719 -370.591057)
			(xy 36.4555 -370.674639) (xy 36.471468 -370.760059) (xy 36.479486 -370.846588) (xy 36.479988 -370.890038)
			(xy 36.479486 -370.933488) (xy 36.471468 -371.020017) (xy 36.4555 -371.105437) (xy 36.431719 -371.189019)
			(xy 36.400327 -371.270051) (xy 36.361593 -371.34784) (xy 36.315846 -371.421724) (xy 36.263477 -371.491071)
			(xy 36.243163 -371.513354) (xy 40.899078 -371.513354) (xy 40.903149 -371.457732) (xy 40.915275 -371.403295)
			(xy 40.935198 -371.351204) (xy 40.962494 -371.302569) (xy 40.99658 -371.258426) (xy 41.036729 -371.219717)
			(xy 41.082087 -371.187266) (xy 41.131687 -371.161765) (xy 41.184471 -371.143758) (xy 41.239314 -371.133628)
			(xy 41.295048 -371.131591) (xy 41.350485 -371.137691) (xy 41.404442 -371.151797) (xy 41.455771 -371.173609)
			(xy 41.503377 -371.202663) (xy 41.546245 -371.238338) (xy 41.583462 -371.279875) (xy 41.614235 -371.326388)
			(xy 41.637907 -371.376885) (xy 41.653975 -371.430292) (xy 41.662095 -371.485468) (xy 41.662604 -371.513354)
			(xy 41.662095 -371.54124) (xy 41.653975 -371.596416) (xy 41.637907 -371.649823) (xy 41.614235 -371.70032)
			(xy 41.583462 -371.746833) (xy 41.546245 -371.78837) (xy 41.503377 -371.824045) (xy 41.455771 -371.853099)
			(xy 41.404442 -371.874911) (xy 41.350485 -371.889017) (xy 41.295048 -371.895117) (xy 41.239314 -371.89308)
			(xy 41.184471 -371.88295) (xy 41.131687 -371.864943) (xy 41.082087 -371.839442) (xy 41.036729 -371.806991)
			(xy 40.99658 -371.768282) (xy 40.962494 -371.724139) (xy 40.935198 -371.675504) (xy 40.915275 -371.623413)
			(xy 40.903149 -371.568976) (xy 40.899078 -371.513354) (xy 36.243163 -371.513354) (xy 36.204933 -371.555291)
			(xy 36.140713 -371.613835) (xy 36.071366 -371.666204) (xy 35.997482 -371.711951) (xy 35.919693 -371.750685)
			(xy 35.838661 -371.782077) (xy 35.755079 -371.805858) (xy 35.669659 -371.821826) (xy 35.58313 -371.829844)
			(xy 35.49623 -371.829844) (xy 35.409701 -371.821826) (xy 35.324281 -371.805858) (xy 35.240699 -371.782077)
			(xy 35.159667 -371.750685) (xy 35.081878 -371.711951) (xy 35.007994 -371.666204) (xy 34.938647 -371.613835)
			(xy 34.874427 -371.555291) (xy 34.815883 -371.491071) (xy 34.763514 -371.421724) (xy 34.717767 -371.34784)
			(xy 34.679033 -371.270051) (xy 34.647641 -371.189019) (xy 34.62386 -371.105437) (xy 34.607892 -371.020017)
			(xy 34.599874 -370.933488) (xy 31.399486 -370.933488) (xy 31.391468 -371.020017) (xy 31.3755 -371.105437)
			(xy 31.351719 -371.189019) (xy 31.320327 -371.270051) (xy 31.281593 -371.34784) (xy 31.235846 -371.421724)
			(xy 31.183477 -371.491071) (xy 31.124933 -371.555291) (xy 31.060713 -371.613835) (xy 30.991366 -371.666204)
			(xy 30.917482 -371.711951) (xy 30.839693 -371.750685) (xy 30.758661 -371.782077) (xy 30.675079 -371.805858)
			(xy 30.589659 -371.821826) (xy 30.50313 -371.829844) (xy 30.41623 -371.829844) (xy 30.329701 -371.821826)
			(xy 30.244281 -371.805858) (xy 30.160699 -371.782077) (xy 30.079667 -371.750685) (xy 30.001878 -371.711951)
			(xy 29.927994 -371.666204) (xy 29.858647 -371.613835) (xy 29.794427 -371.555291) (xy 29.735883 -371.491071)
			(xy 29.683514 -371.421724) (xy 29.637767 -371.34784) (xy 29.599033 -371.270051) (xy 29.567641 -371.189019)
			(xy 29.54386 -371.105437) (xy 29.527892 -371.020017) (xy 29.519874 -370.933488) (xy 21.593048 -370.933488)
			(xy 21.593048 -371.293644) (xy 21.593582 -371.310263) (xy 21.602165 -371.342375) (xy 21.618763 -371.371172)
			(xy 21.630132 -371.383306) (xy 21.947644 -371.700806) (xy 27.195778 -371.700806) (xy 27.199849 -371.645184)
			(xy 27.211975 -371.590747) (xy 27.231898 -371.538656) (xy 27.259194 -371.490021) (xy 27.29328 -371.445878)
			(xy 27.333429 -371.407169) (xy 27.378787 -371.374718) (xy 27.428387 -371.349217) (xy 27.481171 -371.33121)
			(xy 27.536014 -371.32108) (xy 27.591748 -371.319043) (xy 27.647185 -371.325143) (xy 27.701142 -371.339249)
			(xy 27.752471 -371.361061) (xy 27.800077 -371.390115) (xy 27.842945 -371.42579) (xy 27.880162 -371.467327)
			(xy 27.910935 -371.51384) (xy 27.934607 -371.564337) (xy 27.950675 -371.617744) (xy 27.958795 -371.67292)
			(xy 27.959304 -371.700806) (xy 27.958795 -371.728692) (xy 27.950675 -371.783868) (xy 27.934607 -371.837275)
			(xy 27.910935 -371.887772) (xy 27.880162 -371.934285) (xy 27.842945 -371.975822) (xy 27.800077 -372.011497)
			(xy 27.752471 -372.040551) (xy 27.701142 -372.062363) (xy 27.647185 -372.076469) (xy 27.591748 -372.082569)
			(xy 27.536014 -372.080532) (xy 27.481171 -372.070402) (xy 27.428387 -372.052395) (xy 27.378787 -372.026894)
			(xy 27.333429 -371.994443) (xy 27.29328 -371.955734) (xy 27.259194 -371.911591) (xy 27.231898 -371.862956)
			(xy 27.211975 -371.810865) (xy 27.199849 -371.756428) (xy 27.195778 -371.700806) (xy 21.947644 -371.700806)
			(xy 23.720394 -373.473488) (xy 29.519874 -373.473488) (xy 29.519874 -373.386588) (xy 29.527892 -373.300059)
			(xy 29.54386 -373.214639) (xy 29.567641 -373.131057) (xy 29.599033 -373.050025) (xy 29.637767 -372.972236)
			(xy 29.683514 -372.898352) (xy 29.735883 -372.829005) (xy 29.794427 -372.764785) (xy 29.858647 -372.706241)
			(xy 29.927994 -372.653872) (xy 30.001878 -372.608125) (xy 30.079667 -372.569391) (xy 30.160699 -372.537999)
			(xy 30.244281 -372.514218) (xy 30.329701 -372.49825) (xy 30.41623 -372.490232) (xy 30.50313 -372.490232)
			(xy 30.589659 -372.49825) (xy 30.675079 -372.514218) (xy 30.758661 -372.537999) (xy 30.839693 -372.569391)
			(xy 30.917482 -372.608125) (xy 30.991366 -372.653872) (xy 31.060713 -372.706241) (xy 31.124933 -372.764785)
			(xy 31.183477 -372.829005) (xy 31.235846 -372.898352) (xy 31.281593 -372.972236) (xy 31.320327 -373.050025)
			(xy 31.351719 -373.131057) (xy 31.3755 -373.214639) (xy 31.391468 -373.300059) (xy 31.399486 -373.386588)
			(xy 31.399988 -373.430038) (xy 31.399486 -373.473488) (xy 34.599874 -373.473488) (xy 34.599874 -373.386588)
			(xy 34.607892 -373.300059) (xy 34.62386 -373.214639) (xy 34.647641 -373.131057) (xy 34.679033 -373.050025)
			(xy 34.717767 -372.972236) (xy 34.763514 -372.898352) (xy 34.815883 -372.829005) (xy 34.874427 -372.764785)
			(xy 34.938647 -372.706241) (xy 35.007994 -372.653872) (xy 35.081878 -372.608125) (xy 35.159667 -372.569391)
			(xy 35.240699 -372.537999) (xy 35.324281 -372.514218) (xy 35.409701 -372.49825) (xy 35.49623 -372.490232)
			(xy 35.58313 -372.490232) (xy 35.669659 -372.49825) (xy 35.755079 -372.514218) (xy 35.838661 -372.537999)
			(xy 35.919693 -372.569391) (xy 35.997482 -372.608125) (xy 36.071366 -372.653872) (xy 36.140713 -372.706241)
			(xy 36.204933 -372.764785) (xy 36.263477 -372.829005) (xy 36.315846 -372.898352) (xy 36.361593 -372.972236)
			(xy 36.400327 -373.050025) (xy 36.431719 -373.131057) (xy 36.4555 -373.214639) (xy 36.471468 -373.300059)
			(xy 36.479486 -373.386588) (xy 36.479988 -373.430038) (xy 36.479486 -373.473488) (xy 36.471468 -373.560017)
			(xy 36.4555 -373.645437) (xy 36.431719 -373.729019) (xy 36.431138 -373.73052) (xy 40.82745 -373.73052)
			(xy 40.831521 -373.674898) (xy 40.843647 -373.620461) (xy 40.86357 -373.56837) (xy 40.890866 -373.519735)
			(xy 40.924952 -373.475592) (xy 40.965101 -373.436883) (xy 41.010459 -373.404432) (xy 41.060059 -373.378931)
			(xy 41.112843 -373.360924) (xy 41.167686 -373.350794) (xy 41.22342 -373.348757) (xy 41.278857 -373.354857)
			(xy 41.332814 -373.368963) (xy 41.384143 -373.390775) (xy 41.431749 -373.419829) (xy 41.474617 -373.455504)
			(xy 41.511834 -373.497041) (xy 41.542607 -373.543554) (xy 41.566279 -373.594051) (xy 41.582347 -373.647458)
			(xy 41.590467 -373.702634) (xy 41.590976 -373.73052) (xy 41.590467 -373.758406) (xy 41.582347 -373.813582)
			(xy 41.566279 -373.866989) (xy 41.542607 -373.917486) (xy 41.511834 -373.963999) (xy 41.474617 -374.005536)
			(xy 41.431749 -374.041211) (xy 41.384143 -374.070265) (xy 41.332814 -374.092077) (xy 41.278857 -374.106183)
			(xy 41.22342 -374.112283) (xy 41.167686 -374.110246) (xy 41.112843 -374.100116) (xy 41.060059 -374.082109)
			(xy 41.010459 -374.056608) (xy 40.965101 -374.024157) (xy 40.924952 -373.985448) (xy 40.890866 -373.941305)
			(xy 40.86357 -373.89267) (xy 40.843647 -373.840579) (xy 40.831521 -373.786142) (xy 40.82745 -373.73052)
			(xy 36.431138 -373.73052) (xy 36.400327 -373.810051) (xy 36.361593 -373.88784) (xy 36.315846 -373.961724)
			(xy 36.263477 -374.031071) (xy 36.204933 -374.095291) (xy 36.140713 -374.153835) (xy 36.071366 -374.206204)
			(xy 35.997482 -374.251951) (xy 35.919693 -374.290685) (xy 35.838661 -374.322077) (xy 35.755079 -374.345858)
			(xy 35.669659 -374.361826) (xy 35.58313 -374.369844) (xy 35.49623 -374.369844) (xy 35.409701 -374.361826)
			(xy 35.324281 -374.345858) (xy 35.240699 -374.322077) (xy 35.159667 -374.290685) (xy 35.081878 -374.251951)
			(xy 35.007994 -374.206204) (xy 34.938647 -374.153835) (xy 34.874427 -374.095291) (xy 34.815883 -374.031071)
			(xy 34.763514 -373.961724) (xy 34.717767 -373.88784) (xy 34.679033 -373.810051) (xy 34.647641 -373.729019)
			(xy 34.62386 -373.645437) (xy 34.607892 -373.560017) (xy 34.599874 -373.473488) (xy 31.399486 -373.473488)
			(xy 31.391468 -373.560017) (xy 31.3755 -373.645437) (xy 31.351719 -373.729019) (xy 31.320327 -373.810051)
			(xy 31.281593 -373.88784) (xy 31.235846 -373.961724) (xy 31.183477 -374.031071) (xy 31.124933 -374.095291)
			(xy 31.060713 -374.153835) (xy 30.991366 -374.206204) (xy 30.917482 -374.251951) (xy 30.839693 -374.290685)
			(xy 30.758661 -374.322077) (xy 30.675079 -374.345858) (xy 30.589659 -374.361826) (xy 30.50313 -374.369844)
			(xy 30.41623 -374.369844) (xy 30.329701 -374.361826) (xy 30.244281 -374.345858) (xy 30.160699 -374.322077)
			(xy 30.079667 -374.290685) (xy 30.001878 -374.251951) (xy 29.927994 -374.206204) (xy 29.858647 -374.153835)
			(xy 29.794427 -374.095291) (xy 29.735883 -374.031071) (xy 29.683514 -373.961724) (xy 29.637767 -373.88784)
			(xy 29.599033 -373.810051) (xy 29.567641 -373.729019) (xy 29.54386 -373.645437) (xy 29.527892 -373.560017)
			(xy 29.519874 -373.473488) (xy 23.720394 -373.473488) (xy 24.362006 -374.115076) (xy 26.403552 -374.115076)
			(xy 26.407623 -374.059454) (xy 26.419749 -374.005017) (xy 26.439672 -373.952926) (xy 26.466968 -373.904291)
			(xy 26.501054 -373.860148) (xy 26.541203 -373.821439) (xy 26.586561 -373.788988) (xy 26.636161 -373.763487)
			(xy 26.688945 -373.74548) (xy 26.743788 -373.73535) (xy 26.799522 -373.733313) (xy 26.854959 -373.739413)
			(xy 26.908916 -373.753519) (xy 26.960245 -373.775331) (xy 27.007851 -373.804385) (xy 27.050719 -373.84006)
			(xy 27.087936 -373.881597) (xy 27.118709 -373.92811) (xy 27.142381 -373.978607) (xy 27.158449 -374.032014)
			(xy 27.166569 -374.08719) (xy 27.167078 -374.115076) (xy 27.166569 -374.142962) (xy 27.158449 -374.198138)
			(xy 27.142381 -374.251545) (xy 27.118709 -374.302042) (xy 27.087936 -374.348555) (xy 27.050719 -374.390092)
			(xy 27.007851 -374.425767) (xy 26.960245 -374.454821) (xy 26.908916 -374.476633) (xy 26.854959 -374.490739)
			(xy 26.799522 -374.496839) (xy 26.743788 -374.494802) (xy 26.688945 -374.484672) (xy 26.636161 -374.466665)
			(xy 26.586561 -374.441164) (xy 26.541203 -374.408713) (xy 26.501054 -374.370004) (xy 26.466968 -374.325861)
			(xy 26.439672 -374.277226) (xy 26.419749 -374.225135) (xy 26.407623 -374.170698) (xy 26.403552 -374.115076)
			(xy 24.362006 -374.115076) (xy 26.260491 -376.013488) (xy 29.519874 -376.013488) (xy 29.519874 -375.926588)
			(xy 29.527892 -375.840059) (xy 29.54386 -375.754639) (xy 29.567641 -375.671057) (xy 29.599033 -375.590025)
			(xy 29.637767 -375.512236) (xy 29.683514 -375.438352) (xy 29.735883 -375.369005) (xy 29.794427 -375.304785)
			(xy 29.858647 -375.246241) (xy 29.927994 -375.193872) (xy 30.001878 -375.148125) (xy 30.079667 -375.109391)
			(xy 30.160699 -375.077999) (xy 30.244281 -375.054218) (xy 30.329701 -375.03825) (xy 30.41623 -375.030232)
			(xy 30.50313 -375.030232) (xy 30.589659 -375.03825) (xy 30.675079 -375.054218) (xy 30.758661 -375.077999)
			(xy 30.839693 -375.109391) (xy 30.917482 -375.148125) (xy 30.991366 -375.193872) (xy 31.060713 -375.246241)
			(xy 31.124933 -375.304785) (xy 31.183477 -375.369005) (xy 31.235846 -375.438352) (xy 31.281593 -375.512236)
			(xy 31.320327 -375.590025) (xy 31.351719 -375.671057) (xy 31.3755 -375.754639) (xy 31.391468 -375.840059)
			(xy 31.399486 -375.926588) (xy 31.399988 -375.970038) (xy 31.399486 -376.013488) (xy 34.599874 -376.013488)
			(xy 34.599874 -375.926588) (xy 34.607892 -375.840059) (xy 34.62386 -375.754639) (xy 34.647641 -375.671057)
			(xy 34.679033 -375.590025) (xy 34.717767 -375.512236) (xy 34.763514 -375.438352) (xy 34.815883 -375.369005)
			(xy 34.874427 -375.304785) (xy 34.938647 -375.246241) (xy 35.007994 -375.193872) (xy 35.081878 -375.148125)
			(xy 35.159667 -375.109391) (xy 35.240699 -375.077999) (xy 35.324281 -375.054218) (xy 35.409701 -375.03825)
			(xy 35.49623 -375.030232) (xy 35.58313 -375.030232) (xy 35.669659 -375.03825) (xy 35.755079 -375.054218)
			(xy 35.838661 -375.077999) (xy 35.919693 -375.109391) (xy 35.997482 -375.148125) (xy 36.064299 -375.189496)
			(xy 40.058846 -375.189496) (xy 40.062917 -375.133874) (xy 40.075043 -375.079437) (xy 40.094966 -375.027346)
			(xy 40.122262 -374.978711) (xy 40.156348 -374.934568) (xy 40.196497 -374.895859) (xy 40.241855 -374.863408)
			(xy 40.291455 -374.837907) (xy 40.344239 -374.8199) (xy 40.399082 -374.80977) (xy 40.454816 -374.807733)
			(xy 40.510253 -374.813833) (xy 40.56421 -374.827939) (xy 40.615539 -374.849751) (xy 40.663145 -374.878805)
			(xy 40.706013 -374.91448) (xy 40.74323 -374.956017) (xy 40.774003 -375.00253) (xy 40.797675 -375.053027)
			(xy 40.813743 -375.106434) (xy 40.821863 -375.16161) (xy 40.822372 -375.189496) (xy 40.821863 -375.217382)
			(xy 40.813743 -375.272558) (xy 40.797675 -375.325965) (xy 40.774003 -375.376462) (xy 40.74323 -375.422975)
			(xy 40.706013 -375.464512) (xy 40.663145 -375.500187) (xy 40.615539 -375.529241) (xy 40.56421 -375.551053)
			(xy 40.510253 -375.565159) (xy 40.454816 -375.571259) (xy 40.399082 -375.569222) (xy 40.344239 -375.559092)
			(xy 40.291455 -375.541085) (xy 40.241855 -375.515584) (xy 40.196497 -375.483133) (xy 40.156348 -375.444424)
			(xy 40.122262 -375.400281) (xy 40.094966 -375.351646) (xy 40.075043 -375.299555) (xy 40.062917 -375.245118)
			(xy 40.058846 -375.189496) (xy 36.064299 -375.189496) (xy 36.071366 -375.193872) (xy 36.140713 -375.246241)
			(xy 36.204933 -375.304785) (xy 36.263477 -375.369005) (xy 36.315846 -375.438352) (xy 36.361593 -375.512236)
			(xy 36.400327 -375.590025) (xy 36.431719 -375.671057) (xy 36.4555 -375.754639) (xy 36.471468 -375.840059)
			(xy 36.479486 -375.926588) (xy 36.479988 -375.970038) (xy 36.479486 -376.013488) (xy 36.471468 -376.100017)
			(xy 36.4555 -376.185437) (xy 36.431719 -376.269019) (xy 36.400327 -376.350051) (xy 36.361593 -376.42784)
			(xy 36.315846 -376.501724) (xy 36.263477 -376.571071) (xy 36.204933 -376.635291) (xy 36.140713 -376.693835)
			(xy 36.071366 -376.746204) (xy 35.997482 -376.791951) (xy 35.99691 -376.792236) (xy 40.137586 -376.792236)
			(xy 40.141657 -376.736614) (xy 40.153783 -376.682177) (xy 40.173706 -376.630086) (xy 40.201002 -376.581451)
			(xy 40.235088 -376.537308) (xy 40.275237 -376.498599) (xy 40.320595 -376.466148) (xy 40.370195 -376.440647)
			(xy 40.422979 -376.42264) (xy 40.477822 -376.41251) (xy 40.533556 -376.410473) (xy 40.588993 -376.416573)
			(xy 40.64295 -376.430679) (xy 40.694279 -376.452491) (xy 40.741885 -376.481545) (xy 40.784753 -376.51722)
			(xy 40.82197 -376.558757) (xy 40.852743 -376.60527) (xy 40.876415 -376.655767) (xy 40.892483 -376.709174)
			(xy 40.900603 -376.76435) (xy 40.901112 -376.792236) (xy 40.900603 -376.820122) (xy 40.892483 -376.875298)
			(xy 40.876415 -376.928705) (xy 40.852743 -376.979202) (xy 40.82197 -377.025715) (xy 40.784753 -377.067252)
			(xy 40.741885 -377.102927) (xy 40.694279 -377.131981) (xy 40.64295 -377.153793) (xy 40.588993 -377.167899)
			(xy 40.533556 -377.173999) (xy 40.477822 -377.171962) (xy 40.422979 -377.161832) (xy 40.370195 -377.143825)
			(xy 40.320595 -377.118324) (xy 40.275237 -377.085873) (xy 40.235088 -377.047164) (xy 40.201002 -377.003021)
			(xy 40.173706 -376.954386) (xy 40.153783 -376.902295) (xy 40.141657 -376.847858) (xy 40.137586 -376.792236)
			(xy 35.99691 -376.792236) (xy 35.919693 -376.830685) (xy 35.838661 -376.862077) (xy 35.755079 -376.885858)
			(xy 35.669659 -376.901826) (xy 35.58313 -376.909844) (xy 35.49623 -376.909844) (xy 35.409701 -376.901826)
			(xy 35.324281 -376.885858) (xy 35.240699 -376.862077) (xy 35.159667 -376.830685) (xy 35.081878 -376.791951)
			(xy 35.007994 -376.746204) (xy 34.938647 -376.693835) (xy 34.874427 -376.635291) (xy 34.815883 -376.571071)
			(xy 34.763514 -376.501724) (xy 34.717767 -376.42784) (xy 34.679033 -376.350051) (xy 34.647641 -376.269019)
			(xy 34.62386 -376.185437) (xy 34.607892 -376.100017) (xy 34.599874 -376.013488) (xy 31.399486 -376.013488)
			(xy 31.391468 -376.100017) (xy 31.3755 -376.185437) (xy 31.351719 -376.269019) (xy 31.320327 -376.350051)
			(xy 31.281593 -376.42784) (xy 31.235846 -376.501724) (xy 31.183477 -376.571071) (xy 31.124933 -376.635291)
			(xy 31.060713 -376.693835) (xy 30.991366 -376.746204) (xy 30.917482 -376.791951) (xy 30.839693 -376.830685)
			(xy 30.758661 -376.862077) (xy 30.675079 -376.885858) (xy 30.589659 -376.901826) (xy 30.50313 -376.909844)
			(xy 30.41623 -376.909844) (xy 30.329701 -376.901826) (xy 30.244281 -376.885858) (xy 30.160699 -376.862077)
			(xy 30.079667 -376.830685) (xy 30.001878 -376.791951) (xy 29.927994 -376.746204) (xy 29.858647 -376.693835)
			(xy 29.794427 -376.635291) (xy 29.735883 -376.571071) (xy 29.683514 -376.501724) (xy 29.637767 -376.42784)
			(xy 29.599033 -376.350051) (xy 29.567641 -376.269019) (xy 29.54386 -376.185437) (xy 29.527892 -376.100017)
			(xy 29.519874 -376.013488) (xy 26.260491 -376.013488) (xy 28.270708 -378.023628) (xy 28.287158 -378.039361)
			(xy 28.324559 -378.065297) (xy 28.365979 -378.084162) (xy 28.410095 -378.095352) (xy 28.455499 -378.098511)
			(xy 28.50074 -378.093537) (xy 28.544373 -378.080589) (xy 28.585005 -378.060081) (xy 28.603448 -378.046742)
			(xy 28.625542 -378.030619) (xy 28.673429 -378.00419) (xy 28.724599 -377.98487) (xy 28.778003 -377.973057)
			(xy 28.832548 -377.968991) (xy 28.887114 -377.972756) (xy 28.940582 -377.984275) (xy 28.991858 -378.003312)
			(xy 29.03989 -378.029477) (xy 29.083692 -378.062233) (xy 29.122368 -378.100909) (xy 29.155123 -378.144711)
			(xy 29.181288 -378.192743) (xy 29.200325 -378.244019) (xy 29.211844 -378.297488) (xy 29.215609 -378.352053)
			(xy 29.211543 -378.406598) (xy 29.199729 -378.460002) (xy 29.18041 -378.511172) (xy 29.157056 -378.553488)
			(xy 29.519874 -378.553488) (xy 29.519874 -378.466588) (xy 29.527892 -378.380059) (xy 29.54386 -378.294639)
			(xy 29.567641 -378.211057) (xy 29.599033 -378.130025) (xy 29.637767 -378.052236) (xy 29.683514 -377.978352)
			(xy 29.735883 -377.909005) (xy 29.794427 -377.844785) (xy 29.858647 -377.786241) (xy 29.927994 -377.733872)
			(xy 30.001878 -377.688125) (xy 30.079667 -377.649391) (xy 30.160699 -377.617999) (xy 30.244281 -377.594218)
			(xy 30.329701 -377.57825) (xy 30.41623 -377.570232) (xy 30.50313 -377.570232) (xy 30.589659 -377.57825)
			(xy 30.675079 -377.594218) (xy 30.758661 -377.617999) (xy 30.839693 -377.649391) (xy 30.917482 -377.688125)
			(xy 30.991366 -377.733872) (xy 31.060713 -377.786241) (xy 31.124933 -377.844785) (xy 31.183477 -377.909005)
			(xy 31.235846 -377.978352) (xy 31.281593 -378.052236) (xy 31.320327 -378.130025) (xy 31.351719 -378.211057)
			(xy 31.3755 -378.294639) (xy 31.391468 -378.380059) (xy 31.399486 -378.466588) (xy 31.399988 -378.510038)
			(xy 31.399486 -378.553488) (xy 34.599874 -378.553488) (xy 34.599874 -378.466588) (xy 34.607892 -378.380059)
			(xy 34.62386 -378.294639) (xy 34.647641 -378.211057) (xy 34.679033 -378.130025) (xy 34.717767 -378.052236)
			(xy 34.763514 -377.978352) (xy 34.815883 -377.909005) (xy 34.874427 -377.844785) (xy 34.938647 -377.786241)
			(xy 35.007994 -377.733872) (xy 35.081878 -377.688125) (xy 35.159667 -377.649391) (xy 35.240699 -377.617999)
			(xy 35.324281 -377.594218) (xy 35.409701 -377.57825) (xy 35.49623 -377.570232) (xy 35.58313 -377.570232)
			(xy 35.669659 -377.57825) (xy 35.755079 -377.594218) (xy 35.838661 -377.617999) (xy 35.919693 -377.649391)
			(xy 35.997482 -377.688125) (xy 36.071366 -377.733872) (xy 36.140713 -377.786241) (xy 36.204933 -377.844785)
			(xy 36.263477 -377.909005) (xy 36.315846 -377.978352) (xy 36.361593 -378.052236) (xy 36.400327 -378.130025)
			(xy 36.431719 -378.211057) (xy 36.4555 -378.294639) (xy 36.471468 -378.380059) (xy 36.479486 -378.466588)
			(xy 36.479988 -378.510038) (xy 36.479486 -378.553488) (xy 36.471468 -378.640017) (xy 36.4555 -378.725437)
			(xy 36.431719 -378.809019) (xy 36.400327 -378.890051) (xy 36.361593 -378.96784) (xy 36.315846 -379.041724)
			(xy 36.263477 -379.111071) (xy 36.204933 -379.175291) (xy 36.140713 -379.233835) (xy 36.071366 -379.286204)
			(xy 35.997482 -379.331951) (xy 35.919693 -379.370685) (xy 35.838661 -379.402077) (xy 35.755079 -379.425858)
			(xy 35.669659 -379.441826) (xy 35.58313 -379.449844) (xy 35.49623 -379.449844) (xy 35.409701 -379.441826)
			(xy 35.324281 -379.425858) (xy 35.240699 -379.402077) (xy 35.159667 -379.370685) (xy 35.081878 -379.331951)
			(xy 35.007994 -379.286204) (xy 34.938647 -379.233835) (xy 34.874427 -379.175291) (xy 34.815883 -379.111071)
			(xy 34.763514 -379.041724) (xy 34.717767 -378.96784) (xy 34.679033 -378.890051) (xy 34.647641 -378.809019)
			(xy 34.62386 -378.725437) (xy 34.607892 -378.640017) (xy 34.599874 -378.553488) (xy 31.399486 -378.553488)
			(xy 31.391468 -378.640017) (xy 31.3755 -378.725437) (xy 31.351719 -378.809019) (xy 31.320327 -378.890051)
			(xy 31.281593 -378.96784) (xy 31.235846 -379.041724) (xy 31.183477 -379.111071) (xy 31.124933 -379.175291)
			(xy 31.060713 -379.233835) (xy 30.991366 -379.286204) (xy 30.917482 -379.331951) (xy 30.839693 -379.370685)
			(xy 30.758661 -379.402077) (xy 30.675079 -379.425858) (xy 30.589659 -379.441826) (xy 30.50313 -379.449844)
			(xy 30.41623 -379.449844) (xy 30.329701 -379.441826) (xy 30.244281 -379.425858) (xy 30.160699 -379.402077)
			(xy 30.079667 -379.370685) (xy 30.001878 -379.331951) (xy 29.927994 -379.286204) (xy 29.858647 -379.233835)
			(xy 29.794427 -379.175291) (xy 29.735883 -379.111071) (xy 29.683514 -379.041724) (xy 29.637767 -378.96784)
			(xy 29.599033 -378.890051) (xy 29.567641 -378.809019) (xy 29.54386 -378.725437) (xy 29.527892 -378.640017)
			(xy 29.519874 -378.553488) (xy 29.157056 -378.553488) (xy 29.153981 -378.559059) (xy 29.137864 -378.581158)
			(xy 29.124541 -378.59962) (xy 29.103995 -378.640243) (xy 29.091018 -378.683877) (xy 29.086024 -378.729125)
			(xy 29.089173 -378.774539) (xy 29.100365 -378.818665) (xy 29.119242 -378.86009) (xy 29.145198 -378.897488)
			(xy 29.160978 -378.913898) (xy 29.171392 -378.924312) (xy 29.254196 -379.00737) (xy 29.254196 -381.093488)
			(xy 29.519874 -381.093488) (xy 29.519874 -381.006588) (xy 29.527892 -380.920059) (xy 29.54386 -380.834639)
			(xy 29.567641 -380.751057) (xy 29.599033 -380.670025) (xy 29.637767 -380.592236) (xy 29.683514 -380.518352)
			(xy 29.735883 -380.449005) (xy 29.794427 -380.384785) (xy 29.858647 -380.326241) (xy 29.927994 -380.273872)
			(xy 30.001878 -380.228125) (xy 30.079667 -380.189391) (xy 30.160699 -380.157999) (xy 30.244281 -380.134218)
			(xy 30.329701 -380.11825) (xy 30.41623 -380.110232) (xy 30.50313 -380.110232) (xy 30.589659 -380.11825)
			(xy 30.675079 -380.134218) (xy 30.758661 -380.157999) (xy 30.839693 -380.189391) (xy 30.917482 -380.228125)
			(xy 30.991366 -380.273872) (xy 31.060713 -380.326241) (xy 31.124933 -380.384785) (xy 31.183477 -380.449005)
			(xy 31.235846 -380.518352) (xy 31.281593 -380.592236) (xy 31.320327 -380.670025) (xy 31.351719 -380.751057)
			(xy 31.3755 -380.834639) (xy 31.391468 -380.920059) (xy 31.399486 -381.006588) (xy 31.399988 -381.050038)
			(xy 31.399486 -381.093488) (xy 34.599874 -381.093488) (xy 34.599874 -381.006588) (xy 34.607892 -380.920059)
			(xy 34.62386 -380.834639) (xy 34.647641 -380.751057) (xy 34.679033 -380.670025) (xy 34.717767 -380.592236)
			(xy 34.763514 -380.518352) (xy 34.815883 -380.449005) (xy 34.874427 -380.384785) (xy 34.938647 -380.326241)
			(xy 35.007994 -380.273872) (xy 35.081878 -380.228125) (xy 35.159667 -380.189391) (xy 35.240699 -380.157999)
			(xy 35.324281 -380.134218) (xy 35.409701 -380.11825) (xy 35.49623 -380.110232) (xy 35.58313 -380.110232)
			(xy 35.669659 -380.11825) (xy 35.755079 -380.134218) (xy 35.838661 -380.157999) (xy 35.919693 -380.189391)
			(xy 35.997482 -380.228125) (xy 36.071366 -380.273872) (xy 36.140713 -380.326241) (xy 36.204933 -380.384785)
			(xy 36.263477 -380.449005) (xy 36.315846 -380.518352) (xy 36.361593 -380.592236) (xy 36.400327 -380.670025)
			(xy 36.431719 -380.751057) (xy 36.4555 -380.834639) (xy 36.45609 -380.837795) (xy 38.508678 -380.837795)
			(xy 38.508678 -380.766473) (xy 38.516664 -380.695599) (xy 38.532534 -380.626064) (xy 38.556091 -380.558744)
			(xy 38.587036 -380.494485) (xy 38.624982 -380.434094) (xy 38.669451 -380.378332) (xy 38.719884 -380.327899)
			(xy 38.775646 -380.28343) (xy 38.836037 -380.245484) (xy 38.900296 -380.214539) (xy 38.967616 -380.190982)
			(xy 39.037151 -380.175112) (xy 39.108025 -380.167126) (xy 39.179347 -380.167126) (xy 39.250221 -380.175112)
			(xy 39.319756 -380.190982) (xy 39.387076 -380.214539) (xy 39.451335 -380.245484) (xy 39.511726 -380.28343)
			(xy 39.567488 -380.327899) (xy 39.617921 -380.378332) (xy 39.66239 -380.434094) (xy 39.700336 -380.494485)
			(xy 39.731281 -380.558744) (xy 39.754838 -380.626064) (xy 39.770708 -380.695599) (xy 39.778694 -380.766473)
			(xy 39.779194 -380.802134) (xy 39.778694 -380.837795) (xy 40.39539 -380.837795) (xy 40.39539 -380.766473)
			(xy 40.403376 -380.695599) (xy 40.419246 -380.626064) (xy 40.442803 -380.558744) (xy 40.473748 -380.494485)
			(xy 40.511694 -380.434094) (xy 40.556163 -380.378332) (xy 40.606596 -380.327899) (xy 40.662358 -380.28343)
			(xy 40.722749 -380.245484) (xy 40.787008 -380.214539) (xy 40.854328 -380.190982) (xy 40.923863 -380.175112)
			(xy 40.994737 -380.167126) (xy 41.066059 -380.167126) (xy 41.136933 -380.175112) (xy 41.206468 -380.190982)
			(xy 41.273788 -380.214539) (xy 41.338047 -380.245484) (xy 41.398438 -380.28343) (xy 41.4542 -380.327899)
			(xy 41.504633 -380.378332) (xy 41.549102 -380.434094) (xy 41.587048 -380.494485) (xy 41.617993 -380.558744)
			(xy 41.64155 -380.626064) (xy 41.65742 -380.695599) (xy 41.665406 -380.766473) (xy 41.665906 -380.802134)
			(xy 41.665406 -380.837795) (xy 41.65742 -380.908669) (xy 41.64155 -380.978204) (xy 41.617993 -381.045524)
			(xy 41.587048 -381.109783) (xy 41.549102 -381.170174) (xy 41.504633 -381.225936) (xy 41.4542 -381.276369)
			(xy 41.398438 -381.320838) (xy 41.338047 -381.358784) (xy 41.273788 -381.389729) (xy 41.206468 -381.413286)
			(xy 41.136933 -381.429156) (xy 41.066059 -381.437142) (xy 40.994737 -381.437142) (xy 40.923863 -381.429156)
			(xy 40.854328 -381.413286) (xy 40.787008 -381.389729) (xy 40.722749 -381.358784) (xy 40.662358 -381.320838)
			(xy 40.606596 -381.276369) (xy 40.556163 -381.225936) (xy 40.511694 -381.170174) (xy 40.473748 -381.109783)
			(xy 40.442803 -381.045524) (xy 40.419246 -380.978204) (xy 40.403376 -380.908669) (xy 40.39539 -380.837795)
			(xy 39.778694 -380.837795) (xy 39.770708 -380.908669) (xy 39.754838 -380.978204) (xy 39.731281 -381.045524)
			(xy 39.700336 -381.109783) (xy 39.66239 -381.170174) (xy 39.617921 -381.225936) (xy 39.567488 -381.276369)
			(xy 39.511726 -381.320838) (xy 39.451335 -381.358784) (xy 39.387076 -381.389729) (xy 39.319756 -381.413286)
			(xy 39.250221 -381.429156) (xy 39.179347 -381.437142) (xy 39.108025 -381.437142) (xy 39.037151 -381.429156)
			(xy 38.967616 -381.413286) (xy 38.900296 -381.389729) (xy 38.836037 -381.358784) (xy 38.775646 -381.320838)
			(xy 38.719884 -381.276369) (xy 38.669451 -381.225936) (xy 38.624982 -381.170174) (xy 38.587036 -381.109783)
			(xy 38.556091 -381.045524) (xy 38.532534 -380.978204) (xy 38.516664 -380.908669) (xy 38.508678 -380.837795)
			(xy 36.45609 -380.837795) (xy 36.471468 -380.920059) (xy 36.479486 -381.006588) (xy 36.479988 -381.050038)
			(xy 36.479486 -381.093488) (xy 36.471468 -381.180017) (xy 36.4555 -381.265437) (xy 36.431719 -381.349019)
			(xy 36.400327 -381.430051) (xy 36.361593 -381.50784) (xy 36.315846 -381.581724) (xy 36.263477 -381.651071)
			(xy 36.204933 -381.715291) (xy 36.140713 -381.773835) (xy 36.071366 -381.826204) (xy 35.997482 -381.871951)
			(xy 35.919693 -381.910685) (xy 35.838661 -381.942077) (xy 35.755079 -381.965858) (xy 35.669659 -381.981826)
			(xy 35.58313 -381.989844) (xy 35.49623 -381.989844) (xy 35.409701 -381.981826) (xy 35.324281 -381.965858)
			(xy 35.240699 -381.942077) (xy 35.159667 -381.910685) (xy 35.081878 -381.871951) (xy 35.007994 -381.826204)
			(xy 34.938647 -381.773835) (xy 34.874427 -381.715291) (xy 34.815883 -381.651071) (xy 34.763514 -381.581724)
			(xy 34.717767 -381.50784) (xy 34.679033 -381.430051) (xy 34.647641 -381.349019) (xy 34.62386 -381.265437)
			(xy 34.607892 -381.180017) (xy 34.599874 -381.093488) (xy 31.399486 -381.093488) (xy 31.391468 -381.180017)
			(xy 31.3755 -381.265437) (xy 31.351719 -381.349019) (xy 31.320327 -381.430051) (xy 31.281593 -381.50784)
			(xy 31.235846 -381.581724) (xy 31.183477 -381.651071) (xy 31.124933 -381.715291) (xy 31.060713 -381.773835)
			(xy 30.991366 -381.826204) (xy 30.917482 -381.871951) (xy 30.839693 -381.910685) (xy 30.758661 -381.942077)
			(xy 30.675079 -381.965858) (xy 30.589659 -381.981826) (xy 30.50313 -381.989844) (xy 30.41623 -381.989844)
			(xy 30.329701 -381.981826) (xy 30.244281 -381.965858) (xy 30.160699 -381.942077) (xy 30.079667 -381.910685)
			(xy 30.001878 -381.871951) (xy 29.927994 -381.826204) (xy 29.858647 -381.773835) (xy 29.794427 -381.715291)
			(xy 29.735883 -381.651071) (xy 29.683514 -381.581724) (xy 29.637767 -381.50784) (xy 29.599033 -381.430051)
			(xy 29.567641 -381.349019) (xy 29.54386 -381.265437) (xy 29.527892 -381.180017) (xy 29.519874 -381.093488)
			(xy 29.254196 -381.093488) (xy 29.254196 -383.633488) (xy 29.519874 -383.633488) (xy 29.519874 -383.546588)
			(xy 29.527892 -383.460059) (xy 29.54386 -383.374639) (xy 29.567641 -383.291057) (xy 29.599033 -383.210025)
			(xy 29.637767 -383.132236) (xy 29.683514 -383.058352) (xy 29.735883 -382.989005) (xy 29.794427 -382.924785)
			(xy 29.858647 -382.866241) (xy 29.927994 -382.813872) (xy 30.001878 -382.768125) (xy 30.079667 -382.729391)
			(xy 30.160699 -382.697999) (xy 30.244281 -382.674218) (xy 30.329701 -382.65825) (xy 30.41623 -382.650232)
			(xy 30.50313 -382.650232) (xy 30.589659 -382.65825) (xy 30.675079 -382.674218) (xy 30.758661 -382.697999)
			(xy 30.839693 -382.729391) (xy 30.917482 -382.768125) (xy 30.991366 -382.813872) (xy 31.060713 -382.866241)
			(xy 31.124933 -382.924785) (xy 31.183477 -382.989005) (xy 31.235846 -383.058352) (xy 31.281593 -383.132236)
			(xy 31.320327 -383.210025) (xy 31.351719 -383.291057) (xy 31.3755 -383.374639) (xy 31.391468 -383.460059)
			(xy 31.399486 -383.546588) (xy 31.399988 -383.590038) (xy 31.399486 -383.633488) (xy 34.599874 -383.633488)
			(xy 34.599874 -383.546588) (xy 34.607892 -383.460059) (xy 34.62386 -383.374639) (xy 34.647641 -383.291057)
			(xy 34.679033 -383.210025) (xy 34.717767 -383.132236) (xy 34.763514 -383.058352) (xy 34.815883 -382.989005)
			(xy 34.874427 -382.924785) (xy 34.938647 -382.866241) (xy 35.007994 -382.813872) (xy 35.081878 -382.768125)
			(xy 35.159667 -382.729391) (xy 35.240699 -382.697999) (xy 35.324281 -382.674218) (xy 35.409701 -382.65825)
			(xy 35.49623 -382.650232) (xy 35.58313 -382.650232) (xy 35.669659 -382.65825) (xy 35.740117 -382.671421)
			(xy 38.508678 -382.671421) (xy 38.508678 -382.600099) (xy 38.516664 -382.529225) (xy 38.532534 -382.45969)
			(xy 38.556091 -382.39237) (xy 38.587036 -382.328111) (xy 38.624982 -382.26772) (xy 38.669451 -382.211958)
			(xy 38.719884 -382.161525) (xy 38.775646 -382.117056) (xy 38.836037 -382.07911) (xy 38.900296 -382.048165)
			(xy 38.967616 -382.024608) (xy 39.037151 -382.008738) (xy 39.108025 -382.000752) (xy 39.179347 -382.000752)
			(xy 39.250221 -382.008738) (xy 39.319756 -382.024608) (xy 39.387076 -382.048165) (xy 39.451335 -382.07911)
			(xy 39.511726 -382.117056) (xy 39.567488 -382.161525) (xy 39.617921 -382.211958) (xy 39.66239 -382.26772)
			(xy 39.700336 -382.328111) (xy 39.731281 -382.39237) (xy 39.754838 -382.45969) (xy 39.770708 -382.529225)
			(xy 39.778694 -382.600099) (xy 39.779194 -382.63576) (xy 39.778694 -382.671421) (xy 40.39539 -382.671421)
			(xy 40.39539 -382.600099) (xy 40.403376 -382.529225) (xy 40.419246 -382.45969) (xy 40.442803 -382.39237)
			(xy 40.473748 -382.328111) (xy 40.511694 -382.26772) (xy 40.556163 -382.211958) (xy 40.606596 -382.161525)
			(xy 40.662358 -382.117056) (xy 40.722749 -382.07911) (xy 40.787008 -382.048165) (xy 40.854328 -382.024608)
			(xy 40.923863 -382.008738) (xy 40.994737 -382.000752) (xy 41.066059 -382.000752) (xy 41.136933 -382.008738)
			(xy 41.206468 -382.024608) (xy 41.273788 -382.048165) (xy 41.338047 -382.07911) (xy 41.398438 -382.117056)
			(xy 41.4542 -382.161525) (xy 41.504633 -382.211958) (xy 41.549102 -382.26772) (xy 41.587048 -382.328111)
			(xy 41.617993 -382.39237) (xy 41.64155 -382.45969) (xy 41.65742 -382.529225) (xy 41.665406 -382.600099)
			(xy 41.665906 -382.63576) (xy 41.665406 -382.671421) (xy 42.636432 -382.671421) (xy 42.636432 -382.600099)
			(xy 42.644418 -382.529225) (xy 42.660288 -382.45969) (xy 42.683845 -382.39237) (xy 42.71479 -382.328111)
			(xy 42.752736 -382.26772) (xy 42.797205 -382.211958) (xy 42.847638 -382.161525) (xy 42.9034 -382.117056)
			(xy 42.963791 -382.07911) (xy 43.02805 -382.048165) (xy 43.09537 -382.024608) (xy 43.164905 -382.008738)
			(xy 43.235779 -382.000752) (xy 43.307101 -382.000752) (xy 43.377975 -382.008738) (xy 43.44751 -382.024608)
			(xy 43.51483 -382.048165) (xy 43.579089 -382.07911) (xy 43.63948 -382.117056) (xy 43.695242 -382.161525)
			(xy 43.745675 -382.211958) (xy 43.790144 -382.26772) (xy 43.82809 -382.328111) (xy 43.859035 -382.39237)
			(xy 43.882592 -382.45969) (xy 43.898462 -382.529225) (xy 43.906448 -382.600099) (xy 43.906948 -382.63576)
			(xy 43.906448 -382.671421) (xy 44.540416 -382.671421) (xy 44.540416 -382.600099) (xy 44.548402 -382.529225)
			(xy 44.564272 -382.45969) (xy 44.587829 -382.39237) (xy 44.618774 -382.328111) (xy 44.65672 -382.26772)
			(xy 44.701189 -382.211958) (xy 44.751622 -382.161525) (xy 44.807384 -382.117056) (xy 44.867775 -382.07911)
			(xy 44.932034 -382.048165) (xy 44.999354 -382.024608) (xy 45.068889 -382.008738) (xy 45.139763 -382.000752)
			(xy 45.211085 -382.000752) (xy 45.281959 -382.008738) (xy 45.351494 -382.024608) (xy 45.418814 -382.048165)
			(xy 45.483073 -382.07911) (xy 45.543464 -382.117056) (xy 45.599226 -382.161525) (xy 45.649659 -382.211958)
			(xy 45.694128 -382.26772) (xy 45.732074 -382.328111) (xy 45.763019 -382.39237) (xy 45.786576 -382.45969)
			(xy 45.802446 -382.529225) (xy 45.810432 -382.600099) (xy 45.810932 -382.63576) (xy 45.810432 -382.671421)
			(xy 45.802446 -382.742295) (xy 45.786576 -382.81183) (xy 45.763019 -382.87915) (xy 45.732074 -382.943409)
			(xy 45.694128 -383.0038) (xy 45.649659 -383.059562) (xy 45.599226 -383.109995) (xy 45.543464 -383.154464)
			(xy 45.483073 -383.19241) (xy 45.418814 -383.223355) (xy 45.351494 -383.246912) (xy 45.281959 -383.262782)
			(xy 45.211085 -383.270768) (xy 45.139763 -383.270768) (xy 45.068889 -383.262782) (xy 44.999354 -383.246912)
			(xy 44.932034 -383.223355) (xy 44.867775 -383.19241) (xy 44.807384 -383.154464) (xy 44.751622 -383.109995)
			(xy 44.701189 -383.059562) (xy 44.65672 -383.0038) (xy 44.618774 -382.943409) (xy 44.587829 -382.87915)
			(xy 44.564272 -382.81183) (xy 44.548402 -382.742295) (xy 44.540416 -382.671421) (xy 43.906448 -382.671421)
			(xy 43.898462 -382.742295) (xy 43.882592 -382.81183) (xy 43.859035 -382.87915) (xy 43.82809 -382.943409)
			(xy 43.790144 -383.0038) (xy 43.745675 -383.059562) (xy 43.695242 -383.109995) (xy 43.63948 -383.154464)
			(xy 43.579089 -383.19241) (xy 43.51483 -383.223355) (xy 43.44751 -383.246912) (xy 43.377975 -383.262782)
			(xy 43.307101 -383.270768) (xy 43.235779 -383.270768) (xy 43.164905 -383.262782) (xy 43.09537 -383.246912)
			(xy 43.02805 -383.223355) (xy 42.963791 -383.19241) (xy 42.9034 -383.154464) (xy 42.847638 -383.109995)
			(xy 42.797205 -383.059562) (xy 42.752736 -383.0038) (xy 42.71479 -382.943409) (xy 42.683845 -382.87915)
			(xy 42.660288 -382.81183) (xy 42.644418 -382.742295) (xy 42.636432 -382.671421) (xy 41.665406 -382.671421)
			(xy 41.65742 -382.742295) (xy 41.64155 -382.81183) (xy 41.617993 -382.87915) (xy 41.587048 -382.943409)
			(xy 41.549102 -383.0038) (xy 41.504633 -383.059562) (xy 41.4542 -383.109995) (xy 41.398438 -383.154464)
			(xy 41.338047 -383.19241) (xy 41.273788 -383.223355) (xy 41.206468 -383.246912) (xy 41.136933 -383.262782)
			(xy 41.066059 -383.270768) (xy 40.994737 -383.270768) (xy 40.923863 -383.262782) (xy 40.854328 -383.246912)
			(xy 40.787008 -383.223355) (xy 40.722749 -383.19241) (xy 40.662358 -383.154464) (xy 40.606596 -383.109995)
			(xy 40.556163 -383.059562) (xy 40.511694 -383.0038) (xy 40.473748 -382.943409) (xy 40.442803 -382.87915)
			(xy 40.419246 -382.81183) (xy 40.403376 -382.742295) (xy 40.39539 -382.671421) (xy 39.778694 -382.671421)
			(xy 39.770708 -382.742295) (xy 39.754838 -382.81183) (xy 39.731281 -382.87915) (xy 39.700336 -382.943409)
			(xy 39.66239 -383.0038) (xy 39.617921 -383.059562) (xy 39.567488 -383.109995) (xy 39.511726 -383.154464)
			(xy 39.451335 -383.19241) (xy 39.387076 -383.223355) (xy 39.319756 -383.246912) (xy 39.250221 -383.262782)
			(xy 39.179347 -383.270768) (xy 39.108025 -383.270768) (xy 39.037151 -383.262782) (xy 38.967616 -383.246912)
			(xy 38.900296 -383.223355) (xy 38.836037 -383.19241) (xy 38.775646 -383.154464) (xy 38.719884 -383.109995)
			(xy 38.669451 -383.059562) (xy 38.624982 -383.0038) (xy 38.587036 -382.943409) (xy 38.556091 -382.87915)
			(xy 38.532534 -382.81183) (xy 38.516664 -382.742295) (xy 38.508678 -382.671421) (xy 35.740117 -382.671421)
			(xy 35.755079 -382.674218) (xy 35.838661 -382.697999) (xy 35.919693 -382.729391) (xy 35.997482 -382.768125)
			(xy 36.071366 -382.813872) (xy 36.140713 -382.866241) (xy 36.204933 -382.924785) (xy 36.263477 -382.989005)
			(xy 36.315846 -383.058352) (xy 36.361593 -383.132236) (xy 36.400327 -383.210025) (xy 36.431719 -383.291057)
			(xy 36.4555 -383.374639) (xy 36.471468 -383.460059) (xy 36.479486 -383.546588) (xy 36.479988 -383.590038)
			(xy 36.479486 -383.633488) (xy 36.471468 -383.720017) (xy 36.4555 -383.805437) (xy 36.431719 -383.889019)
			(xy 36.400327 -383.970051) (xy 36.361593 -384.04784) (xy 36.315846 -384.121724) (xy 36.263477 -384.191071)
			(xy 36.204933 -384.255291) (xy 36.140713 -384.313835) (xy 36.071366 -384.366204) (xy 35.997482 -384.411951)
			(xy 35.919693 -384.450685) (xy 35.838661 -384.482077) (xy 35.755079 -384.505858) (xy 35.669659 -384.521826)
			(xy 35.58313 -384.529844) (xy 35.49623 -384.529844) (xy 35.409701 -384.521826) (xy 35.324281 -384.505858)
			(xy 35.240699 -384.482077) (xy 35.159667 -384.450685) (xy 35.081878 -384.411951) (xy 35.007994 -384.366204)
			(xy 34.938647 -384.313835) (xy 34.874427 -384.255291) (xy 34.815883 -384.191071) (xy 34.763514 -384.121724)
			(xy 34.717767 -384.04784) (xy 34.679033 -383.970051) (xy 34.647641 -383.889019) (xy 34.62386 -383.805437)
			(xy 34.607892 -383.720017) (xy 34.599874 -383.633488) (xy 31.399486 -383.633488) (xy 31.391468 -383.720017)
			(xy 31.3755 -383.805437) (xy 31.351719 -383.889019) (xy 31.320327 -383.970051) (xy 31.281593 -384.04784)
			(xy 31.235846 -384.121724) (xy 31.183477 -384.191071) (xy 31.124933 -384.255291) (xy 31.060713 -384.313835)
			(xy 30.991366 -384.366204) (xy 30.917482 -384.411951) (xy 30.839693 -384.450685) (xy 30.758661 -384.482077)
			(xy 30.675079 -384.505858) (xy 30.589659 -384.521826) (xy 30.50313 -384.529844) (xy 30.41623 -384.529844)
			(xy 30.329701 -384.521826) (xy 30.244281 -384.505858) (xy 30.160699 -384.482077) (xy 30.079667 -384.450685)
			(xy 30.001878 -384.411951) (xy 29.927994 -384.366204) (xy 29.858647 -384.313835) (xy 29.794427 -384.255291)
			(xy 29.735883 -384.191071) (xy 29.683514 -384.121724) (xy 29.637767 -384.04784) (xy 29.599033 -383.970051)
			(xy 29.567641 -383.889019) (xy 29.54386 -383.805437) (xy 29.527892 -383.720017) (xy 29.519874 -383.633488)
			(xy 29.254196 -383.633488) (xy 29.254196 -384.572357) (xy 38.508678 -384.572357) (xy 38.508678 -384.501035)
			(xy 38.516664 -384.430161) (xy 38.532534 -384.360626) (xy 38.556091 -384.293306) (xy 38.587036 -384.229047)
			(xy 38.624982 -384.168656) (xy 38.669451 -384.112894) (xy 38.719884 -384.062461) (xy 38.775646 -384.017992)
			(xy 38.836037 -383.980046) (xy 38.900296 -383.949101) (xy 38.967616 -383.925544) (xy 39.037151 -383.909674)
			(xy 39.108025 -383.901688) (xy 39.179347 -383.901688) (xy 39.250221 -383.909674) (xy 39.319756 -383.925544)
			(xy 39.387076 -383.949101) (xy 39.451335 -383.980046) (xy 39.511726 -384.017992) (xy 39.567488 -384.062461)
			(xy 39.617921 -384.112894) (xy 39.66239 -384.168656) (xy 39.700336 -384.229047) (xy 39.731281 -384.293306)
			(xy 39.754838 -384.360626) (xy 39.770708 -384.430161) (xy 39.778694 -384.501035) (xy 39.779194 -384.536696)
			(xy 39.778694 -384.572357) (xy 40.39539 -384.572357) (xy 40.39539 -384.501035) (xy 40.403376 -384.430161)
			(xy 40.419246 -384.360626) (xy 40.442803 -384.293306) (xy 40.473748 -384.229047) (xy 40.511694 -384.168656)
			(xy 40.556163 -384.112894) (xy 40.606596 -384.062461) (xy 40.662358 -384.017992) (xy 40.722749 -383.980046)
			(xy 40.787008 -383.949101) (xy 40.854328 -383.925544) (xy 40.923863 -383.909674) (xy 40.994737 -383.901688)
			(xy 41.066059 -383.901688) (xy 41.136933 -383.909674) (xy 41.206468 -383.925544) (xy 41.273788 -383.949101)
			(xy 41.338047 -383.980046) (xy 41.398438 -384.017992) (xy 41.4542 -384.062461) (xy 41.504633 -384.112894)
			(xy 41.549102 -384.168656) (xy 41.587048 -384.229047) (xy 41.617993 -384.293306) (xy 41.64155 -384.360626)
			(xy 41.65742 -384.430161) (xy 41.665406 -384.501035) (xy 41.665906 -384.536696) (xy 41.665406 -384.572357)
			(xy 42.636432 -384.572357) (xy 42.636432 -384.501035) (xy 42.644418 -384.430161) (xy 42.660288 -384.360626)
			(xy 42.683845 -384.293306) (xy 42.71479 -384.229047) (xy 42.752736 -384.168656) (xy 42.797205 -384.112894)
			(xy 42.847638 -384.062461) (xy 42.9034 -384.017992) (xy 42.963791 -383.980046) (xy 43.02805 -383.949101)
			(xy 43.09537 -383.925544) (xy 43.164905 -383.909674) (xy 43.235779 -383.901688) (xy 43.307101 -383.901688)
			(xy 43.377975 -383.909674) (xy 43.44751 -383.925544) (xy 43.51483 -383.949101) (xy 43.579089 -383.980046)
			(xy 43.63948 -384.017992) (xy 43.695242 -384.062461) (xy 43.745675 -384.112894) (xy 43.790144 -384.168656)
			(xy 43.82809 -384.229047) (xy 43.859035 -384.293306) (xy 43.882592 -384.360626) (xy 43.898462 -384.430161)
			(xy 43.906448 -384.501035) (xy 43.906948 -384.536696) (xy 43.906448 -384.572357) (xy 44.540416 -384.572357)
			(xy 44.540416 -384.501035) (xy 44.548402 -384.430161) (xy 44.564272 -384.360626) (xy 44.587829 -384.293306)
			(xy 44.618774 -384.229047) (xy 44.65672 -384.168656) (xy 44.701189 -384.112894) (xy 44.751622 -384.062461)
			(xy 44.807384 -384.017992) (xy 44.867775 -383.980046) (xy 44.932034 -383.949101) (xy 44.999354 -383.925544)
			(xy 45.068889 -383.909674) (xy 45.139763 -383.901688) (xy 45.211085 -383.901688) (xy 45.281959 -383.909674)
			(xy 45.351494 -383.925544) (xy 45.418814 -383.949101) (xy 45.483073 -383.980046) (xy 45.543464 -384.017992)
			(xy 45.599226 -384.062461) (xy 45.649659 -384.112894) (xy 45.694128 -384.168656) (xy 45.732074 -384.229047)
			(xy 45.763019 -384.293306) (xy 45.786576 -384.360626) (xy 45.802446 -384.430161) (xy 45.810432 -384.501035)
			(xy 45.810932 -384.536696) (xy 45.810432 -384.572357) (xy 45.802446 -384.643231) (xy 45.786576 -384.712766)
			(xy 45.763019 -384.780086) (xy 45.732074 -384.844345) (xy 45.694128 -384.904736) (xy 45.649659 -384.960498)
			(xy 45.599226 -385.010931) (xy 45.543464 -385.0554) (xy 45.483073 -385.093346) (xy 45.418814 -385.124291)
			(xy 45.351494 -385.147848) (xy 45.281959 -385.163718) (xy 45.211085 -385.171704) (xy 45.139763 -385.171704)
			(xy 45.068889 -385.163718) (xy 44.999354 -385.147848) (xy 44.932034 -385.124291) (xy 44.867775 -385.093346)
			(xy 44.807384 -385.0554) (xy 44.751622 -385.010931) (xy 44.701189 -384.960498) (xy 44.65672 -384.904736)
			(xy 44.618774 -384.844345) (xy 44.587829 -384.780086) (xy 44.564272 -384.712766) (xy 44.548402 -384.643231)
			(xy 44.540416 -384.572357) (xy 43.906448 -384.572357) (xy 43.898462 -384.643231) (xy 43.882592 -384.712766)
			(xy 43.859035 -384.780086) (xy 43.82809 -384.844345) (xy 43.790144 -384.904736) (xy 43.745675 -384.960498)
			(xy 43.695242 -385.010931) (xy 43.63948 -385.0554) (xy 43.579089 -385.093346) (xy 43.51483 -385.124291)
			(xy 43.44751 -385.147848) (xy 43.377975 -385.163718) (xy 43.307101 -385.171704) (xy 43.235779 -385.171704)
			(xy 43.164905 -385.163718) (xy 43.09537 -385.147848) (xy 43.02805 -385.124291) (xy 42.963791 -385.093346)
			(xy 42.9034 -385.0554) (xy 42.847638 -385.010931) (xy 42.797205 -384.960498) (xy 42.752736 -384.904736)
			(xy 42.71479 -384.844345) (xy 42.683845 -384.780086) (xy 42.660288 -384.712766) (xy 42.644418 -384.643231)
			(xy 42.636432 -384.572357) (xy 41.665406 -384.572357) (xy 41.65742 -384.643231) (xy 41.64155 -384.712766)
			(xy 41.617993 -384.780086) (xy 41.587048 -384.844345) (xy 41.549102 -384.904736) (xy 41.504633 -384.960498)
			(xy 41.4542 -385.010931) (xy 41.398438 -385.0554) (xy 41.338047 -385.093346) (xy 41.273788 -385.124291)
			(xy 41.206468 -385.147848) (xy 41.136933 -385.163718) (xy 41.066059 -385.171704) (xy 40.994737 -385.171704)
			(xy 40.923863 -385.163718) (xy 40.854328 -385.147848) (xy 40.787008 -385.124291) (xy 40.722749 -385.093346)
			(xy 40.662358 -385.0554) (xy 40.606596 -385.010931) (xy 40.556163 -384.960498) (xy 40.511694 -384.904736)
			(xy 40.473748 -384.844345) (xy 40.442803 -384.780086) (xy 40.419246 -384.712766) (xy 40.403376 -384.643231)
			(xy 40.39539 -384.572357) (xy 39.778694 -384.572357) (xy 39.770708 -384.643231) (xy 39.754838 -384.712766)
			(xy 39.731281 -384.780086) (xy 39.700336 -384.844345) (xy 39.66239 -384.904736) (xy 39.617921 -384.960498)
			(xy 39.567488 -385.010931) (xy 39.511726 -385.0554) (xy 39.451335 -385.093346) (xy 39.387076 -385.124291)
			(xy 39.319756 -385.147848) (xy 39.250221 -385.163718) (xy 39.179347 -385.171704) (xy 39.108025 -385.171704)
			(xy 39.037151 -385.163718) (xy 38.967616 -385.147848) (xy 38.900296 -385.124291) (xy 38.836037 -385.093346)
			(xy 38.775646 -385.0554) (xy 38.719884 -385.010931) (xy 38.669451 -384.960498) (xy 38.624982 -384.904736)
			(xy 38.587036 -384.844345) (xy 38.556091 -384.780086) (xy 38.532534 -384.712766) (xy 38.516664 -384.643231)
			(xy 38.508678 -384.572357) (xy 29.254196 -384.572357) (xy 29.254196 -386.173488) (xy 29.519874 -386.173488)
			(xy 29.519874 -386.086588) (xy 29.527892 -386.000059) (xy 29.54386 -385.914639) (xy 29.567641 -385.831057)
			(xy 29.599033 -385.750025) (xy 29.637767 -385.672236) (xy 29.683514 -385.598352) (xy 29.735883 -385.529005)
			(xy 29.794427 -385.464785) (xy 29.858647 -385.406241) (xy 29.927994 -385.353872) (xy 30.001878 -385.308125)
			(xy 30.079667 -385.269391) (xy 30.160699 -385.237999) (xy 30.244281 -385.214218) (xy 30.329701 -385.19825)
			(xy 30.41623 -385.190232) (xy 30.50313 -385.190232) (xy 30.589659 -385.19825) (xy 30.675079 -385.214218)
			(xy 30.758661 -385.237999) (xy 30.839693 -385.269391) (xy 30.917482 -385.308125) (xy 30.991366 -385.353872)
			(xy 31.060713 -385.406241) (xy 31.124933 -385.464785) (xy 31.183477 -385.529005) (xy 31.235846 -385.598352)
			(xy 31.281593 -385.672236) (xy 31.320327 -385.750025) (xy 31.351719 -385.831057) (xy 31.3755 -385.914639)
			(xy 31.391468 -386.000059) (xy 31.399486 -386.086588) (xy 31.399988 -386.130038) (xy 31.399486 -386.173488)
			(xy 34.599874 -386.173488) (xy 34.599874 -386.086588) (xy 34.607892 -386.000059) (xy 34.62386 -385.914639)
			(xy 34.647641 -385.831057) (xy 34.679033 -385.750025) (xy 34.717767 -385.672236) (xy 34.763514 -385.598352)
			(xy 34.815883 -385.529005) (xy 34.874427 -385.464785) (xy 34.938647 -385.406241) (xy 35.007994 -385.353872)
			(xy 35.081878 -385.308125) (xy 35.159667 -385.269391) (xy 35.240699 -385.237999) (xy 35.324281 -385.214218)
			(xy 35.409701 -385.19825) (xy 35.49623 -385.190232) (xy 35.58313 -385.190232) (xy 35.669659 -385.19825)
			(xy 35.755079 -385.214218) (xy 35.838661 -385.237999) (xy 35.919693 -385.269391) (xy 35.997482 -385.308125)
			(xy 36.071366 -385.353872) (xy 36.140713 -385.406241) (xy 36.204933 -385.464785) (xy 36.263477 -385.529005)
			(xy 36.315846 -385.598352) (xy 36.361593 -385.672236) (xy 36.400327 -385.750025) (xy 36.431719 -385.831057)
			(xy 36.4555 -385.914639) (xy 36.471468 -386.000059) (xy 36.479486 -386.086588) (xy 36.479988 -386.130038)
			(xy 36.479486 -386.173488) (xy 36.472629 -386.247487) (xy 38.508678 -386.247487) (xy 38.508678 -386.176165)
			(xy 38.516664 -386.105291) (xy 38.532534 -386.035756) (xy 38.556091 -385.968436) (xy 38.587036 -385.904177)
			(xy 38.624982 -385.843786) (xy 38.669451 -385.788024) (xy 38.719884 -385.737591) (xy 38.775646 -385.693122)
			(xy 38.836037 -385.655176) (xy 38.900296 -385.624231) (xy 38.967616 -385.600674) (xy 39.037151 -385.584804)
			(xy 39.108025 -385.576818) (xy 39.179347 -385.576818) (xy 39.250221 -385.584804) (xy 39.319756 -385.600674)
			(xy 39.387076 -385.624231) (xy 39.451335 -385.655176) (xy 39.511726 -385.693122) (xy 39.567488 -385.737591)
			(xy 39.617921 -385.788024) (xy 39.66239 -385.843786) (xy 39.700336 -385.904177) (xy 39.731281 -385.968436)
			(xy 39.754838 -386.035756) (xy 39.770708 -386.105291) (xy 39.778694 -386.176165) (xy 39.779194 -386.211826)
			(xy 39.778694 -386.247487) (xy 40.39539 -386.247487) (xy 40.39539 -386.176165) (xy 40.403376 -386.105291)
			(xy 40.419246 -386.035756) (xy 40.442803 -385.968436) (xy 40.473748 -385.904177) (xy 40.511694 -385.843786)
			(xy 40.556163 -385.788024) (xy 40.606596 -385.737591) (xy 40.662358 -385.693122) (xy 40.722749 -385.655176)
			(xy 40.787008 -385.624231) (xy 40.854328 -385.600674) (xy 40.923863 -385.584804) (xy 40.994737 -385.576818)
			(xy 41.066059 -385.576818) (xy 41.136933 -385.584804) (xy 41.206468 -385.600674) (xy 41.273788 -385.624231)
			(xy 41.338047 -385.655176) (xy 41.398438 -385.693122) (xy 41.4542 -385.737591) (xy 41.504633 -385.788024)
			(xy 41.549102 -385.843786) (xy 41.587048 -385.904177) (xy 41.617993 -385.968436) (xy 41.64155 -386.035756)
			(xy 41.65742 -386.105291) (xy 41.665406 -386.176165) (xy 41.665906 -386.211826) (xy 41.665406 -386.247487)
			(xy 42.636432 -386.247487) (xy 42.636432 -386.176165) (xy 42.644418 -386.105291) (xy 42.660288 -386.035756)
			(xy 42.683845 -385.968436) (xy 42.71479 -385.904177) (xy 42.752736 -385.843786) (xy 42.797205 -385.788024)
			(xy 42.847638 -385.737591) (xy 42.9034 -385.693122) (xy 42.963791 -385.655176) (xy 43.02805 -385.624231)
			(xy 43.09537 -385.600674) (xy 43.164905 -385.584804) (xy 43.235779 -385.576818) (xy 43.307101 -385.576818)
			(xy 43.377975 -385.584804) (xy 43.44751 -385.600674) (xy 43.51483 -385.624231) (xy 43.579089 -385.655176)
			(xy 43.63948 -385.693122) (xy 43.695242 -385.737591) (xy 43.745675 -385.788024) (xy 43.790144 -385.843786)
			(xy 43.82809 -385.904177) (xy 43.859035 -385.968436) (xy 43.882592 -386.035756) (xy 43.898462 -386.105291)
			(xy 43.906448 -386.176165) (xy 43.906948 -386.211826) (xy 43.906448 -386.247487) (xy 44.540416 -386.247487)
			(xy 44.540416 -386.176165) (xy 44.548402 -386.105291) (xy 44.564272 -386.035756) (xy 44.587829 -385.968436)
			(xy 44.618774 -385.904177) (xy 44.65672 -385.843786) (xy 44.701189 -385.788024) (xy 44.751622 -385.737591)
			(xy 44.807384 -385.693122) (xy 44.867775 -385.655176) (xy 44.932034 -385.624231) (xy 44.999354 -385.600674)
			(xy 45.068889 -385.584804) (xy 45.139763 -385.576818) (xy 45.211085 -385.576818) (xy 45.281959 -385.584804)
			(xy 45.351494 -385.600674) (xy 45.418814 -385.624231) (xy 45.483073 -385.655176) (xy 45.543464 -385.693122)
			(xy 45.599226 -385.737591) (xy 45.649659 -385.788024) (xy 45.694128 -385.843786) (xy 45.732074 -385.904177)
			(xy 45.763019 -385.968436) (xy 45.786576 -386.035756) (xy 45.802446 -386.105291) (xy 45.810432 -386.176165)
			(xy 45.810932 -386.211826) (xy 45.810432 -386.247487) (xy 45.802446 -386.318361) (xy 45.786576 -386.387896)
			(xy 45.763019 -386.455216) (xy 45.732074 -386.519475) (xy 45.694128 -386.579866) (xy 45.649659 -386.635628)
			(xy 45.599226 -386.686061) (xy 45.543464 -386.73053) (xy 45.483073 -386.768476) (xy 45.418814 -386.799421)
			(xy 45.351494 -386.822978) (xy 45.281959 -386.838848) (xy 45.211085 -386.846834) (xy 45.139763 -386.846834)
			(xy 45.068889 -386.838848) (xy 44.999354 -386.822978) (xy 44.932034 -386.799421) (xy 44.867775 -386.768476)
			(xy 44.807384 -386.73053) (xy 44.751622 -386.686061) (xy 44.701189 -386.635628) (xy 44.65672 -386.579866)
			(xy 44.618774 -386.519475) (xy 44.587829 -386.455216) (xy 44.564272 -386.387896) (xy 44.548402 -386.318361)
			(xy 44.540416 -386.247487) (xy 43.906448 -386.247487) (xy 43.898462 -386.318361) (xy 43.882592 -386.387896)
			(xy 43.859035 -386.455216) (xy 43.82809 -386.519475) (xy 43.790144 -386.579866) (xy 43.745675 -386.635628)
			(xy 43.695242 -386.686061) (xy 43.63948 -386.73053) (xy 43.579089 -386.768476) (xy 43.51483 -386.799421)
			(xy 43.44751 -386.822978) (xy 43.377975 -386.838848) (xy 43.307101 -386.846834) (xy 43.235779 -386.846834)
			(xy 43.164905 -386.838848) (xy 43.09537 -386.822978) (xy 43.02805 -386.799421) (xy 42.963791 -386.768476)
			(xy 42.9034 -386.73053) (xy 42.847638 -386.686061) (xy 42.797205 -386.635628) (xy 42.752736 -386.579866)
			(xy 42.71479 -386.519475) (xy 42.683845 -386.455216) (xy 42.660288 -386.387896) (xy 42.644418 -386.318361)
			(xy 42.636432 -386.247487) (xy 41.665406 -386.247487) (xy 41.65742 -386.318361) (xy 41.64155 -386.387896)
			(xy 41.617993 -386.455216) (xy 41.587048 -386.519475) (xy 41.549102 -386.579866) (xy 41.504633 -386.635628)
			(xy 41.4542 -386.686061) (xy 41.398438 -386.73053) (xy 41.338047 -386.768476) (xy 41.273788 -386.799421)
			(xy 41.206468 -386.822978) (xy 41.136933 -386.838848) (xy 41.066059 -386.846834) (xy 40.994737 -386.846834)
			(xy 40.923863 -386.838848) (xy 40.854328 -386.822978) (xy 40.787008 -386.799421) (xy 40.722749 -386.768476)
			(xy 40.662358 -386.73053) (xy 40.606596 -386.686061) (xy 40.556163 -386.635628) (xy 40.511694 -386.579866)
			(xy 40.473748 -386.519475) (xy 40.442803 -386.455216) (xy 40.419246 -386.387896) (xy 40.403376 -386.318361)
			(xy 40.39539 -386.247487) (xy 39.778694 -386.247487) (xy 39.770708 -386.318361) (xy 39.754838 -386.387896)
			(xy 39.731281 -386.455216) (xy 39.700336 -386.519475) (xy 39.66239 -386.579866) (xy 39.617921 -386.635628)
			(xy 39.567488 -386.686061) (xy 39.511726 -386.73053) (xy 39.451335 -386.768476) (xy 39.387076 -386.799421)
			(xy 39.319756 -386.822978) (xy 39.250221 -386.838848) (xy 39.179347 -386.846834) (xy 39.108025 -386.846834)
			(xy 39.037151 -386.838848) (xy 38.967616 -386.822978) (xy 38.900296 -386.799421) (xy 38.836037 -386.768476)
			(xy 38.775646 -386.73053) (xy 38.719884 -386.686061) (xy 38.669451 -386.635628) (xy 38.624982 -386.579866)
			(xy 38.587036 -386.519475) (xy 38.556091 -386.455216) (xy 38.532534 -386.387896) (xy 38.516664 -386.318361)
			(xy 38.508678 -386.247487) (xy 36.472629 -386.247487) (xy 36.471468 -386.260017) (xy 36.4555 -386.345437)
			(xy 36.431719 -386.429019) (xy 36.400327 -386.510051) (xy 36.361593 -386.58784) (xy 36.315846 -386.661724)
			(xy 36.263477 -386.731071) (xy 36.204933 -386.795291) (xy 36.140713 -386.853835) (xy 36.071366 -386.906204)
			(xy 35.997482 -386.951951) (xy 35.919693 -386.990685) (xy 35.838661 -387.022077) (xy 35.755079 -387.045858)
			(xy 35.669659 -387.061826) (xy 35.58313 -387.069844) (xy 35.49623 -387.069844) (xy 35.409701 -387.061826)
			(xy 35.324281 -387.045858) (xy 35.240699 -387.022077) (xy 35.159667 -386.990685) (xy 35.081878 -386.951951)
			(xy 35.007994 -386.906204) (xy 34.938647 -386.853835) (xy 34.874427 -386.795291) (xy 34.815883 -386.731071)
			(xy 34.763514 -386.661724) (xy 34.717767 -386.58784) (xy 34.679033 -386.510051) (xy 34.647641 -386.429019)
			(xy 34.62386 -386.345437) (xy 34.607892 -386.260017) (xy 34.599874 -386.173488) (xy 31.399486 -386.173488)
			(xy 31.391468 -386.260017) (xy 31.3755 -386.345437) (xy 31.351719 -386.429019) (xy 31.320327 -386.510051)
			(xy 31.281593 -386.58784) (xy 31.235846 -386.661724) (xy 31.183477 -386.731071) (xy 31.124933 -386.795291)
			(xy 31.060713 -386.853835) (xy 30.991366 -386.906204) (xy 30.917482 -386.951951) (xy 30.839693 -386.990685)
			(xy 30.758661 -387.022077) (xy 30.675079 -387.045858) (xy 30.589659 -387.061826) (xy 30.50313 -387.069844)
			(xy 30.41623 -387.069844) (xy 30.329701 -387.061826) (xy 30.244281 -387.045858) (xy 30.160699 -387.022077)
			(xy 30.079667 -386.990685) (xy 30.001878 -386.951951) (xy 29.927994 -386.906204) (xy 29.858647 -386.853835)
			(xy 29.794427 -386.795291) (xy 29.735883 -386.731071) (xy 29.683514 -386.661724) (xy 29.637767 -386.58784)
			(xy 29.599033 -386.510051) (xy 29.567641 -386.429019) (xy 29.54386 -386.345437) (xy 29.527892 -386.260017)
			(xy 29.519874 -386.173488) (xy 29.254196 -386.173488) (xy 29.254196 -388.713488) (xy 29.519874 -388.713488)
			(xy 29.519874 -388.626588) (xy 29.527892 -388.540059) (xy 29.54386 -388.454639) (xy 29.567641 -388.371057)
			(xy 29.599033 -388.290025) (xy 29.637767 -388.212236) (xy 29.683514 -388.138352) (xy 29.735883 -388.069005)
			(xy 29.794427 -388.004785) (xy 29.858647 -387.946241) (xy 29.927994 -387.893872) (xy 30.001878 -387.848125)
			(xy 30.079667 -387.809391) (xy 30.160699 -387.777999) (xy 30.244281 -387.754218) (xy 30.329701 -387.73825)
			(xy 30.41623 -387.730232) (xy 30.50313 -387.730232) (xy 30.589659 -387.73825) (xy 30.675079 -387.754218)
			(xy 30.758661 -387.777999) (xy 30.839693 -387.809391) (xy 30.917482 -387.848125) (xy 30.991366 -387.893872)
			(xy 31.060713 -387.946241) (xy 31.124933 -388.004785) (xy 31.183477 -388.069005) (xy 31.235846 -388.138352)
			(xy 31.281593 -388.212236) (xy 31.320327 -388.290025) (xy 31.351719 -388.371057) (xy 31.3755 -388.454639)
			(xy 31.391468 -388.540059) (xy 31.399486 -388.626588) (xy 31.399988 -388.670038) (xy 31.399486 -388.713488)
			(xy 34.599874 -388.713488) (xy 34.599874 -388.626588) (xy 34.607892 -388.540059) (xy 34.62386 -388.454639)
			(xy 34.647641 -388.371057) (xy 34.679033 -388.290025) (xy 34.717767 -388.212236) (xy 34.763514 -388.138352)
			(xy 34.815883 -388.069005) (xy 34.874427 -388.004785) (xy 34.938647 -387.946241) (xy 35.007994 -387.893872)
			(xy 35.081878 -387.848125) (xy 35.159667 -387.809391) (xy 35.240699 -387.777999) (xy 35.324281 -387.754218)
			(xy 35.409701 -387.73825) (xy 35.49623 -387.730232) (xy 35.58313 -387.730232) (xy 35.669659 -387.73825)
			(xy 35.755079 -387.754218) (xy 35.838661 -387.777999) (xy 35.919693 -387.809391) (xy 35.997482 -387.848125)
			(xy 36.071366 -387.893872) (xy 36.140713 -387.946241) (xy 36.204933 -388.004785) (xy 36.263477 -388.069005)
			(xy 36.315846 -388.138352) (xy 36.361593 -388.212236) (xy 36.384709 -388.258659) (xy 38.465244 -388.258659)
			(xy 38.465244 -388.187337) (xy 38.47323 -388.116463) (xy 38.4891 -388.046928) (xy 38.512657 -387.979608)
			(xy 38.543602 -387.915349) (xy 38.581548 -387.854958) (xy 38.626017 -387.799196) (xy 38.67645 -387.748763)
			(xy 38.732212 -387.704294) (xy 38.792603 -387.666348) (xy 38.856862 -387.635403) (xy 38.924182 -387.611846)
			(xy 38.993717 -387.595976) (xy 39.064591 -387.58799) (xy 39.135913 -387.58799) (xy 39.206787 -387.595976)
			(xy 39.276322 -387.611846) (xy 39.343642 -387.635403) (xy 39.407901 -387.666348) (xy 39.468292 -387.704294)
			(xy 39.524054 -387.748763) (xy 39.574487 -387.799196) (xy 39.618956 -387.854958) (xy 39.656902 -387.915349)
			(xy 39.687847 -387.979608) (xy 39.711404 -388.046928) (xy 39.727274 -388.116463) (xy 39.73526 -388.187337)
			(xy 39.73576 -388.222998) (xy 39.73526 -388.258659) (xy 40.351956 -388.258659) (xy 40.351956 -388.187337)
			(xy 40.359942 -388.116463) (xy 40.375812 -388.046928) (xy 40.399369 -387.979608) (xy 40.430314 -387.915349)
			(xy 40.46826 -387.854958) (xy 40.512729 -387.799196) (xy 40.563162 -387.748763) (xy 40.618924 -387.704294)
			(xy 40.679315 -387.666348) (xy 40.743574 -387.635403) (xy 40.810894 -387.611846) (xy 40.880429 -387.595976)
			(xy 40.951303 -387.58799) (xy 41.022625 -387.58799) (xy 41.093499 -387.595976) (xy 41.163034 -387.611846)
			(xy 41.230354 -387.635403) (xy 41.294613 -387.666348) (xy 41.355004 -387.704294) (xy 41.410766 -387.748763)
			(xy 41.461199 -387.799196) (xy 41.505668 -387.854958) (xy 41.543614 -387.915349) (xy 41.574559 -387.979608)
			(xy 41.598116 -388.046928) (xy 41.613986 -388.116463) (xy 41.621972 -388.187337) (xy 41.622472 -388.222998)
			(xy 41.621972 -388.258659) (xy 42.592998 -388.258659) (xy 42.592998 -388.187337) (xy 42.600984 -388.116463)
			(xy 42.616854 -388.046928) (xy 42.640411 -387.979608) (xy 42.671356 -387.915349) (xy 42.709302 -387.854958)
			(xy 42.753771 -387.799196) (xy 42.804204 -387.748763) (xy 42.859966 -387.704294) (xy 42.920357 -387.666348)
			(xy 42.984616 -387.635403) (xy 43.051936 -387.611846) (xy 43.121471 -387.595976) (xy 43.192345 -387.58799)
			(xy 43.263667 -387.58799) (xy 43.334541 -387.595976) (xy 43.404076 -387.611846) (xy 43.471396 -387.635403)
			(xy 43.535655 -387.666348) (xy 43.596046 -387.704294) (xy 43.651808 -387.748763) (xy 43.702241 -387.799196)
			(xy 43.74671 -387.854958) (xy 43.784656 -387.915349) (xy 43.815601 -387.979608) (xy 43.839158 -388.046928)
			(xy 43.855028 -388.116463) (xy 43.863014 -388.187337) (xy 43.863514 -388.222998) (xy 43.863014 -388.258659)
			(xy 44.496982 -388.258659) (xy 44.496982 -388.187337) (xy 44.504968 -388.116463) (xy 44.520838 -388.046928)
			(xy 44.544395 -387.979608) (xy 44.57534 -387.915349) (xy 44.613286 -387.854958) (xy 44.657755 -387.799196)
			(xy 44.708188 -387.748763) (xy 44.76395 -387.704294) (xy 44.824341 -387.666348) (xy 44.8886 -387.635403)
			(xy 44.95592 -387.611846) (xy 45.025455 -387.595976) (xy 45.096329 -387.58799) (xy 45.167651 -387.58799)
			(xy 45.238525 -387.595976) (xy 45.30806 -387.611846) (xy 45.37538 -387.635403) (xy 45.439639 -387.666348)
			(xy 45.50003 -387.704294) (xy 45.555792 -387.748763) (xy 45.606225 -387.799196) (xy 45.650694 -387.854958)
			(xy 45.68864 -387.915349) (xy 45.719585 -387.979608) (xy 45.743142 -388.046928) (xy 45.759012 -388.116463)
			(xy 45.766998 -388.187337) (xy 45.767498 -388.222998) (xy 45.766998 -388.258659) (xy 45.759012 -388.329533)
			(xy 45.743142 -388.399068) (xy 45.719585 -388.466388) (xy 45.68864 -388.530647) (xy 45.650694 -388.591038)
			(xy 45.606225 -388.6468) (xy 45.555792 -388.697233) (xy 45.50003 -388.741702) (xy 45.439639 -388.779648)
			(xy 45.37538 -388.810593) (xy 45.30806 -388.83415) (xy 45.238525 -388.85002) (xy 45.167651 -388.858006)
			(xy 45.096329 -388.858006) (xy 45.025455 -388.85002) (xy 44.95592 -388.83415) (xy 44.8886 -388.810593)
			(xy 44.824341 -388.779648) (xy 44.76395 -388.741702) (xy 44.708188 -388.697233) (xy 44.657755 -388.6468)
			(xy 44.613286 -388.591038) (xy 44.57534 -388.530647) (xy 44.544395 -388.466388) (xy 44.520838 -388.399068)
			(xy 44.504968 -388.329533) (xy 44.496982 -388.258659) (xy 43.863014 -388.258659) (xy 43.855028 -388.329533)
			(xy 43.839158 -388.399068) (xy 43.815601 -388.466388) (xy 43.784656 -388.530647) (xy 43.74671 -388.591038)
			(xy 43.702241 -388.6468) (xy 43.651808 -388.697233) (xy 43.596046 -388.741702) (xy 43.535655 -388.779648)
			(xy 43.471396 -388.810593) (xy 43.404076 -388.83415) (xy 43.334541 -388.85002) (xy 43.263667 -388.858006)
			(xy 43.192345 -388.858006) (xy 43.121471 -388.85002) (xy 43.051936 -388.83415) (xy 42.984616 -388.810593)
			(xy 42.920357 -388.779648) (xy 42.859966 -388.741702) (xy 42.804204 -388.697233) (xy 42.753771 -388.6468)
			(xy 42.709302 -388.591038) (xy 42.671356 -388.530647) (xy 42.640411 -388.466388) (xy 42.616854 -388.399068)
			(xy 42.600984 -388.329533) (xy 42.592998 -388.258659) (xy 41.621972 -388.258659) (xy 41.613986 -388.329533)
			(xy 41.598116 -388.399068) (xy 41.574559 -388.466388) (xy 41.543614 -388.530647) (xy 41.505668 -388.591038)
			(xy 41.461199 -388.6468) (xy 41.410766 -388.697233) (xy 41.355004 -388.741702) (xy 41.294613 -388.779648)
			(xy 41.230354 -388.810593) (xy 41.163034 -388.83415) (xy 41.093499 -388.85002) (xy 41.022625 -388.858006)
			(xy 40.951303 -388.858006) (xy 40.880429 -388.85002) (xy 40.810894 -388.83415) (xy 40.743574 -388.810593)
			(xy 40.679315 -388.779648) (xy 40.618924 -388.741702) (xy 40.563162 -388.697233) (xy 40.512729 -388.6468)
			(xy 40.46826 -388.591038) (xy 40.430314 -388.530647) (xy 40.399369 -388.466388) (xy 40.375812 -388.399068)
			(xy 40.359942 -388.329533) (xy 40.351956 -388.258659) (xy 39.73526 -388.258659) (xy 39.727274 -388.329533)
			(xy 39.711404 -388.399068) (xy 39.687847 -388.466388) (xy 39.656902 -388.530647) (xy 39.618956 -388.591038)
			(xy 39.574487 -388.6468) (xy 39.524054 -388.697233) (xy 39.468292 -388.741702) (xy 39.407901 -388.779648)
			(xy 39.343642 -388.810593) (xy 39.276322 -388.83415) (xy 39.206787 -388.85002) (xy 39.135913 -388.858006)
			(xy 39.064591 -388.858006) (xy 38.993717 -388.85002) (xy 38.924182 -388.83415) (xy 38.856862 -388.810593)
			(xy 38.792603 -388.779648) (xy 38.732212 -388.741702) (xy 38.67645 -388.697233) (xy 38.626017 -388.6468)
			(xy 38.581548 -388.591038) (xy 38.543602 -388.530647) (xy 38.512657 -388.466388) (xy 38.4891 -388.399068)
			(xy 38.47323 -388.329533) (xy 38.465244 -388.258659) (xy 36.384709 -388.258659) (xy 36.400327 -388.290025)
			(xy 36.431719 -388.371057) (xy 36.4555 -388.454639) (xy 36.471468 -388.540059) (xy 36.479486 -388.626588)
			(xy 36.479988 -388.670038) (xy 36.479486 -388.713488) (xy 36.471468 -388.800017) (xy 36.4555 -388.885437)
			(xy 36.431719 -388.969019) (xy 36.400327 -389.050051) (xy 36.361593 -389.12784) (xy 36.315846 -389.201724)
			(xy 36.263477 -389.271071) (xy 36.204933 -389.335291) (xy 36.140713 -389.393835) (xy 36.071366 -389.446204)
			(xy 35.997482 -389.491951) (xy 35.919693 -389.530685) (xy 35.838661 -389.562077) (xy 35.755079 -389.585858)
			(xy 35.669659 -389.601826) (xy 35.58313 -389.609844) (xy 35.49623 -389.609844) (xy 35.409701 -389.601826)
			(xy 35.324281 -389.585858) (xy 35.240699 -389.562077) (xy 35.159667 -389.530685) (xy 35.081878 -389.491951)
			(xy 35.007994 -389.446204) (xy 34.938647 -389.393835) (xy 34.874427 -389.335291) (xy 34.815883 -389.271071)
			(xy 34.763514 -389.201724) (xy 34.717767 -389.12784) (xy 34.679033 -389.050051) (xy 34.647641 -388.969019)
			(xy 34.62386 -388.885437) (xy 34.607892 -388.800017) (xy 34.599874 -388.713488) (xy 31.399486 -388.713488)
			(xy 31.391468 -388.800017) (xy 31.3755 -388.885437) (xy 31.351719 -388.969019) (xy 31.320327 -389.050051)
			(xy 31.281593 -389.12784) (xy 31.235846 -389.201724) (xy 31.183477 -389.271071) (xy 31.124933 -389.335291)
			(xy 31.060713 -389.393835) (xy 30.991366 -389.446204) (xy 30.917482 -389.491951) (xy 30.839693 -389.530685)
			(xy 30.758661 -389.562077) (xy 30.675079 -389.585858) (xy 30.589659 -389.601826) (xy 30.50313 -389.609844)
			(xy 30.41623 -389.609844) (xy 30.329701 -389.601826) (xy 30.244281 -389.585858) (xy 30.160699 -389.562077)
			(xy 30.079667 -389.530685) (xy 30.001878 -389.491951) (xy 29.927994 -389.446204) (xy 29.858647 -389.393835)
			(xy 29.794427 -389.335291) (xy 29.735883 -389.271071) (xy 29.683514 -389.201724) (xy 29.637767 -389.12784)
			(xy 29.599033 -389.050051) (xy 29.567641 -388.969019) (xy 29.54386 -388.885437) (xy 29.527892 -388.800017)
			(xy 29.519874 -388.713488) (xy 29.254196 -388.713488) (xy 29.254196 -390.149181) (xy 38.465244 -390.149181)
			(xy 38.465244 -390.077859) (xy 38.47323 -390.006985) (xy 38.4891 -389.93745) (xy 38.512657 -389.87013)
			(xy 38.543602 -389.805871) (xy 38.581548 -389.74548) (xy 38.626017 -389.689718) (xy 38.67645 -389.639285)
			(xy 38.732212 -389.594816) (xy 38.792603 -389.55687) (xy 38.856862 -389.525925) (xy 38.924182 -389.502368)
			(xy 38.993717 -389.486498) (xy 39.064591 -389.478512) (xy 39.135913 -389.478512) (xy 39.206787 -389.486498)
			(xy 39.276322 -389.502368) (xy 39.343642 -389.525925) (xy 39.407901 -389.55687) (xy 39.468292 -389.594816)
			(xy 39.524054 -389.639285) (xy 39.574487 -389.689718) (xy 39.618956 -389.74548) (xy 39.656902 -389.805871)
			(xy 39.687847 -389.87013) (xy 39.711404 -389.93745) (xy 39.727274 -390.006985) (xy 39.73526 -390.077859)
			(xy 39.73576 -390.11352) (xy 39.73526 -390.149181) (xy 40.351956 -390.149181) (xy 40.351956 -390.077859)
			(xy 40.359942 -390.006985) (xy 40.375812 -389.93745) (xy 40.399369 -389.87013) (xy 40.430314 -389.805871)
			(xy 40.46826 -389.74548) (xy 40.512729 -389.689718) (xy 40.563162 -389.639285) (xy 40.618924 -389.594816)
			(xy 40.679315 -389.55687) (xy 40.743574 -389.525925) (xy 40.810894 -389.502368) (xy 40.880429 -389.486498)
			(xy 40.951303 -389.478512) (xy 41.022625 -389.478512) (xy 41.093499 -389.486498) (xy 41.163034 -389.502368)
			(xy 41.230354 -389.525925) (xy 41.294613 -389.55687) (xy 41.355004 -389.594816) (xy 41.410766 -389.639285)
			(xy 41.461199 -389.689718) (xy 41.505668 -389.74548) (xy 41.543614 -389.805871) (xy 41.574559 -389.87013)
			(xy 41.598116 -389.93745) (xy 41.613986 -390.006985) (xy 41.621972 -390.077859) (xy 41.622472 -390.11352)
			(xy 41.621972 -390.149181) (xy 42.592998 -390.149181) (xy 42.592998 -390.077859) (xy 42.600984 -390.006985)
			(xy 42.616854 -389.93745) (xy 42.640411 -389.87013) (xy 42.671356 -389.805871) (xy 42.709302 -389.74548)
			(xy 42.753771 -389.689718) (xy 42.804204 -389.639285) (xy 42.859966 -389.594816) (xy 42.920357 -389.55687)
			(xy 42.984616 -389.525925) (xy 43.051936 -389.502368) (xy 43.121471 -389.486498) (xy 43.192345 -389.478512)
			(xy 43.263667 -389.478512) (xy 43.334541 -389.486498) (xy 43.404076 -389.502368) (xy 43.471396 -389.525925)
			(xy 43.535655 -389.55687) (xy 43.596046 -389.594816) (xy 43.651808 -389.639285) (xy 43.702241 -389.689718)
			(xy 43.74671 -389.74548) (xy 43.784656 -389.805871) (xy 43.815601 -389.87013) (xy 43.839158 -389.93745)
			(xy 43.855028 -390.006985) (xy 43.863014 -390.077859) (xy 43.863514 -390.11352) (xy 43.863014 -390.149181)
			(xy 44.496982 -390.149181) (xy 44.496982 -390.077859) (xy 44.504968 -390.006985) (xy 44.520838 -389.93745)
			(xy 44.544395 -389.87013) (xy 44.57534 -389.805871) (xy 44.613286 -389.74548) (xy 44.657755 -389.689718)
			(xy 44.708188 -389.639285) (xy 44.76395 -389.594816) (xy 44.824341 -389.55687) (xy 44.8886 -389.525925)
			(xy 44.95592 -389.502368) (xy 45.025455 -389.486498) (xy 45.096329 -389.478512) (xy 45.167651 -389.478512)
			(xy 45.238525 -389.486498) (xy 45.30806 -389.502368) (xy 45.37538 -389.525925) (xy 45.439639 -389.55687)
			(xy 45.50003 -389.594816) (xy 45.555792 -389.639285) (xy 45.606225 -389.689718) (xy 45.650694 -389.74548)
			(xy 45.68864 -389.805871) (xy 45.719585 -389.87013) (xy 45.743142 -389.93745) (xy 45.759012 -390.006985)
			(xy 45.766998 -390.077859) (xy 45.767498 -390.11352) (xy 45.766998 -390.149181) (xy 45.759012 -390.220055)
			(xy 45.743142 -390.28959) (xy 45.719585 -390.35691) (xy 45.68864 -390.421169) (xy 45.650694 -390.48156)
			(xy 45.606225 -390.537322) (xy 45.555792 -390.587755) (xy 45.50003 -390.632224) (xy 45.439639 -390.67017)
			(xy 45.37538 -390.701115) (xy 45.30806 -390.724672) (xy 45.238525 -390.740542) (xy 45.167651 -390.748528)
			(xy 45.096329 -390.748528) (xy 45.025455 -390.740542) (xy 44.95592 -390.724672) (xy 44.8886 -390.701115)
			(xy 44.824341 -390.67017) (xy 44.76395 -390.632224) (xy 44.708188 -390.587755) (xy 44.657755 -390.537322)
			(xy 44.613286 -390.48156) (xy 44.57534 -390.421169) (xy 44.544395 -390.35691) (xy 44.520838 -390.28959)
			(xy 44.504968 -390.220055) (xy 44.496982 -390.149181) (xy 43.863014 -390.149181) (xy 43.855028 -390.220055)
			(xy 43.839158 -390.28959) (xy 43.815601 -390.35691) (xy 43.784656 -390.421169) (xy 43.74671 -390.48156)
			(xy 43.702241 -390.537322) (xy 43.651808 -390.587755) (xy 43.596046 -390.632224) (xy 43.535655 -390.67017)
			(xy 43.471396 -390.701115) (xy 43.404076 -390.724672) (xy 43.334541 -390.740542) (xy 43.263667 -390.748528)
			(xy 43.192345 -390.748528) (xy 43.121471 -390.740542) (xy 43.051936 -390.724672) (xy 42.984616 -390.701115)
			(xy 42.920357 -390.67017) (xy 42.859966 -390.632224) (xy 42.804204 -390.587755) (xy 42.753771 -390.537322)
			(xy 42.709302 -390.48156) (xy 42.671356 -390.421169) (xy 42.640411 -390.35691) (xy 42.616854 -390.28959)
			(xy 42.600984 -390.220055) (xy 42.592998 -390.149181) (xy 41.621972 -390.149181) (xy 41.613986 -390.220055)
			(xy 41.598116 -390.28959) (xy 41.574559 -390.35691) (xy 41.543614 -390.421169) (xy 41.505668 -390.48156)
			(xy 41.461199 -390.537322) (xy 41.410766 -390.587755) (xy 41.355004 -390.632224) (xy 41.294613 -390.67017)
			(xy 41.230354 -390.701115) (xy 41.163034 -390.724672) (xy 41.093499 -390.740542) (xy 41.022625 -390.748528)
			(xy 40.951303 -390.748528) (xy 40.880429 -390.740542) (xy 40.810894 -390.724672) (xy 40.743574 -390.701115)
			(xy 40.679315 -390.67017) (xy 40.618924 -390.632224) (xy 40.563162 -390.587755) (xy 40.512729 -390.537322)
			(xy 40.46826 -390.48156) (xy 40.430314 -390.421169) (xy 40.399369 -390.35691) (xy 40.375812 -390.28959)
			(xy 40.359942 -390.220055) (xy 40.351956 -390.149181) (xy 39.73526 -390.149181) (xy 39.727274 -390.220055)
			(xy 39.711404 -390.28959) (xy 39.687847 -390.35691) (xy 39.656902 -390.421169) (xy 39.618956 -390.48156)
			(xy 39.574487 -390.537322) (xy 39.524054 -390.587755) (xy 39.468292 -390.632224) (xy 39.407901 -390.67017)
			(xy 39.343642 -390.701115) (xy 39.276322 -390.724672) (xy 39.206787 -390.740542) (xy 39.135913 -390.748528)
			(xy 39.064591 -390.748528) (xy 38.993717 -390.740542) (xy 38.924182 -390.724672) (xy 38.856862 -390.701115)
			(xy 38.792603 -390.67017) (xy 38.732212 -390.632224) (xy 38.67645 -390.587755) (xy 38.626017 -390.537322)
			(xy 38.581548 -390.48156) (xy 38.543602 -390.421169) (xy 38.512657 -390.35691) (xy 38.4891 -390.28959)
			(xy 38.47323 -390.220055) (xy 38.465244 -390.149181) (xy 29.254196 -390.149181) (xy 29.254196 -391.253488)
			(xy 29.519874 -391.253488) (xy 29.519874 -391.166588) (xy 29.527892 -391.080059) (xy 29.54386 -390.994639)
			(xy 29.567641 -390.911057) (xy 29.599033 -390.830025) (xy 29.637767 -390.752236) (xy 29.683514 -390.678352)
			(xy 29.735883 -390.609005) (xy 29.794427 -390.544785) (xy 29.858647 -390.486241) (xy 29.927994 -390.433872)
			(xy 30.001878 -390.388125) (xy 30.079667 -390.349391) (xy 30.160699 -390.317999) (xy 30.244281 -390.294218)
			(xy 30.329701 -390.27825) (xy 30.41623 -390.270232) (xy 30.50313 -390.270232) (xy 30.589659 -390.27825)
			(xy 30.675079 -390.294218) (xy 30.758661 -390.317999) (xy 30.839693 -390.349391) (xy 30.917482 -390.388125)
			(xy 30.991366 -390.433872) (xy 31.060713 -390.486241) (xy 31.124933 -390.544785) (xy 31.183477 -390.609005)
			(xy 31.235846 -390.678352) (xy 31.281593 -390.752236) (xy 31.320327 -390.830025) (xy 31.351719 -390.911057)
			(xy 31.3755 -390.994639) (xy 31.391468 -391.080059) (xy 31.399486 -391.166588) (xy 31.399988 -391.210038)
			(xy 31.399486 -391.253488) (xy 34.599874 -391.253488) (xy 34.599874 -391.166588) (xy 34.607892 -391.080059)
			(xy 34.62386 -390.994639) (xy 34.647641 -390.911057) (xy 34.679033 -390.830025) (xy 34.717767 -390.752236)
			(xy 34.763514 -390.678352) (xy 34.815883 -390.609005) (xy 34.874427 -390.544785) (xy 34.938647 -390.486241)
			(xy 35.007994 -390.433872) (xy 35.081878 -390.388125) (xy 35.159667 -390.349391) (xy 35.240699 -390.317999)
			(xy 35.324281 -390.294218) (xy 35.409701 -390.27825) (xy 35.49623 -390.270232) (xy 35.58313 -390.270232)
			(xy 35.669659 -390.27825) (xy 35.755079 -390.294218) (xy 35.838661 -390.317999) (xy 35.919693 -390.349391)
			(xy 35.997482 -390.388125) (xy 36.071366 -390.433872) (xy 36.140713 -390.486241) (xy 36.204933 -390.544785)
			(xy 36.263477 -390.609005) (xy 36.315846 -390.678352) (xy 36.361593 -390.752236) (xy 36.400327 -390.830025)
			(xy 36.431719 -390.911057) (xy 36.4555 -390.994639) (xy 36.471468 -391.080059) (xy 36.479486 -391.166588)
			(xy 36.479988 -391.210038) (xy 36.479486 -391.253488) (xy 36.471468 -391.340017) (xy 36.4555 -391.425437)
			(xy 36.431719 -391.509019) (xy 36.400327 -391.590051) (xy 36.361593 -391.66784) (xy 36.315846 -391.741724)
			(xy 36.263477 -391.811071) (xy 36.204933 -391.875291) (xy 36.140713 -391.933835) (xy 36.071366 -391.986204)
			(xy 35.997482 -392.031951) (xy 35.919693 -392.070685) (xy 35.838661 -392.102077) (xy 35.755079 -392.125858)
			(xy 35.669659 -392.141826) (xy 35.58313 -392.149844) (xy 35.49623 -392.149844) (xy 35.409701 -392.141826)
			(xy 35.324281 -392.125858) (xy 35.240699 -392.102077) (xy 35.159667 -392.070685) (xy 35.081878 -392.031951)
			(xy 35.007994 -391.986204) (xy 34.938647 -391.933835) (xy 34.874427 -391.875291) (xy 34.815883 -391.811071)
			(xy 34.763514 -391.741724) (xy 34.717767 -391.66784) (xy 34.679033 -391.590051) (xy 34.647641 -391.509019)
			(xy 34.62386 -391.425437) (xy 34.607892 -391.340017) (xy 34.599874 -391.253488) (xy 31.399486 -391.253488)
			(xy 31.391468 -391.340017) (xy 31.3755 -391.425437) (xy 31.351719 -391.509019) (xy 31.320327 -391.590051)
			(xy 31.281593 -391.66784) (xy 31.235846 -391.741724) (xy 31.183477 -391.811071) (xy 31.124933 -391.875291)
			(xy 31.060713 -391.933835) (xy 30.991366 -391.986204) (xy 30.917482 -392.031951) (xy 30.839693 -392.070685)
			(xy 30.758661 -392.102077) (xy 30.675079 -392.125858) (xy 30.589659 -392.141826) (xy 30.50313 -392.149844)
			(xy 30.41623 -392.149844) (xy 30.329701 -392.141826) (xy 30.244281 -392.125858) (xy 30.160699 -392.102077)
			(xy 30.079667 -392.070685) (xy 30.001878 -392.031951) (xy 29.927994 -391.986204) (xy 29.858647 -391.933835)
			(xy 29.794427 -391.875291) (xy 29.735883 -391.811071) (xy 29.683514 -391.741724) (xy 29.637767 -391.66784)
			(xy 29.599033 -391.590051) (xy 29.567641 -391.509019) (xy 29.54386 -391.425437) (xy 29.527892 -391.340017)
			(xy 29.519874 -391.253488) (xy 29.254196 -391.253488) (xy 29.254196 -392.190325) (xy 38.465244 -392.190325)
			(xy 38.465244 -392.119003) (xy 38.47323 -392.048129) (xy 38.4891 -391.978594) (xy 38.512657 -391.911274)
			(xy 38.543602 -391.847015) (xy 38.581548 -391.786624) (xy 38.626017 -391.730862) (xy 38.67645 -391.680429)
			(xy 38.732212 -391.63596) (xy 38.792603 -391.598014) (xy 38.856862 -391.567069) (xy 38.924182 -391.543512)
			(xy 38.993717 -391.527642) (xy 39.064591 -391.519656) (xy 39.135913 -391.519656) (xy 39.206787 -391.527642)
			(xy 39.276322 -391.543512) (xy 39.343642 -391.567069) (xy 39.407901 -391.598014) (xy 39.468292 -391.63596)
			(xy 39.524054 -391.680429) (xy 39.574487 -391.730862) (xy 39.618956 -391.786624) (xy 39.656902 -391.847015)
			(xy 39.687847 -391.911274) (xy 39.711404 -391.978594) (xy 39.727274 -392.048129) (xy 39.73526 -392.119003)
			(xy 39.73576 -392.154664) (xy 39.73526 -392.190325) (xy 40.351956 -392.190325) (xy 40.351956 -392.119003)
			(xy 40.359942 -392.048129) (xy 40.375812 -391.978594) (xy 40.399369 -391.911274) (xy 40.430314 -391.847015)
			(xy 40.46826 -391.786624) (xy 40.512729 -391.730862) (xy 40.563162 -391.680429) (xy 40.618924 -391.63596)
			(xy 40.679315 -391.598014) (xy 40.743574 -391.567069) (xy 40.810894 -391.543512) (xy 40.880429 -391.527642)
			(xy 40.951303 -391.519656) (xy 41.022625 -391.519656) (xy 41.093499 -391.527642) (xy 41.163034 -391.543512)
			(xy 41.230354 -391.567069) (xy 41.294613 -391.598014) (xy 41.355004 -391.63596) (xy 41.410766 -391.680429)
			(xy 41.461199 -391.730862) (xy 41.505668 -391.786624) (xy 41.543614 -391.847015) (xy 41.574559 -391.911274)
			(xy 41.598116 -391.978594) (xy 41.613986 -392.048129) (xy 41.621972 -392.119003) (xy 41.622472 -392.154664)
			(xy 41.621972 -392.190325) (xy 42.592998 -392.190325) (xy 42.592998 -392.119003) (xy 42.600984 -392.048129)
			(xy 42.616854 -391.978594) (xy 42.640411 -391.911274) (xy 42.671356 -391.847015) (xy 42.709302 -391.786624)
			(xy 42.753771 -391.730862) (xy 42.804204 -391.680429) (xy 42.859966 -391.63596) (xy 42.920357 -391.598014)
			(xy 42.984616 -391.567069) (xy 43.051936 -391.543512) (xy 43.121471 -391.527642) (xy 43.192345 -391.519656)
			(xy 43.263667 -391.519656) (xy 43.334541 -391.527642) (xy 43.404076 -391.543512) (xy 43.471396 -391.567069)
			(xy 43.535655 -391.598014) (xy 43.596046 -391.63596) (xy 43.651808 -391.680429) (xy 43.702241 -391.730862)
			(xy 43.74671 -391.786624) (xy 43.784656 -391.847015) (xy 43.815601 -391.911274) (xy 43.839158 -391.978594)
			(xy 43.855028 -392.048129) (xy 43.863014 -392.119003) (xy 43.863514 -392.154664) (xy 43.863014 -392.190325)
			(xy 44.496982 -392.190325) (xy 44.496982 -392.119003) (xy 44.504968 -392.048129) (xy 44.520838 -391.978594)
			(xy 44.544395 -391.911274) (xy 44.57534 -391.847015) (xy 44.613286 -391.786624) (xy 44.657755 -391.730862)
			(xy 44.708188 -391.680429) (xy 44.76395 -391.63596) (xy 44.824341 -391.598014) (xy 44.8886 -391.567069)
			(xy 44.95592 -391.543512) (xy 45.025455 -391.527642) (xy 45.096329 -391.519656) (xy 45.167651 -391.519656)
			(xy 45.238525 -391.527642) (xy 45.30806 -391.543512) (xy 45.37538 -391.567069) (xy 45.439639 -391.598014)
			(xy 45.50003 -391.63596) (xy 45.555792 -391.680429) (xy 45.606225 -391.730862) (xy 45.650694 -391.786624)
			(xy 45.68864 -391.847015) (xy 45.719585 -391.911274) (xy 45.743142 -391.978594) (xy 45.759012 -392.048129)
			(xy 45.766998 -392.119003) (xy 45.767498 -392.154664) (xy 45.766998 -392.190325) (xy 45.759012 -392.261199)
			(xy 45.743142 -392.330734) (xy 45.719585 -392.398054) (xy 45.68864 -392.462313) (xy 45.650694 -392.522704)
			(xy 45.606225 -392.578466) (xy 45.555792 -392.628899) (xy 45.50003 -392.673368) (xy 45.439639 -392.711314)
			(xy 45.37538 -392.742259) (xy 45.30806 -392.765816) (xy 45.238525 -392.781686) (xy 45.167651 -392.789672)
			(xy 45.096329 -392.789672) (xy 45.025455 -392.781686) (xy 44.95592 -392.765816) (xy 44.8886 -392.742259)
			(xy 44.824341 -392.711314) (xy 44.76395 -392.673368) (xy 44.708188 -392.628899) (xy 44.657755 -392.578466)
			(xy 44.613286 -392.522704) (xy 44.57534 -392.462313) (xy 44.544395 -392.398054) (xy 44.520838 -392.330734)
			(xy 44.504968 -392.261199) (xy 44.496982 -392.190325) (xy 43.863014 -392.190325) (xy 43.855028 -392.261199)
			(xy 43.839158 -392.330734) (xy 43.815601 -392.398054) (xy 43.784656 -392.462313) (xy 43.74671 -392.522704)
			(xy 43.702241 -392.578466) (xy 43.651808 -392.628899) (xy 43.596046 -392.673368) (xy 43.535655 -392.711314)
			(xy 43.471396 -392.742259) (xy 43.404076 -392.765816) (xy 43.334541 -392.781686) (xy 43.263667 -392.789672)
			(xy 43.192345 -392.789672) (xy 43.121471 -392.781686) (xy 43.051936 -392.765816) (xy 42.984616 -392.742259)
			(xy 42.920357 -392.711314) (xy 42.859966 -392.673368) (xy 42.804204 -392.628899) (xy 42.753771 -392.578466)
			(xy 42.709302 -392.522704) (xy 42.671356 -392.462313) (xy 42.640411 -392.398054) (xy 42.616854 -392.330734)
			(xy 42.600984 -392.261199) (xy 42.592998 -392.190325) (xy 41.621972 -392.190325) (xy 41.613986 -392.261199)
			(xy 41.598116 -392.330734) (xy 41.574559 -392.398054) (xy 41.543614 -392.462313) (xy 41.505668 -392.522704)
			(xy 41.461199 -392.578466) (xy 41.410766 -392.628899) (xy 41.355004 -392.673368) (xy 41.294613 -392.711314)
			(xy 41.230354 -392.742259) (xy 41.163034 -392.765816) (xy 41.093499 -392.781686) (xy 41.022625 -392.789672)
			(xy 40.951303 -392.789672) (xy 40.880429 -392.781686) (xy 40.810894 -392.765816) (xy 40.743574 -392.742259)
			(xy 40.679315 -392.711314) (xy 40.618924 -392.673368) (xy 40.563162 -392.628899) (xy 40.512729 -392.578466)
			(xy 40.46826 -392.522704) (xy 40.430314 -392.462313) (xy 40.399369 -392.398054) (xy 40.375812 -392.330734)
			(xy 40.359942 -392.261199) (xy 40.351956 -392.190325) (xy 39.73526 -392.190325) (xy 39.727274 -392.261199)
			(xy 39.711404 -392.330734) (xy 39.687847 -392.398054) (xy 39.656902 -392.462313) (xy 39.618956 -392.522704)
			(xy 39.574487 -392.578466) (xy 39.524054 -392.628899) (xy 39.468292 -392.673368) (xy 39.407901 -392.711314)
			(xy 39.343642 -392.742259) (xy 39.276322 -392.765816) (xy 39.206787 -392.781686) (xy 39.135913 -392.789672)
			(xy 39.064591 -392.789672) (xy 38.993717 -392.781686) (xy 38.924182 -392.765816) (xy 38.856862 -392.742259)
			(xy 38.792603 -392.711314) (xy 38.732212 -392.673368) (xy 38.67645 -392.628899) (xy 38.626017 -392.578466)
			(xy 38.581548 -392.522704) (xy 38.543602 -392.462313) (xy 38.512657 -392.398054) (xy 38.4891 -392.330734)
			(xy 38.47323 -392.261199) (xy 38.465244 -392.190325) (xy 29.254196 -392.190325) (xy 29.254196 -393.793488)
			(xy 29.519874 -393.793488) (xy 29.519874 -393.706588) (xy 29.527892 -393.620059) (xy 29.54386 -393.534639)
			(xy 29.567641 -393.451057) (xy 29.599033 -393.370025) (xy 29.637767 -393.292236) (xy 29.683514 -393.218352)
			(xy 29.735883 -393.149005) (xy 29.794427 -393.084785) (xy 29.858647 -393.026241) (xy 29.927994 -392.973872)
			(xy 30.001878 -392.928125) (xy 30.079667 -392.889391) (xy 30.160699 -392.857999) (xy 30.244281 -392.834218)
			(xy 30.329701 -392.81825) (xy 30.41623 -392.810232) (xy 30.50313 -392.810232) (xy 30.589659 -392.81825)
			(xy 30.675079 -392.834218) (xy 30.758661 -392.857999) (xy 30.839693 -392.889391) (xy 30.917482 -392.928125)
			(xy 30.991366 -392.973872) (xy 31.060713 -393.026241) (xy 31.124933 -393.084785) (xy 31.183477 -393.149005)
			(xy 31.235846 -393.218352) (xy 31.281593 -393.292236) (xy 31.320327 -393.370025) (xy 31.351719 -393.451057)
			(xy 31.3755 -393.534639) (xy 31.391468 -393.620059) (xy 31.399486 -393.706588) (xy 31.399988 -393.750038)
			(xy 31.399486 -393.793488) (xy 34.599874 -393.793488) (xy 34.599874 -393.706588) (xy 34.607892 -393.620059)
			(xy 34.62386 -393.534639) (xy 34.647641 -393.451057) (xy 34.679033 -393.370025) (xy 34.717767 -393.292236)
			(xy 34.763514 -393.218352) (xy 34.815883 -393.149005) (xy 34.874427 -393.084785) (xy 34.938647 -393.026241)
			(xy 35.007994 -392.973872) (xy 35.081878 -392.928125) (xy 35.159667 -392.889391) (xy 35.240699 -392.857999)
			(xy 35.324281 -392.834218) (xy 35.409701 -392.81825) (xy 35.49623 -392.810232) (xy 35.58313 -392.810232)
			(xy 35.669659 -392.81825) (xy 35.755079 -392.834218) (xy 35.838661 -392.857999) (xy 35.919693 -392.889391)
			(xy 35.997482 -392.928125) (xy 36.071366 -392.973872) (xy 36.140713 -393.026241) (xy 36.204933 -393.084785)
			(xy 36.263477 -393.149005) (xy 36.315846 -393.218352) (xy 36.361593 -393.292236) (xy 36.400327 -393.370025)
			(xy 36.431719 -393.451057) (xy 36.4555 -393.534639) (xy 36.471468 -393.620059) (xy 36.479486 -393.706588)
			(xy 36.479988 -393.750038) (xy 36.479486 -393.793488) (xy 36.471468 -393.880017) (xy 36.4555 -393.965437)
			(xy 36.431719 -394.049019) (xy 36.41191 -394.100151) (xy 38.465244 -394.100151) (xy 38.465244 -394.028829)
			(xy 38.47323 -393.957955) (xy 38.4891 -393.88842) (xy 38.512657 -393.8211) (xy 38.543602 -393.756841)
			(xy 38.581548 -393.69645) (xy 38.626017 -393.640688) (xy 38.67645 -393.590255) (xy 38.732212 -393.545786)
			(xy 38.792603 -393.50784) (xy 38.856862 -393.476895) (xy 38.924182 -393.453338) (xy 38.993717 -393.437468)
			(xy 39.064591 -393.429482) (xy 39.135913 -393.429482) (xy 39.206787 -393.437468) (xy 39.276322 -393.453338)
			(xy 39.343642 -393.476895) (xy 39.407901 -393.50784) (xy 39.468292 -393.545786) (xy 39.524054 -393.590255)
			(xy 39.574487 -393.640688) (xy 39.618956 -393.69645) (xy 39.656902 -393.756841) (xy 39.687847 -393.8211)
			(xy 39.711404 -393.88842) (xy 39.727274 -393.957955) (xy 39.73526 -394.028829) (xy 39.73576 -394.06449)
			(xy 39.73526 -394.100151) (xy 40.351956 -394.100151) (xy 40.351956 -394.028829) (xy 40.359942 -393.957955)
			(xy 40.375812 -393.88842) (xy 40.399369 -393.8211) (xy 40.430314 -393.756841) (xy 40.46826 -393.69645)
			(xy 40.512729 -393.640688) (xy 40.563162 -393.590255) (xy 40.618924 -393.545786) (xy 40.679315 -393.50784)
			(xy 40.743574 -393.476895) (xy 40.810894 -393.453338) (xy 40.880429 -393.437468) (xy 40.951303 -393.429482)
			(xy 41.022625 -393.429482) (xy 41.093499 -393.437468) (xy 41.163034 -393.453338) (xy 41.230354 -393.476895)
			(xy 41.294613 -393.50784) (xy 41.355004 -393.545786) (xy 41.410766 -393.590255) (xy 41.461199 -393.640688)
			(xy 41.505668 -393.69645) (xy 41.543614 -393.756841) (xy 41.574559 -393.8211) (xy 41.598116 -393.88842)
			(xy 41.613986 -393.957955) (xy 41.621972 -394.028829) (xy 41.622472 -394.06449) (xy 41.621972 -394.100151)
			(xy 42.592998 -394.100151) (xy 42.592998 -394.028829) (xy 42.600984 -393.957955) (xy 42.616854 -393.88842)
			(xy 42.640411 -393.8211) (xy 42.671356 -393.756841) (xy 42.709302 -393.69645) (xy 42.753771 -393.640688)
			(xy 42.804204 -393.590255) (xy 42.859966 -393.545786) (xy 42.920357 -393.50784) (xy 42.984616 -393.476895)
			(xy 43.051936 -393.453338) (xy 43.121471 -393.437468) (xy 43.192345 -393.429482) (xy 43.263667 -393.429482)
			(xy 43.334541 -393.437468) (xy 43.404076 -393.453338) (xy 43.471396 -393.476895) (xy 43.535655 -393.50784)
			(xy 43.596046 -393.545786) (xy 43.651808 -393.590255) (xy 43.702241 -393.640688) (xy 43.74671 -393.69645)
			(xy 43.784656 -393.756841) (xy 43.815601 -393.8211) (xy 43.839158 -393.88842) (xy 43.855028 -393.957955)
			(xy 43.863014 -394.028829) (xy 43.863514 -394.06449) (xy 43.863014 -394.100151) (xy 44.496982 -394.100151)
			(xy 44.496982 -394.028829) (xy 44.504968 -393.957955) (xy 44.520838 -393.88842) (xy 44.544395 -393.8211)
			(xy 44.57534 -393.756841) (xy 44.613286 -393.69645) (xy 44.657755 -393.640688) (xy 44.708188 -393.590255)
			(xy 44.76395 -393.545786) (xy 44.824341 -393.50784) (xy 44.8886 -393.476895) (xy 44.95592 -393.453338)
			(xy 45.025455 -393.437468) (xy 45.096329 -393.429482) (xy 45.167651 -393.429482) (xy 45.238525 -393.437468)
			(xy 45.30806 -393.453338) (xy 45.37538 -393.476895) (xy 45.439639 -393.50784) (xy 45.50003 -393.545786)
			(xy 45.555792 -393.590255) (xy 45.606225 -393.640688) (xy 45.650694 -393.69645) (xy 45.68864 -393.756841)
			(xy 45.719585 -393.8211) (xy 45.743142 -393.88842) (xy 45.759012 -393.957955) (xy 45.766998 -394.028829)
			(xy 45.767498 -394.06449) (xy 45.766998 -394.100151) (xy 45.759012 -394.171025) (xy 45.743142 -394.24056)
			(xy 45.719585 -394.30788) (xy 45.68864 -394.372139) (xy 45.650694 -394.43253) (xy 45.606225 -394.488292)
			(xy 45.555792 -394.538725) (xy 45.50003 -394.583194) (xy 45.439639 -394.62114) (xy 45.37538 -394.652085)
			(xy 45.30806 -394.675642) (xy 45.238525 -394.691512) (xy 45.167651 -394.699498) (xy 45.096329 -394.699498)
			(xy 45.025455 -394.691512) (xy 44.95592 -394.675642) (xy 44.8886 -394.652085) (xy 44.824341 -394.62114)
			(xy 44.76395 -394.583194) (xy 44.708188 -394.538725) (xy 44.657755 -394.488292) (xy 44.613286 -394.43253)
			(xy 44.57534 -394.372139) (xy 44.544395 -394.30788) (xy 44.520838 -394.24056) (xy 44.504968 -394.171025)
			(xy 44.496982 -394.100151) (xy 43.863014 -394.100151) (xy 43.855028 -394.171025) (xy 43.839158 -394.24056)
			(xy 43.815601 -394.30788) (xy 43.784656 -394.372139) (xy 43.74671 -394.43253) (xy 43.702241 -394.488292)
			(xy 43.651808 -394.538725) (xy 43.596046 -394.583194) (xy 43.535655 -394.62114) (xy 43.471396 -394.652085)
			(xy 43.404076 -394.675642) (xy 43.334541 -394.691512) (xy 43.263667 -394.699498) (xy 43.192345 -394.699498)
			(xy 43.121471 -394.691512) (xy 43.051936 -394.675642) (xy 42.984616 -394.652085) (xy 42.920357 -394.62114)
			(xy 42.859966 -394.583194) (xy 42.804204 -394.538725) (xy 42.753771 -394.488292) (xy 42.709302 -394.43253)
			(xy 42.671356 -394.372139) (xy 42.640411 -394.30788) (xy 42.616854 -394.24056) (xy 42.600984 -394.171025)
			(xy 42.592998 -394.100151) (xy 41.621972 -394.100151) (xy 41.613986 -394.171025) (xy 41.598116 -394.24056)
			(xy 41.574559 -394.30788) (xy 41.543614 -394.372139) (xy 41.505668 -394.43253) (xy 41.461199 -394.488292)
			(xy 41.410766 -394.538725) (xy 41.355004 -394.583194) (xy 41.294613 -394.62114) (xy 41.230354 -394.652085)
			(xy 41.163034 -394.675642) (xy 41.093499 -394.691512) (xy 41.022625 -394.699498) (xy 40.951303 -394.699498)
			(xy 40.880429 -394.691512) (xy 40.810894 -394.675642) (xy 40.743574 -394.652085) (xy 40.679315 -394.62114)
			(xy 40.618924 -394.583194) (xy 40.563162 -394.538725) (xy 40.512729 -394.488292) (xy 40.46826 -394.43253)
			(xy 40.430314 -394.372139) (xy 40.399369 -394.30788) (xy 40.375812 -394.24056) (xy 40.359942 -394.171025)
			(xy 40.351956 -394.100151) (xy 39.73526 -394.100151) (xy 39.727274 -394.171025) (xy 39.711404 -394.24056)
			(xy 39.687847 -394.30788) (xy 39.656902 -394.372139) (xy 39.618956 -394.43253) (xy 39.574487 -394.488292)
			(xy 39.524054 -394.538725) (xy 39.468292 -394.583194) (xy 39.407901 -394.62114) (xy 39.343642 -394.652085)
			(xy 39.276322 -394.675642) (xy 39.206787 -394.691512) (xy 39.135913 -394.699498) (xy 39.064591 -394.699498)
			(xy 38.993717 -394.691512) (xy 38.924182 -394.675642) (xy 38.856862 -394.652085) (xy 38.792603 -394.62114)
			(xy 38.732212 -394.583194) (xy 38.67645 -394.538725) (xy 38.626017 -394.488292) (xy 38.581548 -394.43253)
			(xy 38.543602 -394.372139) (xy 38.512657 -394.30788) (xy 38.4891 -394.24056) (xy 38.47323 -394.171025)
			(xy 38.465244 -394.100151) (xy 36.41191 -394.100151) (xy 36.400327 -394.130051) (xy 36.361593 -394.20784)
			(xy 36.315846 -394.281724) (xy 36.263477 -394.351071) (xy 36.204933 -394.415291) (xy 36.140713 -394.473835)
			(xy 36.071366 -394.526204) (xy 35.997482 -394.571951) (xy 35.919693 -394.610685) (xy 35.838661 -394.642077)
			(xy 35.755079 -394.665858) (xy 35.669659 -394.681826) (xy 35.58313 -394.689844) (xy 35.49623 -394.689844)
			(xy 35.409701 -394.681826) (xy 35.324281 -394.665858) (xy 35.240699 -394.642077) (xy 35.159667 -394.610685)
			(xy 35.081878 -394.571951) (xy 35.007994 -394.526204) (xy 34.938647 -394.473835) (xy 34.874427 -394.415291)
			(xy 34.815883 -394.351071) (xy 34.763514 -394.281724) (xy 34.717767 -394.20784) (xy 34.679033 -394.130051)
			(xy 34.647641 -394.049019) (xy 34.62386 -393.965437) (xy 34.607892 -393.880017) (xy 34.599874 -393.793488)
			(xy 31.399486 -393.793488) (xy 31.391468 -393.880017) (xy 31.3755 -393.965437) (xy 31.351719 -394.049019)
			(xy 31.320327 -394.130051) (xy 31.281593 -394.20784) (xy 31.235846 -394.281724) (xy 31.183477 -394.351071)
			(xy 31.124933 -394.415291) (xy 31.060713 -394.473835) (xy 30.991366 -394.526204) (xy 30.917482 -394.571951)
			(xy 30.839693 -394.610685) (xy 30.758661 -394.642077) (xy 30.675079 -394.665858) (xy 30.589659 -394.681826)
			(xy 30.50313 -394.689844) (xy 30.41623 -394.689844) (xy 30.329701 -394.681826) (xy 30.244281 -394.665858)
			(xy 30.160699 -394.642077) (xy 30.079667 -394.610685) (xy 30.001878 -394.571951) (xy 29.927994 -394.526204)
			(xy 29.858647 -394.473835) (xy 29.794427 -394.415291) (xy 29.735883 -394.351071) (xy 29.683514 -394.281724)
			(xy 29.637767 -394.20784) (xy 29.599033 -394.130051) (xy 29.567641 -394.049019) (xy 29.54386 -393.965437)
			(xy 29.527892 -393.880017) (xy 29.519874 -393.793488) (xy 29.254196 -393.793488) (xy 29.254196 -396.333488)
			(xy 29.519874 -396.333488) (xy 29.519874 -396.246588) (xy 29.527892 -396.160059) (xy 29.54386 -396.074639)
			(xy 29.567641 -395.991057) (xy 29.599033 -395.910025) (xy 29.637767 -395.832236) (xy 29.683514 -395.758352)
			(xy 29.735883 -395.689005) (xy 29.794427 -395.624785) (xy 29.858647 -395.566241) (xy 29.927994 -395.513872)
			(xy 30.001878 -395.468125) (xy 30.079667 -395.429391) (xy 30.160699 -395.397999) (xy 30.244281 -395.374218)
			(xy 30.329701 -395.35825) (xy 30.41623 -395.350232) (xy 30.50313 -395.350232) (xy 30.589659 -395.35825)
			(xy 30.675079 -395.374218) (xy 30.758661 -395.397999) (xy 30.839693 -395.429391) (xy 30.917482 -395.468125)
			(xy 30.991366 -395.513872) (xy 31.060713 -395.566241) (xy 31.124933 -395.624785) (xy 31.183477 -395.689005)
			(xy 31.235846 -395.758352) (xy 31.281593 -395.832236) (xy 31.320327 -395.910025) (xy 31.351719 -395.991057)
			(xy 31.3755 -396.074639) (xy 31.391468 -396.160059) (xy 31.399486 -396.246588) (xy 31.399988 -396.290038)
			(xy 31.399486 -396.333488) (xy 34.599874 -396.333488) (xy 34.599874 -396.246588) (xy 34.607892 -396.160059)
			(xy 34.62386 -396.074639) (xy 34.647641 -395.991057) (xy 34.679033 -395.910025) (xy 34.717767 -395.832236)
			(xy 34.763514 -395.758352) (xy 34.815883 -395.689005) (xy 34.874427 -395.624785) (xy 34.938647 -395.566241)
			(xy 35.007994 -395.513872) (xy 35.081878 -395.468125) (xy 35.159667 -395.429391) (xy 35.240699 -395.397999)
			(xy 35.324281 -395.374218) (xy 35.409701 -395.35825) (xy 35.49623 -395.350232) (xy 35.58313 -395.350232)
			(xy 35.669659 -395.35825) (xy 35.755079 -395.374218) (xy 35.838661 -395.397999) (xy 35.919693 -395.429391)
			(xy 35.997482 -395.468125) (xy 36.071366 -395.513872) (xy 36.140713 -395.566241) (xy 36.165583 -395.588913)
			(xy 47.708556 -395.588913) (xy 47.708556 -395.507803) (xy 47.716506 -395.427084) (xy 47.732329 -395.347533)
			(xy 47.755874 -395.269917) (xy 47.786913 -395.194981) (xy 47.825148 -395.123449) (xy 47.87021 -395.056009)
			(xy 47.921665 -394.99331) (xy 47.979018 -394.935957) (xy 48.041717 -394.884502) (xy 48.109157 -394.83944)
			(xy 48.180689 -394.801205) (xy 48.255625 -394.770166) (xy 48.333241 -394.746621) (xy 48.412792 -394.730798)
			(xy 48.493511 -394.722848) (xy 48.574621 -394.722848) (xy 48.65534 -394.730798) (xy 48.734891 -394.746621)
			(xy 48.812507 -394.770166) (xy 48.887443 -394.801205) (xy 48.958975 -394.83944) (xy 49.026415 -394.884502)
			(xy 49.089114 -394.935957) (xy 49.146467 -394.99331) (xy 49.197922 -395.056009) (xy 49.242984 -395.123449)
			(xy 49.281219 -395.194981) (xy 49.312258 -395.269917) (xy 49.335803 -395.347533) (xy 49.351626 -395.427084)
			(xy 49.359576 -395.507803) (xy 49.360074 -395.548358) (xy 49.359576 -395.588913) (xy 49.351626 -395.669632)
			(xy 49.335803 -395.749183) (xy 49.312258 -395.826799) (xy 49.281219 -395.901735) (xy 49.242984 -395.973267)
			(xy 49.197922 -396.040707) (xy 49.146467 -396.103406) (xy 49.089114 -396.160759) (xy 49.026415 -396.212214)
			(xy 48.958975 -396.257276) (xy 48.887443 -396.295511) (xy 48.812507 -396.32655) (xy 48.734891 -396.350095)
			(xy 48.65534 -396.365918) (xy 48.574621 -396.373868) (xy 48.493511 -396.373868) (xy 48.412792 -396.365918)
			(xy 48.333241 -396.350095) (xy 48.255625 -396.32655) (xy 48.180689 -396.295511) (xy 48.109157 -396.257276)
			(xy 48.041717 -396.212214) (xy 47.979018 -396.160759) (xy 47.921665 -396.103406) (xy 47.87021 -396.040707)
			(xy 47.825148 -395.973267) (xy 47.786913 -395.901735) (xy 47.755874 -395.826799) (xy 47.732329 -395.749183)
			(xy 47.716506 -395.669632) (xy 47.708556 -395.588913) (xy 36.165583 -395.588913) (xy 36.204933 -395.624785)
			(xy 36.263477 -395.689005) (xy 36.315846 -395.758352) (xy 36.361593 -395.832236) (xy 36.400327 -395.910025)
			(xy 36.431719 -395.991057) (xy 36.4555 -396.074639) (xy 36.471468 -396.160059) (xy 36.479486 -396.246588)
			(xy 36.479988 -396.290038) (xy 36.479486 -396.333488) (xy 36.471468 -396.420017) (xy 36.4555 -396.505437)
			(xy 36.431719 -396.589019) (xy 36.400327 -396.670051) (xy 36.361593 -396.74784) (xy 36.315846 -396.821724)
			(xy 36.263477 -396.891071) (xy 36.204933 -396.955291) (xy 36.140713 -397.013835) (xy 36.071366 -397.066204)
			(xy 35.997482 -397.111951) (xy 35.919693 -397.150685) (xy 35.838661 -397.182077) (xy 35.755079 -397.205858)
			(xy 35.669659 -397.221826) (xy 35.58313 -397.229844) (xy 35.49623 -397.229844) (xy 35.409701 -397.221826)
			(xy 35.324281 -397.205858) (xy 35.240699 -397.182077) (xy 35.159667 -397.150685) (xy 35.081878 -397.111951)
			(xy 35.007994 -397.066204) (xy 34.938647 -397.013835) (xy 34.874427 -396.955291) (xy 34.815883 -396.891071)
			(xy 34.763514 -396.821724) (xy 34.717767 -396.74784) (xy 34.679033 -396.670051) (xy 34.647641 -396.589019)
			(xy 34.62386 -396.505437) (xy 34.607892 -396.420017) (xy 34.599874 -396.333488) (xy 31.399486 -396.333488)
			(xy 31.391468 -396.420017) (xy 31.3755 -396.505437) (xy 31.351719 -396.589019) (xy 31.320327 -396.670051)
			(xy 31.281593 -396.74784) (xy 31.235846 -396.821724) (xy 31.183477 -396.891071) (xy 31.124933 -396.955291)
			(xy 31.060713 -397.013835) (xy 30.991366 -397.066204) (xy 30.917482 -397.111951) (xy 30.839693 -397.150685)
			(xy 30.758661 -397.182077) (xy 30.675079 -397.205858) (xy 30.589659 -397.221826) (xy 30.50313 -397.229844)
			(xy 30.41623 -397.229844) (xy 30.329701 -397.221826) (xy 30.244281 -397.205858) (xy 30.160699 -397.182077)
			(xy 30.079667 -397.150685) (xy 30.001878 -397.111951) (xy 29.927994 -397.066204) (xy 29.858647 -397.013835)
			(xy 29.794427 -396.955291) (xy 29.735883 -396.891071) (xy 29.683514 -396.821724) (xy 29.637767 -396.74784)
			(xy 29.599033 -396.670051) (xy 29.567641 -396.589019) (xy 29.54386 -396.505437) (xy 29.527892 -396.420017)
			(xy 29.519874 -396.333488) (xy 29.254196 -396.333488) (xy 29.254196 -398.873488) (xy 29.519874 -398.873488)
			(xy 29.519874 -398.786588) (xy 29.527892 -398.700059) (xy 29.54386 -398.614639) (xy 29.567641 -398.531057)
			(xy 29.599033 -398.450025) (xy 29.637767 -398.372236) (xy 29.683514 -398.298352) (xy 29.735883 -398.229005)
			(xy 29.794427 -398.164785) (xy 29.858647 -398.106241) (xy 29.927994 -398.053872) (xy 30.001878 -398.008125)
			(xy 30.079667 -397.969391) (xy 30.160699 -397.937999) (xy 30.244281 -397.914218) (xy 30.329701 -397.89825)
			(xy 30.41623 -397.890232) (xy 30.50313 -397.890232) (xy 30.589659 -397.89825) (xy 30.675079 -397.914218)
			(xy 30.758661 -397.937999) (xy 30.839693 -397.969391) (xy 30.917482 -398.008125) (xy 30.991366 -398.053872)
			(xy 31.060713 -398.106241) (xy 31.124933 -398.164785) (xy 31.183477 -398.229005) (xy 31.235846 -398.298352)
			(xy 31.281593 -398.372236) (xy 31.320327 -398.450025) (xy 31.351719 -398.531057) (xy 31.3755 -398.614639)
			(xy 31.391468 -398.700059) (xy 31.399486 -398.786588) (xy 31.399988 -398.830038) (xy 31.399486 -398.873488)
			(xy 34.599874 -398.873488) (xy 34.599874 -398.786588) (xy 34.607892 -398.700059) (xy 34.62386 -398.614639)
			(xy 34.647641 -398.531057) (xy 34.679033 -398.450025) (xy 34.717767 -398.372236) (xy 34.763514 -398.298352)
			(xy 34.815883 -398.229005) (xy 34.874427 -398.164785) (xy 34.938647 -398.106241) (xy 35.007994 -398.053872)
			(xy 35.081878 -398.008125) (xy 35.159667 -397.969391) (xy 35.240699 -397.937999) (xy 35.324281 -397.914218)
			(xy 35.409701 -397.89825) (xy 35.49623 -397.890232) (xy 35.58313 -397.890232) (xy 35.669659 -397.89825)
			(xy 35.755079 -397.914218) (xy 35.838661 -397.937999) (xy 35.919693 -397.969391) (xy 35.997482 -398.008125)
			(xy 36.071366 -398.053872) (xy 36.140713 -398.106241) (xy 36.204933 -398.164785) (xy 36.263477 -398.229005)
			(xy 36.315846 -398.298352) (xy 36.361593 -398.372236) (xy 36.400327 -398.450025) (xy 36.431719 -398.531057)
			(xy 36.4555 -398.614639) (xy 36.471468 -398.700059) (xy 36.479486 -398.786588) (xy 36.479988 -398.830038)
			(xy 36.479486 -398.873488) (xy 36.471468 -398.960017) (xy 36.4555 -399.045437) (xy 36.431719 -399.129019)
			(xy 36.400327 -399.210051) (xy 36.361593 -399.28784) (xy 36.315846 -399.361724) (xy 36.263477 -399.431071)
			(xy 36.204933 -399.495291) (xy 36.140713 -399.553835) (xy 36.071366 -399.606204) (xy 35.997482 -399.651951)
			(xy 35.919693 -399.690685) (xy 35.838661 -399.722077) (xy 35.755079 -399.745858) (xy 35.669659 -399.761826)
			(xy 35.58313 -399.769844) (xy 35.49623 -399.769844) (xy 35.409701 -399.761826) (xy 35.324281 -399.745858)
			(xy 35.240699 -399.722077) (xy 35.159667 -399.690685) (xy 35.081878 -399.651951) (xy 35.007994 -399.606204)
			(xy 34.938647 -399.553835) (xy 34.874427 -399.495291) (xy 34.815883 -399.431071) (xy 34.763514 -399.361724)
			(xy 34.717767 -399.28784) (xy 34.679033 -399.210051) (xy 34.647641 -399.129019) (xy 34.62386 -399.045437)
			(xy 34.607892 -398.960017) (xy 34.599874 -398.873488) (xy 31.399486 -398.873488) (xy 31.391468 -398.960017)
			(xy 31.3755 -399.045437) (xy 31.351719 -399.129019) (xy 31.320327 -399.210051) (xy 31.281593 -399.28784)
			(xy 31.235846 -399.361724) (xy 31.183477 -399.431071) (xy 31.124933 -399.495291) (xy 31.060713 -399.553835)
			(xy 30.991366 -399.606204) (xy 30.917482 -399.651951) (xy 30.839693 -399.690685) (xy 30.758661 -399.722077)
			(xy 30.675079 -399.745858) (xy 30.589659 -399.761826) (xy 30.50313 -399.769844) (xy 30.41623 -399.769844)
			(xy 30.329701 -399.761826) (xy 30.244281 -399.745858) (xy 30.160699 -399.722077) (xy 30.079667 -399.690685)
			(xy 30.001878 -399.651951) (xy 29.927994 -399.606204) (xy 29.858647 -399.553835) (xy 29.794427 -399.495291)
			(xy 29.735883 -399.431071) (xy 29.683514 -399.361724) (xy 29.637767 -399.28784) (xy 29.599033 -399.210051)
			(xy 29.567641 -399.129019) (xy 29.54386 -399.045437) (xy 29.527892 -398.960017) (xy 29.519874 -398.873488)
			(xy 29.254196 -398.873488) (xy 29.254196 -401.413488) (xy 29.519874 -401.413488) (xy 29.519874 -401.326588)
			(xy 29.527892 -401.240059) (xy 29.54386 -401.154639) (xy 29.567641 -401.071057) (xy 29.599033 -400.990025)
			(xy 29.637767 -400.912236) (xy 29.683514 -400.838352) (xy 29.735883 -400.769005) (xy 29.794427 -400.704785)
			(xy 29.858647 -400.646241) (xy 29.927994 -400.593872) (xy 30.001878 -400.548125) (xy 30.079667 -400.509391)
			(xy 30.160699 -400.477999) (xy 30.244281 -400.454218) (xy 30.329701 -400.43825) (xy 30.41623 -400.430232)
			(xy 30.50313 -400.430232) (xy 30.589659 -400.43825) (xy 30.675079 -400.454218) (xy 30.758661 -400.477999)
			(xy 30.839693 -400.509391) (xy 30.917482 -400.548125) (xy 30.991366 -400.593872) (xy 31.060713 -400.646241)
			(xy 31.124933 -400.704785) (xy 31.183477 -400.769005) (xy 31.235846 -400.838352) (xy 31.281593 -400.912236)
			(xy 31.320327 -400.990025) (xy 31.351719 -401.071057) (xy 31.3755 -401.154639) (xy 31.391468 -401.240059)
			(xy 31.399486 -401.326588) (xy 31.399988 -401.370038) (xy 31.399486 -401.413488) (xy 34.599874 -401.413488)
			(xy 34.599874 -401.326588) (xy 34.607892 -401.240059) (xy 34.62386 -401.154639) (xy 34.647641 -401.071057)
			(xy 34.679033 -400.990025) (xy 34.717767 -400.912236) (xy 34.763514 -400.838352) (xy 34.815883 -400.769005)
			(xy 34.874427 -400.704785) (xy 34.938647 -400.646241) (xy 35.007994 -400.593872) (xy 35.081878 -400.548125)
			(xy 35.159667 -400.509391) (xy 35.240699 -400.477999) (xy 35.324281 -400.454218) (xy 35.409701 -400.43825)
			(xy 35.49623 -400.430232) (xy 35.58313 -400.430232) (xy 35.669659 -400.43825) (xy 35.755079 -400.454218)
			(xy 35.838661 -400.477999) (xy 35.919693 -400.509391) (xy 35.997482 -400.548125) (xy 36.071366 -400.593872)
			(xy 36.140713 -400.646241) (xy 36.204933 -400.704785) (xy 36.263477 -400.769005) (xy 36.315846 -400.838352)
			(xy 36.361593 -400.912236) (xy 36.400327 -400.990025) (xy 36.431719 -401.071057) (xy 36.4555 -401.154639)
			(xy 36.471468 -401.240059) (xy 36.479486 -401.326588) (xy 36.479988 -401.370038) (xy 36.479486 -401.413488)
			(xy 36.471468 -401.500017) (xy 36.4555 -401.585437) (xy 36.431719 -401.669019) (xy 36.400327 -401.750051)
			(xy 36.361593 -401.82784) (xy 36.315846 -401.901724) (xy 36.263477 -401.971071) (xy 36.204933 -402.035291)
			(xy 36.140713 -402.093835) (xy 36.071366 -402.146204) (xy 35.997482 -402.191951) (xy 35.919693 -402.230685)
			(xy 35.838661 -402.262077) (xy 35.755079 -402.285858) (xy 35.669659 -402.301826) (xy 35.58313 -402.309844)
			(xy 35.49623 -402.309844) (xy 35.409701 -402.301826) (xy 35.324281 -402.285858) (xy 35.240699 -402.262077)
			(xy 35.159667 -402.230685) (xy 35.081878 -402.191951) (xy 35.007994 -402.146204) (xy 34.938647 -402.093835)
			(xy 34.874427 -402.035291) (xy 34.815883 -401.971071) (xy 34.763514 -401.901724) (xy 34.717767 -401.82784)
			(xy 34.679033 -401.750051) (xy 34.647641 -401.669019) (xy 34.62386 -401.585437) (xy 34.607892 -401.500017)
			(xy 34.599874 -401.413488) (xy 31.399486 -401.413488) (xy 31.391468 -401.500017) (xy 31.3755 -401.585437)
			(xy 31.351719 -401.669019) (xy 31.320327 -401.750051) (xy 31.281593 -401.82784) (xy 31.235846 -401.901724)
			(xy 31.183477 -401.971071) (xy 31.124933 -402.035291) (xy 31.060713 -402.093835) (xy 30.991366 -402.146204)
			(xy 30.917482 -402.191951) (xy 30.839693 -402.230685) (xy 30.758661 -402.262077) (xy 30.675079 -402.285858)
			(xy 30.589659 -402.301826) (xy 30.50313 -402.309844) (xy 30.41623 -402.309844) (xy 30.329701 -402.301826)
			(xy 30.244281 -402.285858) (xy 30.160699 -402.262077) (xy 30.079667 -402.230685) (xy 30.001878 -402.191951)
			(xy 29.927994 -402.146204) (xy 29.858647 -402.093835) (xy 29.794427 -402.035291) (xy 29.735883 -401.971071)
			(xy 29.683514 -401.901724) (xy 29.637767 -401.82784) (xy 29.599033 -401.750051) (xy 29.567641 -401.669019)
			(xy 29.54386 -401.585437) (xy 29.527892 -401.500017) (xy 29.519874 -401.413488) (xy 29.254196 -401.413488)
			(xy 29.254196 -403.953488) (xy 29.519874 -403.953488) (xy 29.519874 -403.866588) (xy 29.527892 -403.780059)
			(xy 29.54386 -403.694639) (xy 29.567641 -403.611057) (xy 29.599033 -403.530025) (xy 29.637767 -403.452236)
			(xy 29.683514 -403.378352) (xy 29.735883 -403.309005) (xy 29.794427 -403.244785) (xy 29.858647 -403.186241)
			(xy 29.927994 -403.133872) (xy 30.001878 -403.088125) (xy 30.079667 -403.049391) (xy 30.160699 -403.017999)
			(xy 30.244281 -402.994218) (xy 30.329701 -402.97825) (xy 30.41623 -402.970232) (xy 30.50313 -402.970232)
			(xy 30.589659 -402.97825) (xy 30.675079 -402.994218) (xy 30.758661 -403.017999) (xy 30.839693 -403.049391)
			(xy 30.917482 -403.088125) (xy 30.991366 -403.133872) (xy 31.060713 -403.186241) (xy 31.124933 -403.244785)
			(xy 31.183477 -403.309005) (xy 31.235846 -403.378352) (xy 31.281593 -403.452236) (xy 31.320327 -403.530025)
			(xy 31.351719 -403.611057) (xy 31.3755 -403.694639) (xy 31.391468 -403.780059) (xy 31.399486 -403.866588)
			(xy 31.399988 -403.910038) (xy 31.399486 -403.953488) (xy 34.599874 -403.953488) (xy 34.599874 -403.866588)
			(xy 34.607892 -403.780059) (xy 34.62386 -403.694639) (xy 34.647641 -403.611057) (xy 34.679033 -403.530025)
			(xy 34.717767 -403.452236) (xy 34.763514 -403.378352) (xy 34.815883 -403.309005) (xy 34.874427 -403.244785)
			(xy 34.938647 -403.186241) (xy 35.007994 -403.133872) (xy 35.081878 -403.088125) (xy 35.159667 -403.049391)
			(xy 35.240699 -403.017999) (xy 35.324281 -402.994218) (xy 35.409701 -402.97825) (xy 35.49623 -402.970232)
			(xy 35.58313 -402.970232) (xy 35.669659 -402.97825) (xy 35.755079 -402.994218) (xy 35.838661 -403.017999)
			(xy 35.919693 -403.049391) (xy 35.997482 -403.088125) (xy 36.071366 -403.133872) (xy 36.140713 -403.186241)
			(xy 36.204933 -403.244785) (xy 36.263477 -403.309005) (xy 36.315846 -403.378352) (xy 36.361593 -403.452236)
			(xy 36.400327 -403.530025) (xy 36.431719 -403.611057) (xy 36.4555 -403.694639) (xy 36.471468 -403.780059)
			(xy 36.479486 -403.866588) (xy 36.479988 -403.910038) (xy 36.479486 -403.953488) (xy 36.471468 -404.040017)
			(xy 36.4555 -404.125437) (xy 36.431719 -404.209019) (xy 36.400327 -404.290051) (xy 36.361593 -404.36784)
			(xy 36.315846 -404.441724) (xy 36.263477 -404.511071) (xy 36.204933 -404.575291) (xy 36.140713 -404.633835)
			(xy 36.071366 -404.686204) (xy 35.997482 -404.731951) (xy 35.919693 -404.770685) (xy 35.838661 -404.802077)
			(xy 35.755079 -404.825858) (xy 35.669659 -404.841826) (xy 35.58313 -404.849844) (xy 35.49623 -404.849844)
			(xy 35.409701 -404.841826) (xy 35.324281 -404.825858) (xy 35.240699 -404.802077) (xy 35.159667 -404.770685)
			(xy 35.081878 -404.731951) (xy 35.007994 -404.686204) (xy 34.938647 -404.633835) (xy 34.874427 -404.575291)
			(xy 34.815883 -404.511071) (xy 34.763514 -404.441724) (xy 34.717767 -404.36784) (xy 34.679033 -404.290051)
			(xy 34.647641 -404.209019) (xy 34.62386 -404.125437) (xy 34.607892 -404.040017) (xy 34.599874 -403.953488)
			(xy 31.399486 -403.953488) (xy 31.391468 -404.040017) (xy 31.3755 -404.125437) (xy 31.351719 -404.209019)
			(xy 31.320327 -404.290051) (xy 31.281593 -404.36784) (xy 31.235846 -404.441724) (xy 31.183477 -404.511071)
			(xy 31.124933 -404.575291) (xy 31.060713 -404.633835) (xy 30.991366 -404.686204) (xy 30.917482 -404.731951)
			(xy 30.839693 -404.770685) (xy 30.758661 -404.802077) (xy 30.675079 -404.825858) (xy 30.589659 -404.841826)
			(xy 30.50313 -404.849844) (xy 30.41623 -404.849844) (xy 30.329701 -404.841826) (xy 30.244281 -404.825858)
			(xy 30.160699 -404.802077) (xy 30.079667 -404.770685) (xy 30.001878 -404.731951) (xy 29.927994 -404.686204)
			(xy 29.858647 -404.633835) (xy 29.794427 -404.575291) (xy 29.735883 -404.511071) (xy 29.683514 -404.441724)
			(xy 29.637767 -404.36784) (xy 29.599033 -404.290051) (xy 29.567641 -404.209019) (xy 29.54386 -404.125437)
			(xy 29.527892 -404.040017) (xy 29.519874 -403.953488) (xy 29.254196 -403.953488) (xy 29.254196 -406.493488)
			(xy 29.519874 -406.493488) (xy 29.519874 -406.406588) (xy 29.527892 -406.320059) (xy 29.54386 -406.234639)
			(xy 29.567641 -406.151057) (xy 29.599033 -406.070025) (xy 29.637767 -405.992236) (xy 29.683514 -405.918352)
			(xy 29.735883 -405.849005) (xy 29.794427 -405.784785) (xy 29.858647 -405.726241) (xy 29.927994 -405.673872)
			(xy 30.001878 -405.628125) (xy 30.079667 -405.589391) (xy 30.160699 -405.557999) (xy 30.244281 -405.534218)
			(xy 30.329701 -405.51825) (xy 30.41623 -405.510232) (xy 30.50313 -405.510232) (xy 30.589659 -405.51825)
			(xy 30.675079 -405.534218) (xy 30.758661 -405.557999) (xy 30.839693 -405.589391) (xy 30.917482 -405.628125)
			(xy 30.991366 -405.673872) (xy 31.060713 -405.726241) (xy 31.124933 -405.784785) (xy 31.183477 -405.849005)
			(xy 31.235846 -405.918352) (xy 31.281593 -405.992236) (xy 31.320327 -406.070025) (xy 31.351719 -406.151057)
			(xy 31.3755 -406.234639) (xy 31.391468 -406.320059) (xy 31.399486 -406.406588) (xy 31.399988 -406.450038)
			(xy 31.399486 -406.493488) (xy 34.599874 -406.493488) (xy 34.599874 -406.406588) (xy 34.607892 -406.320059)
			(xy 34.62386 -406.234639) (xy 34.647641 -406.151057) (xy 34.679033 -406.070025) (xy 34.717767 -405.992236)
			(xy 34.763514 -405.918352) (xy 34.815883 -405.849005) (xy 34.874427 -405.784785) (xy 34.938647 -405.726241)
			(xy 35.007994 -405.673872) (xy 35.081878 -405.628125) (xy 35.159667 -405.589391) (xy 35.240699 -405.557999)
			(xy 35.324281 -405.534218) (xy 35.409701 -405.51825) (xy 35.49623 -405.510232) (xy 35.58313 -405.510232)
			(xy 35.669659 -405.51825) (xy 35.755079 -405.534218) (xy 35.838661 -405.557999) (xy 35.919693 -405.589391)
			(xy 35.997482 -405.628125) (xy 36.071366 -405.673872) (xy 36.140713 -405.726241) (xy 36.204933 -405.784785)
			(xy 36.263477 -405.849005) (xy 36.315846 -405.918352) (xy 36.361593 -405.992236) (xy 36.400327 -406.070025)
			(xy 36.431719 -406.151057) (xy 36.4555 -406.234639) (xy 36.471468 -406.320059) (xy 36.479486 -406.406588)
			(xy 36.479988 -406.450038) (xy 36.479486 -406.493488) (xy 36.471468 -406.580017) (xy 36.4555 -406.665437)
			(xy 36.431719 -406.749019) (xy 36.400327 -406.830051) (xy 36.361593 -406.90784) (xy 36.329254 -406.96007)
			(xy 39.818063 -406.96007) (xy 39.82207 -406.844046) (xy 39.834072 -406.728574) (xy 39.854012 -406.614206)
			(xy 39.881795 -406.501486) (xy 39.917289 -406.390952) (xy 39.960324 -406.283129) (xy 40.010695 -406.178532)
			(xy 40.068162 -406.07766) (xy 40.132452 -405.980993) (xy 40.203257 -405.888992) (xy 40.280241 -405.802095)
			(xy 40.363037 -405.720716) (xy 40.45125 -405.645243) (xy 40.54446 -405.576036) (xy 40.642223 -405.513424)
			(xy 40.744072 -405.457707) (xy 40.849522 -405.409149) (xy 40.958071 -405.367981) (xy 41.069202 -405.334401)
			(xy 41.182385 -405.308568) (xy 41.29708 -405.290605) (xy 41.412742 -405.280597) (xy 41.528818 -405.278594)
			(xy 41.644756 -405.284603) (xy 41.760003 -405.298596) (xy 41.874009 -405.320507) (xy 41.986233 -405.350232)
			(xy 42.096139 -405.387628) (xy 42.203202 -405.432517) (xy 42.306914 -405.484686) (xy 42.406779 -405.543886)
			(xy 42.502322 -405.609835) (xy 42.502604 -405.61006) (xy 43.327577 -405.61006) (xy 43.331612 -405.534356)
			(xy 43.343671 -405.459511) (xy 43.363617 -405.38637) (xy 43.391224 -405.315765) (xy 43.42618 -405.248494)
			(xy 43.468088 -405.185319) (xy 43.516474 -405.126957) (xy 43.57079 -405.074069) (xy 43.630419 -405.027254)
			(xy 43.694687 -404.987042) (xy 43.762864 -404.95389) (xy 43.83418 -404.928172) (xy 43.907825 -404.91018)
			(xy 43.982965 -404.900118) (xy 44.058749 -404.898099) (xy 44.134319 -404.904148) (xy 44.208817 -404.918195)
			(xy 44.2814 -404.940081) (xy 44.351246 -404.969558) (xy 44.417563 -405.006293) (xy 44.479599 -405.049868)
			(xy 44.536652 -405.09979) (xy 44.588076 -405.155494) (xy 44.633287 -405.216349) (xy 44.671774 -405.281664)
			(xy 44.7031 -405.3507) (xy 44.72691 -405.422675) (xy 44.742935 -405.496773) (xy 44.750994 -405.572154)
			(xy 44.751498 -405.61006) (xy 45.867577 -405.61006) (xy 45.871612 -405.534356) (xy 45.883671 -405.459511)
			(xy 45.903617 -405.38637) (xy 45.931224 -405.315765) (xy 45.96618 -405.248494) (xy 46.008088 -405.185319)
			(xy 46.056474 -405.126957) (xy 46.11079 -405.074069) (xy 46.170419 -405.027254) (xy 46.234687 -404.987042)
			(xy 46.302864 -404.95389) (xy 46.37418 -404.928172) (xy 46.447825 -404.91018) (xy 46.522965 -404.900118)
			(xy 46.598749 -404.898099) (xy 46.674319 -404.904148) (xy 46.748817 -404.918195) (xy 46.8214 -404.940081)
			(xy 46.891246 -404.969558) (xy 46.957563 -405.006293) (xy 47.019599 -405.049868) (xy 47.076652 -405.09979)
			(xy 47.128076 -405.155494) (xy 47.173287 -405.216349) (xy 47.211774 -405.281664) (xy 47.2431 -405.3507)
			(xy 47.26691 -405.422675) (xy 47.282935 -405.496773) (xy 47.290994 -405.572154) (xy 47.291498 -405.61006)
			(xy 48.407577 -405.61006) (xy 48.411612 -405.534356) (xy 48.423671 -405.459511) (xy 48.443617 -405.38637)
			(xy 48.471224 -405.315765) (xy 48.50618 -405.248494) (xy 48.548088 -405.185319) (xy 48.596474 -405.126957)
			(xy 48.65079 -405.074069) (xy 48.710419 -405.027254) (xy 48.774687 -404.987042) (xy 48.842864 -404.95389)
			(xy 48.91418 -404.928172) (xy 48.987825 -404.91018) (xy 49.062965 -404.900118) (xy 49.138749 -404.898099)
			(xy 49.214319 -404.904148) (xy 49.288817 -404.918195) (xy 49.3614 -404.940081) (xy 49.431246 -404.969558)
			(xy 49.497563 -405.006293) (xy 49.559599 -405.049868) (xy 49.616652 -405.09979) (xy 49.668076 -405.155494)
			(xy 49.713287 -405.216349) (xy 49.751774 -405.281664) (xy 49.7831 -405.3507) (xy 49.80691 -405.422675)
			(xy 49.822935 -405.496773) (xy 49.830994 -405.572154) (xy 49.831498 -405.61006) (xy 50.947577 -405.61006)
			(xy 50.951612 -405.534356) (xy 50.963671 -405.459511) (xy 50.983617 -405.38637) (xy 51.011224 -405.315765)
			(xy 51.04618 -405.248494) (xy 51.088088 -405.185319) (xy 51.136474 -405.126957) (xy 51.19079 -405.074069)
			(xy 51.250419 -405.027254) (xy 51.314687 -404.987042) (xy 51.382864 -404.95389) (xy 51.45418 -404.928172)
			(xy 51.527825 -404.91018) (xy 51.602965 -404.900118) (xy 51.678749 -404.898099) (xy 51.754319 -404.904148)
			(xy 51.828817 -404.918195) (xy 51.9014 -404.940081) (xy 51.971246 -404.969558) (xy 52.037563 -405.006293)
			(xy 52.099599 -405.049868) (xy 52.156652 -405.09979) (xy 52.208076 -405.155494) (xy 52.253287 -405.216349)
			(xy 52.291774 -405.281664) (xy 52.3231 -405.3507) (xy 52.34691 -405.422675) (xy 52.362935 -405.496773)
			(xy 52.370994 -405.572154) (xy 52.371498 -405.61006) (xy 53.487577 -405.61006) (xy 53.491612 -405.534356)
			(xy 53.503671 -405.459511) (xy 53.523617 -405.38637) (xy 53.551224 -405.315765) (xy 53.58618 -405.248494)
			(xy 53.628088 -405.185319) (xy 53.676474 -405.126957) (xy 53.73079 -405.074069) (xy 53.790419 -405.027254)
			(xy 53.854687 -404.987042) (xy 53.922864 -404.95389) (xy 53.99418 -404.928172) (xy 54.067825 -404.91018)
			(xy 54.142965 -404.900118) (xy 54.218749 -404.898099) (xy 54.294319 -404.904148) (xy 54.368817 -404.918195)
			(xy 54.4414 -404.940081) (xy 54.511246 -404.969558) (xy 54.577563 -405.006293) (xy 54.639599 -405.049868)
			(xy 54.696652 -405.09979) (xy 54.748076 -405.155494) (xy 54.793287 -405.216349) (xy 54.831774 -405.281664)
			(xy 54.8631 -405.3507) (xy 54.88691 -405.422675) (xy 54.902935 -405.496773) (xy 54.910994 -405.572154)
			(xy 54.911498 -405.61006) (xy 56.027577 -405.61006) (xy 56.031612 -405.534356) (xy 56.043671 -405.459511)
			(xy 56.063617 -405.38637) (xy 56.091224 -405.315765) (xy 56.12618 -405.248494) (xy 56.168088 -405.185319)
			(xy 56.216474 -405.126957) (xy 56.27079 -405.074069) (xy 56.330419 -405.027254) (xy 56.394687 -404.987042)
			(xy 56.462864 -404.95389) (xy 56.53418 -404.928172) (xy 56.607825 -404.91018) (xy 56.682965 -404.900118)
			(xy 56.758749 -404.898099) (xy 56.834319 -404.904148) (xy 56.908817 -404.918195) (xy 56.9814 -404.940081)
			(xy 57.051246 -404.969558) (xy 57.117563 -405.006293) (xy 57.179599 -405.049868) (xy 57.236652 -405.09979)
			(xy 57.288076 -405.155494) (xy 57.333287 -405.216349) (xy 57.371774 -405.281664) (xy 57.4031 -405.3507)
			(xy 57.42691 -405.422675) (xy 57.442935 -405.496773) (xy 57.450994 -405.572154) (xy 57.451498 -405.61006)
			(xy 58.567577 -405.61006) (xy 58.571612 -405.534356) (xy 58.583671 -405.459511) (xy 58.603617 -405.38637)
			(xy 58.631224 -405.315765) (xy 58.66618 -405.248494) (xy 58.708088 -405.185319) (xy 58.756474 -405.126957)
			(xy 58.81079 -405.074069) (xy 58.870419 -405.027254) (xy 58.934687 -404.987042) (xy 59.002864 -404.95389)
			(xy 59.07418 -404.928172) (xy 59.147825 -404.91018) (xy 59.222965 -404.900118) (xy 59.298749 -404.898099)
			(xy 59.374319 -404.904148) (xy 59.448817 -404.918195) (xy 59.5214 -404.940081) (xy 59.591246 -404.969558)
			(xy 59.657563 -405.006293) (xy 59.719599 -405.049868) (xy 59.776652 -405.09979) (xy 59.828076 -405.155494)
			(xy 59.873287 -405.216349) (xy 59.911774 -405.281664) (xy 59.9431 -405.3507) (xy 59.96691 -405.422675)
			(xy 59.982935 -405.496773) (xy 59.990994 -405.572154) (xy 59.991498 -405.61006) (xy 61.107577 -405.61006)
			(xy 61.111612 -405.534356) (xy 61.123671 -405.459511) (xy 61.143617 -405.38637) (xy 61.171224 -405.315765)
			(xy 61.20618 -405.248494) (xy 61.248088 -405.185319) (xy 61.296474 -405.126957) (xy 61.35079 -405.074069)
			(xy 61.410419 -405.027254) (xy 61.474687 -404.987042) (xy 61.542864 -404.95389) (xy 61.61418 -404.928172)
			(xy 61.687825 -404.91018) (xy 61.762965 -404.900118) (xy 61.838749 -404.898099) (xy 61.914319 -404.904148)
			(xy 61.988817 -404.918195) (xy 62.0614 -404.940081) (xy 62.131246 -404.969558) (xy 62.197563 -405.006293)
			(xy 62.259599 -405.049868) (xy 62.316652 -405.09979) (xy 62.368076 -405.155494) (xy 62.413287 -405.216349)
			(xy 62.451774 -405.281664) (xy 62.4831 -405.3507) (xy 62.50691 -405.422675) (xy 62.522935 -405.496773)
			(xy 62.530994 -405.572154) (xy 62.531498 -405.61006) (xy 62.530994 -405.647966) (xy 62.522935 -405.723347)
			(xy 62.50691 -405.797445) (xy 62.4831 -405.86942) (xy 62.451774 -405.938456) (xy 62.413287 -406.003771)
			(xy 62.368076 -406.064626) (xy 62.316652 -406.12033) (xy 62.259599 -406.170252) (xy 62.197563 -406.213827)
			(xy 62.131246 -406.250562) (xy 62.0614 -406.280039) (xy 61.988817 -406.301925) (xy 61.914319 -406.315972)
			(xy 61.838749 -406.322021) (xy 61.762965 -406.320002) (xy 61.687825 -406.30994) (xy 61.61418 -406.291948)
			(xy 61.542864 -406.26623) (xy 61.474687 -406.233078) (xy 61.410419 -406.192866) (xy 61.35079 -406.146051)
			(xy 61.296474 -406.093163) (xy 61.248088 -406.034801) (xy 61.20618 -405.971626) (xy 61.171224 -405.904355)
			(xy 61.143617 -405.83375) (xy 61.123671 -405.760609) (xy 61.111612 -405.685764) (xy 61.107577 -405.61006)
			(xy 59.991498 -405.61006) (xy 59.990994 -405.647966) (xy 59.982935 -405.723347) (xy 59.96691 -405.797445)
			(xy 59.9431 -405.86942) (xy 59.911774 -405.938456) (xy 59.873287 -406.003771) (xy 59.828076 -406.064626)
			(xy 59.776652 -406.12033) (xy 59.719599 -406.170252) (xy 59.657563 -406.213827) (xy 59.591246 -406.250562)
			(xy 59.5214 -406.280039) (xy 59.448817 -406.301925) (xy 59.374319 -406.315972) (xy 59.298749 -406.322021)
			(xy 59.222965 -406.320002) (xy 59.147825 -406.30994) (xy 59.07418 -406.291948) (xy 59.002864 -406.26623)
			(xy 58.934687 -406.233078) (xy 58.870419 -406.192866) (xy 58.81079 -406.146051) (xy 58.756474 -406.093163)
			(xy 58.708088 -406.034801) (xy 58.66618 -405.971626) (xy 58.631224 -405.904355) (xy 58.603617 -405.83375)
			(xy 58.583671 -405.760609) (xy 58.571612 -405.685764) (xy 58.567577 -405.61006) (xy 57.451498 -405.61006)
			(xy 57.450994 -405.647966) (xy 57.442935 -405.723347) (xy 57.42691 -405.797445) (xy 57.4031 -405.86942)
			(xy 57.371774 -405.938456) (xy 57.333287 -406.003771) (xy 57.288076 -406.064626) (xy 57.236652 -406.12033)
			(xy 57.179599 -406.170252) (xy 57.117563 -406.213827) (xy 57.051246 -406.250562) (xy 56.9814 -406.280039)
			(xy 56.908817 -406.301925) (xy 56.834319 -406.315972) (xy 56.758749 -406.322021) (xy 56.682965 -406.320002)
			(xy 56.607825 -406.30994) (xy 56.53418 -406.291948) (xy 56.462864 -406.26623) (xy 56.394687 -406.233078)
			(xy 56.330419 -406.192866) (xy 56.27079 -406.146051) (xy 56.216474 -406.093163) (xy 56.168088 -406.034801)
			(xy 56.12618 -405.971626) (xy 56.091224 -405.904355) (xy 56.063617 -405.83375) (xy 56.043671 -405.760609)
			(xy 56.031612 -405.685764) (xy 56.027577 -405.61006) (xy 54.911498 -405.61006) (xy 54.910994 -405.647966)
			(xy 54.902935 -405.723347) (xy 54.88691 -405.797445) (xy 54.8631 -405.86942) (xy 54.831774 -405.938456)
			(xy 54.793287 -406.003771) (xy 54.748076 -406.064626) (xy 54.696652 -406.12033) (xy 54.639599 -406.170252)
			(xy 54.577563 -406.213827) (xy 54.511246 -406.250562) (xy 54.4414 -406.280039) (xy 54.368817 -406.301925)
			(xy 54.294319 -406.315972) (xy 54.218749 -406.322021) (xy 54.142965 -406.320002) (xy 54.067825 -406.30994)
			(xy 53.99418 -406.291948) (xy 53.922864 -406.26623) (xy 53.854687 -406.233078) (xy 53.790419 -406.192866)
			(xy 53.73079 -406.146051) (xy 53.676474 -406.093163) (xy 53.628088 -406.034801) (xy 53.58618 -405.971626)
			(xy 53.551224 -405.904355) (xy 53.523617 -405.83375) (xy 53.503671 -405.760609) (xy 53.491612 -405.685764)
			(xy 53.487577 -405.61006) (xy 52.371498 -405.61006) (xy 52.370994 -405.647966) (xy 52.362935 -405.723347)
			(xy 52.34691 -405.797445) (xy 52.3231 -405.86942) (xy 52.291774 -405.938456) (xy 52.253287 -406.003771)
			(xy 52.208076 -406.064626) (xy 52.156652 -406.12033) (xy 52.099599 -406.170252) (xy 52.037563 -406.213827)
			(xy 51.971246 -406.250562) (xy 51.9014 -406.280039) (xy 51.828817 -406.301925) (xy 51.754319 -406.315972)
			(xy 51.678749 -406.322021) (xy 51.602965 -406.320002) (xy 51.527825 -406.30994) (xy 51.45418 -406.291948)
			(xy 51.382864 -406.26623) (xy 51.314687 -406.233078) (xy 51.250419 -406.192866) (xy 51.19079 -406.146051)
			(xy 51.136474 -406.093163) (xy 51.088088 -406.034801) (xy 51.04618 -405.971626) (xy 51.011224 -405.904355)
			(xy 50.983617 -405.83375) (xy 50.963671 -405.760609) (xy 50.951612 -405.685764) (xy 50.947577 -405.61006)
			(xy 49.831498 -405.61006) (xy 49.830994 -405.647966) (xy 49.822935 -405.723347) (xy 49.80691 -405.797445)
			(xy 49.7831 -405.86942) (xy 49.751774 -405.938456) (xy 49.713287 -406.003771) (xy 49.668076 -406.064626)
			(xy 49.616652 -406.12033) (xy 49.559599 -406.170252) (xy 49.497563 -406.213827) (xy 49.431246 -406.250562)
			(xy 49.3614 -406.280039) (xy 49.288817 -406.301925) (xy 49.214319 -406.315972) (xy 49.138749 -406.322021)
			(xy 49.062965 -406.320002) (xy 48.987825 -406.30994) (xy 48.91418 -406.291948) (xy 48.842864 -406.26623)
			(xy 48.774687 -406.233078) (xy 48.710419 -406.192866) (xy 48.65079 -406.146051) (xy 48.596474 -406.093163)
			(xy 48.548088 -406.034801) (xy 48.50618 -405.971626) (xy 48.471224 -405.904355) (xy 48.443617 -405.83375)
			(xy 48.423671 -405.760609) (xy 48.411612 -405.685764) (xy 48.407577 -405.61006) (xy 47.291498 -405.61006)
			(xy 47.290994 -405.647966) (xy 47.282935 -405.723347) (xy 47.26691 -405.797445) (xy 47.2431 -405.86942)
			(xy 47.211774 -405.938456) (xy 47.173287 -406.003771) (xy 47.128076 -406.064626) (xy 47.076652 -406.12033)
			(xy 47.019599 -406.170252) (xy 46.957563 -406.213827) (xy 46.891246 -406.250562) (xy 46.8214 -406.280039)
			(xy 46.748817 -406.301925) (xy 46.674319 -406.315972) (xy 46.598749 -406.322021) (xy 46.522965 -406.320002)
			(xy 46.447825 -406.30994) (xy 46.37418 -406.291948) (xy 46.302864 -406.26623) (xy 46.234687 -406.233078)
			(xy 46.170419 -406.192866) (xy 46.11079 -406.146051) (xy 46.056474 -406.093163) (xy 46.008088 -406.034801)
			(xy 45.96618 -405.971626) (xy 45.931224 -405.904355) (xy 45.903617 -405.83375) (xy 45.883671 -405.760609)
			(xy 45.871612 -405.685764) (xy 45.867577 -405.61006) (xy 44.751498 -405.61006) (xy 44.750994 -405.647966)
			(xy 44.742935 -405.723347) (xy 44.72691 -405.797445) (xy 44.7031 -405.86942) (xy 44.671774 -405.938456)
			(xy 44.633287 -406.003771) (xy 44.588076 -406.064626) (xy 44.536652 -406.12033) (xy 44.479599 -406.170252)
			(xy 44.417563 -406.213827) (xy 44.351246 -406.250562) (xy 44.2814 -406.280039) (xy 44.208817 -406.301925)
			(xy 44.134319 -406.315972) (xy 44.058749 -406.322021) (xy 43.982965 -406.320002) (xy 43.907825 -406.30994)
			(xy 43.83418 -406.291948) (xy 43.762864 -406.26623) (xy 43.694687 -406.233078) (xy 43.630419 -406.192866)
			(xy 43.57079 -406.146051) (xy 43.516474 -406.093163) (xy 43.468088 -406.034801) (xy 43.42618 -405.971626)
			(xy 43.391224 -405.904355) (xy 43.363617 -405.83375) (xy 43.343671 -405.760609) (xy 43.331612 -405.685764)
			(xy 43.327577 -405.61006) (xy 42.502604 -405.61006) (xy 42.593088 -405.682218) (xy 42.678643 -405.760691)
			(xy 42.758581 -405.844879) (xy 42.83252 -405.934381) (xy 42.900108 -406.028772) (xy 42.961022 -406.1276)
			(xy 43.014974 -406.230396) (xy 43.061704 -406.336669) (xy 43.100992 -406.445913) (xy 43.132649 -406.557606)
			(xy 43.156525 -406.671218) (xy 43.172506 -406.786206) (xy 43.180515 -406.902023) (xy 43.181016 -406.96007)
			(xy 43.180515 -407.018117) (xy 43.172506 -407.133934) (xy 43.156525 -407.248922) (xy 43.132649 -407.362534)
			(xy 43.100992 -407.474227) (xy 43.061704 -407.583471) (xy 43.014974 -407.689744) (xy 42.961022 -407.79254)
			(xy 42.900108 -407.891368) (xy 42.83252 -407.985759) (xy 42.758581 -408.075261) (xy 42.678643 -408.159449)
			(xy 42.593088 -408.237922) (xy 42.502604 -408.31008) (xy 43.327577 -408.31008) (xy 43.331612 -408.234376)
			(xy 43.343671 -408.159531) (xy 43.363617 -408.08639) (xy 43.391224 -408.015785) (xy 43.42618 -407.948514)
			(xy 43.468088 -407.885339) (xy 43.516474 -407.826977) (xy 43.57079 -407.774089) (xy 43.630419 -407.727274)
			(xy 43.694687 -407.687062) (xy 43.762864 -407.65391) (xy 43.83418 -407.628192) (xy 43.907825 -407.6102)
			(xy 43.982965 -407.600138) (xy 44.058749 -407.598119) (xy 44.134319 -407.604168) (xy 44.208817 -407.618215)
			(xy 44.2814 -407.640101) (xy 44.351246 -407.669578) (xy 44.417563 -407.706313) (xy 44.479599 -407.749888)
			(xy 44.536652 -407.79981) (xy 44.588076 -407.855514) (xy 44.633287 -407.916369) (xy 44.671774 -407.981684)
			(xy 44.7031 -408.05072) (xy 44.72691 -408.122695) (xy 44.742935 -408.196793) (xy 44.750994 -408.272174)
			(xy 44.751498 -408.31008) (xy 45.867577 -408.31008) (xy 45.871612 -408.234376) (xy 45.883671 -408.159531)
			(xy 45.903617 -408.08639) (xy 45.931224 -408.015785) (xy 45.96618 -407.948514) (xy 46.008088 -407.885339)
			(xy 46.056474 -407.826977) (xy 46.11079 -407.774089) (xy 46.170419 -407.727274) (xy 46.234687 -407.687062)
			(xy 46.302864 -407.65391) (xy 46.37418 -407.628192) (xy 46.447825 -407.6102) (xy 46.522965 -407.600138)
			(xy 46.598749 -407.598119) (xy 46.674319 -407.604168) (xy 46.748817 -407.618215) (xy 46.8214 -407.640101)
			(xy 46.891246 -407.669578) (xy 46.957563 -407.706313) (xy 47.019599 -407.749888) (xy 47.076652 -407.79981)
			(xy 47.128076 -407.855514) (xy 47.173287 -407.916369) (xy 47.211774 -407.981684) (xy 47.2431 -408.05072)
			(xy 47.26691 -408.122695) (xy 47.282935 -408.196793) (xy 47.290994 -408.272174) (xy 47.291498 -408.31008)
			(xy 48.407577 -408.31008) (xy 48.411612 -408.234376) (xy 48.423671 -408.159531) (xy 48.443617 -408.08639)
			(xy 48.471224 -408.015785) (xy 48.50618 -407.948514) (xy 48.548088 -407.885339) (xy 48.596474 -407.826977)
			(xy 48.65079 -407.774089) (xy 48.710419 -407.727274) (xy 48.774687 -407.687062) (xy 48.842864 -407.65391)
			(xy 48.91418 -407.628192) (xy 48.987825 -407.6102) (xy 49.062965 -407.600138) (xy 49.138749 -407.598119)
			(xy 49.214319 -407.604168) (xy 49.288817 -407.618215) (xy 49.3614 -407.640101) (xy 49.431246 -407.669578)
			(xy 49.497563 -407.706313) (xy 49.559599 -407.749888) (xy 49.616652 -407.79981) (xy 49.668076 -407.855514)
			(xy 49.713287 -407.916369) (xy 49.751774 -407.981684) (xy 49.7831 -408.05072) (xy 49.80691 -408.122695)
			(xy 49.822935 -408.196793) (xy 49.830994 -408.272174) (xy 49.831498 -408.31008) (xy 50.947577 -408.31008)
			(xy 50.951612 -408.234376) (xy 50.963671 -408.159531) (xy 50.983617 -408.08639) (xy 51.011224 -408.015785)
			(xy 51.04618 -407.948514) (xy 51.088088 -407.885339) (xy 51.136474 -407.826977) (xy 51.19079 -407.774089)
			(xy 51.250419 -407.727274) (xy 51.314687 -407.687062) (xy 51.382864 -407.65391) (xy 51.45418 -407.628192)
			(xy 51.527825 -407.6102) (xy 51.602965 -407.600138) (xy 51.678749 -407.598119) (xy 51.754319 -407.604168)
			(xy 51.828817 -407.618215) (xy 51.9014 -407.640101) (xy 51.971246 -407.669578) (xy 52.037563 -407.706313)
			(xy 52.099599 -407.749888) (xy 52.156652 -407.79981) (xy 52.208076 -407.855514) (xy 52.253287 -407.916369)
			(xy 52.291774 -407.981684) (xy 52.3231 -408.05072) (xy 52.34691 -408.122695) (xy 52.362935 -408.196793)
			(xy 52.370994 -408.272174) (xy 52.371498 -408.31008) (xy 53.487577 -408.31008) (xy 53.491612 -408.234376)
			(xy 53.503671 -408.159531) (xy 53.523617 -408.08639) (xy 53.551224 -408.015785) (xy 53.58618 -407.948514)
			(xy 53.628088 -407.885339) (xy 53.676474 -407.826977) (xy 53.73079 -407.774089) (xy 53.790419 -407.727274)
			(xy 53.854687 -407.687062) (xy 53.922864 -407.65391) (xy 53.99418 -407.628192) (xy 54.067825 -407.6102)
			(xy 54.142965 -407.600138) (xy 54.218749 -407.598119) (xy 54.294319 -407.604168) (xy 54.368817 -407.618215)
			(xy 54.4414 -407.640101) (xy 54.511246 -407.669578) (xy 54.577563 -407.706313) (xy 54.639599 -407.749888)
			(xy 54.696652 -407.79981) (xy 54.748076 -407.855514) (xy 54.793287 -407.916369) (xy 54.831774 -407.981684)
			(xy 54.8631 -408.05072) (xy 54.88691 -408.122695) (xy 54.902935 -408.196793) (xy 54.910994 -408.272174)
			(xy 54.911498 -408.31008) (xy 56.027577 -408.31008) (xy 56.031612 -408.234376) (xy 56.043671 -408.159531)
			(xy 56.063617 -408.08639) (xy 56.091224 -408.015785) (xy 56.12618 -407.948514) (xy 56.168088 -407.885339)
			(xy 56.216474 -407.826977) (xy 56.27079 -407.774089) (xy 56.330419 -407.727274) (xy 56.394687 -407.687062)
			(xy 56.462864 -407.65391) (xy 56.53418 -407.628192) (xy 56.607825 -407.6102) (xy 56.682965 -407.600138)
			(xy 56.758749 -407.598119) (xy 56.834319 -407.604168) (xy 56.908817 -407.618215) (xy 56.9814 -407.640101)
			(xy 57.051246 -407.669578) (xy 57.117563 -407.706313) (xy 57.179599 -407.749888) (xy 57.236652 -407.79981)
			(xy 57.288076 -407.855514) (xy 57.333287 -407.916369) (xy 57.371774 -407.981684) (xy 57.4031 -408.05072)
			(xy 57.42691 -408.122695) (xy 57.442935 -408.196793) (xy 57.450994 -408.272174) (xy 57.451498 -408.31008)
			(xy 58.567577 -408.31008) (xy 58.571612 -408.234376) (xy 58.583671 -408.159531) (xy 58.603617 -408.08639)
			(xy 58.631224 -408.015785) (xy 58.66618 -407.948514) (xy 58.708088 -407.885339) (xy 58.756474 -407.826977)
			(xy 58.81079 -407.774089) (xy 58.870419 -407.727274) (xy 58.934687 -407.687062) (xy 59.002864 -407.65391)
			(xy 59.07418 -407.628192) (xy 59.147825 -407.6102) (xy 59.222965 -407.600138) (xy 59.298749 -407.598119)
			(xy 59.374319 -407.604168) (xy 59.448817 -407.618215) (xy 59.5214 -407.640101) (xy 59.591246 -407.669578)
			(xy 59.657563 -407.706313) (xy 59.719599 -407.749888) (xy 59.776652 -407.79981) (xy 59.828076 -407.855514)
			(xy 59.873287 -407.916369) (xy 59.911774 -407.981684) (xy 59.9431 -408.05072) (xy 59.96691 -408.122695)
			(xy 59.982935 -408.196793) (xy 59.990994 -408.272174) (xy 59.991498 -408.31008) (xy 61.107577 -408.31008)
			(xy 61.111612 -408.234376) (xy 61.123671 -408.159531) (xy 61.143617 -408.08639) (xy 61.171224 -408.015785)
			(xy 61.20618 -407.948514) (xy 61.248088 -407.885339) (xy 61.296474 -407.826977) (xy 61.35079 -407.774089)
			(xy 61.410419 -407.727274) (xy 61.474687 -407.687062) (xy 61.542864 -407.65391) (xy 61.61418 -407.628192)
			(xy 61.687825 -407.6102) (xy 61.762965 -407.600138) (xy 61.838749 -407.598119) (xy 61.914319 -407.604168)
			(xy 61.988817 -407.618215) (xy 62.0614 -407.640101) (xy 62.131246 -407.669578) (xy 62.197563 -407.706313)
			(xy 62.259599 -407.749888) (xy 62.316652 -407.79981) (xy 62.368076 -407.855514) (xy 62.413287 -407.916369)
			(xy 62.451774 -407.981684) (xy 62.4831 -408.05072) (xy 62.50691 -408.122695) (xy 62.522935 -408.196793)
			(xy 62.530994 -408.272174) (xy 62.531498 -408.31008) (xy 62.530994 -408.347986) (xy 62.522935 -408.423367)
			(xy 62.50691 -408.497465) (xy 62.4831 -408.56944) (xy 62.451774 -408.638476) (xy 62.413287 -408.703791)
			(xy 62.368076 -408.764646) (xy 62.316652 -408.82035) (xy 62.259599 -408.870272) (xy 62.197563 -408.913847)
			(xy 62.131246 -408.950582) (xy 62.0614 -408.980059) (xy 61.988817 -409.001945) (xy 61.914319 -409.015992)
			(xy 61.838749 -409.022041) (xy 61.762965 -409.020022) (xy 61.687825 -409.00996) (xy 61.61418 -408.991968)
			(xy 61.542864 -408.96625) (xy 61.474687 -408.933098) (xy 61.410419 -408.892886) (xy 61.35079 -408.846071)
			(xy 61.296474 -408.793183) (xy 61.248088 -408.734821) (xy 61.20618 -408.671646) (xy 61.171224 -408.604375)
			(xy 61.143617 -408.53377) (xy 61.123671 -408.460629) (xy 61.111612 -408.385784) (xy 61.107577 -408.31008)
			(xy 59.991498 -408.31008) (xy 59.990994 -408.347986) (xy 59.982935 -408.423367) (xy 59.96691 -408.497465)
			(xy 59.9431 -408.56944) (xy 59.911774 -408.638476) (xy 59.873287 -408.703791) (xy 59.828076 -408.764646)
			(xy 59.776652 -408.82035) (xy 59.719599 -408.870272) (xy 59.657563 -408.913847) (xy 59.591246 -408.950582)
			(xy 59.5214 -408.980059) (xy 59.448817 -409.001945) (xy 59.374319 -409.015992) (xy 59.298749 -409.022041)
			(xy 59.222965 -409.020022) (xy 59.147825 -409.00996) (xy 59.07418 -408.991968) (xy 59.002864 -408.96625)
			(xy 58.934687 -408.933098) (xy 58.870419 -408.892886) (xy 58.81079 -408.846071) (xy 58.756474 -408.793183)
			(xy 58.708088 -408.734821) (xy 58.66618 -408.671646) (xy 58.631224 -408.604375) (xy 58.603617 -408.53377)
			(xy 58.583671 -408.460629) (xy 58.571612 -408.385784) (xy 58.567577 -408.31008) (xy 57.451498 -408.31008)
			(xy 57.450994 -408.347986) (xy 57.442935 -408.423367) (xy 57.42691 -408.497465) (xy 57.4031 -408.56944)
			(xy 57.371774 -408.638476) (xy 57.333287 -408.703791) (xy 57.288076 -408.764646) (xy 57.236652 -408.82035)
			(xy 57.179599 -408.870272) (xy 57.117563 -408.913847) (xy 57.051246 -408.950582) (xy 56.9814 -408.980059)
			(xy 56.908817 -409.001945) (xy 56.834319 -409.015992) (xy 56.758749 -409.022041) (xy 56.682965 -409.020022)
			(xy 56.607825 -409.00996) (xy 56.53418 -408.991968) (xy 56.462864 -408.96625) (xy 56.394687 -408.933098)
			(xy 56.330419 -408.892886) (xy 56.27079 -408.846071) (xy 56.216474 -408.793183) (xy 56.168088 -408.734821)
			(xy 56.12618 -408.671646) (xy 56.091224 -408.604375) (xy 56.063617 -408.53377) (xy 56.043671 -408.460629)
			(xy 56.031612 -408.385784) (xy 56.027577 -408.31008) (xy 54.911498 -408.31008) (xy 54.910994 -408.347986)
			(xy 54.902935 -408.423367) (xy 54.88691 -408.497465) (xy 54.8631 -408.56944) (xy 54.831774 -408.638476)
			(xy 54.793287 -408.703791) (xy 54.748076 -408.764646) (xy 54.696652 -408.82035) (xy 54.639599 -408.870272)
			(xy 54.577563 -408.913847) (xy 54.511246 -408.950582) (xy 54.4414 -408.980059) (xy 54.368817 -409.001945)
			(xy 54.294319 -409.015992) (xy 54.218749 -409.022041) (xy 54.142965 -409.020022) (xy 54.067825 -409.00996)
			(xy 53.99418 -408.991968) (xy 53.922864 -408.96625) (xy 53.854687 -408.933098) (xy 53.790419 -408.892886)
			(xy 53.73079 -408.846071) (xy 53.676474 -408.793183) (xy 53.628088 -408.734821) (xy 53.58618 -408.671646)
			(xy 53.551224 -408.604375) (xy 53.523617 -408.53377) (xy 53.503671 -408.460629) (xy 53.491612 -408.385784)
			(xy 53.487577 -408.31008) (xy 52.371498 -408.31008) (xy 52.370994 -408.347986) (xy 52.362935 -408.423367)
			(xy 52.34691 -408.497465) (xy 52.3231 -408.56944) (xy 52.291774 -408.638476) (xy 52.253287 -408.703791)
			(xy 52.208076 -408.764646) (xy 52.156652 -408.82035) (xy 52.099599 -408.870272) (xy 52.037563 -408.913847)
			(xy 51.971246 -408.950582) (xy 51.9014 -408.980059) (xy 51.828817 -409.001945) (xy 51.754319 -409.015992)
			(xy 51.678749 -409.022041) (xy 51.602965 -409.020022) (xy 51.527825 -409.00996) (xy 51.45418 -408.991968)
			(xy 51.382864 -408.96625) (xy 51.314687 -408.933098) (xy 51.250419 -408.892886) (xy 51.19079 -408.846071)
			(xy 51.136474 -408.793183) (xy 51.088088 -408.734821) (xy 51.04618 -408.671646) (xy 51.011224 -408.604375)
			(xy 50.983617 -408.53377) (xy 50.963671 -408.460629) (xy 50.951612 -408.385784) (xy 50.947577 -408.31008)
			(xy 49.831498 -408.31008) (xy 49.830994 -408.347986) (xy 49.822935 -408.423367) (xy 49.80691 -408.497465)
			(xy 49.7831 -408.56944) (xy 49.751774 -408.638476) (xy 49.713287 -408.703791) (xy 49.668076 -408.764646)
			(xy 49.616652 -408.82035) (xy 49.559599 -408.870272) (xy 49.497563 -408.913847) (xy 49.431246 -408.950582)
			(xy 49.3614 -408.980059) (xy 49.288817 -409.001945) (xy 49.214319 -409.015992) (xy 49.138749 -409.022041)
			(xy 49.062965 -409.020022) (xy 48.987825 -409.00996) (xy 48.91418 -408.991968) (xy 48.842864 -408.96625)
			(xy 48.774687 -408.933098) (xy 48.710419 -408.892886) (xy 48.65079 -408.846071) (xy 48.596474 -408.793183)
			(xy 48.548088 -408.734821) (xy 48.50618 -408.671646) (xy 48.471224 -408.604375) (xy 48.443617 -408.53377)
			(xy 48.423671 -408.460629) (xy 48.411612 -408.385784) (xy 48.407577 -408.31008) (xy 47.291498 -408.31008)
			(xy 47.290994 -408.347986) (xy 47.282935 -408.423367) (xy 47.26691 -408.497465) (xy 47.2431 -408.56944)
			(xy 47.211774 -408.638476) (xy 47.173287 -408.703791) (xy 47.128076 -408.764646) (xy 47.076652 -408.82035)
			(xy 47.019599 -408.870272) (xy 46.957563 -408.913847) (xy 46.891246 -408.950582) (xy 46.8214 -408.980059)
			(xy 46.748817 -409.001945) (xy 46.674319 -409.015992) (xy 46.598749 -409.022041) (xy 46.522965 -409.020022)
			(xy 46.447825 -409.00996) (xy 46.37418 -408.991968) (xy 46.302864 -408.96625) (xy 46.234687 -408.933098)
			(xy 46.170419 -408.892886) (xy 46.11079 -408.846071) (xy 46.056474 -408.793183) (xy 46.008088 -408.734821)
			(xy 45.96618 -408.671646) (xy 45.931224 -408.604375) (xy 45.903617 -408.53377) (xy 45.883671 -408.460629)
			(xy 45.871612 -408.385784) (xy 45.867577 -408.31008) (xy 44.751498 -408.31008) (xy 44.750994 -408.347986)
			(xy 44.742935 -408.423367) (xy 44.72691 -408.497465) (xy 44.7031 -408.56944) (xy 44.671774 -408.638476)
			(xy 44.633287 -408.703791) (xy 44.588076 -408.764646) (xy 44.536652 -408.82035) (xy 44.479599 -408.870272)
			(xy 44.417563 -408.913847) (xy 44.351246 -408.950582) (xy 44.2814 -408.980059) (xy 44.208817 -409.001945)
			(xy 44.134319 -409.015992) (xy 44.058749 -409.022041) (xy 43.982965 -409.020022) (xy 43.907825 -409.00996)
			(xy 43.83418 -408.991968) (xy 43.762864 -408.96625) (xy 43.694687 -408.933098) (xy 43.630419 -408.892886)
			(xy 43.57079 -408.846071) (xy 43.516474 -408.793183) (xy 43.468088 -408.734821) (xy 43.42618 -408.671646)
			(xy 43.391224 -408.604375) (xy 43.363617 -408.53377) (xy 43.343671 -408.460629) (xy 43.331612 -408.385784)
			(xy 43.327577 -408.31008) (xy 42.502604 -408.31008) (xy 42.502322 -408.310305) (xy 42.406779 -408.376254)
			(xy 42.306914 -408.435454) (xy 42.203202 -408.487623) (xy 42.096139 -408.532512) (xy 41.986233 -408.569908)
			(xy 41.874009 -408.599633) (xy 41.760003 -408.621544) (xy 41.644756 -408.635537) (xy 41.528818 -408.641546)
			(xy 41.412742 -408.639543) (xy 41.29708 -408.629535) (xy 41.182385 -408.611572) (xy 41.069202 -408.585739)
			(xy 40.958071 -408.552159) (xy 40.849522 -408.510991) (xy 40.744072 -408.462433) (xy 40.642223 -408.406716)
			(xy 40.54446 -408.344104) (xy 40.45125 -408.274897) (xy 40.363037 -408.199424) (xy 40.280241 -408.118045)
			(xy 40.203257 -408.031148) (xy 40.132452 -407.939147) (xy 40.068162 -407.84248) (xy 40.010695 -407.741608)
			(xy 39.960324 -407.637011) (xy 39.917289 -407.529188) (xy 39.881795 -407.418654) (xy 39.854012 -407.305934)
			(xy 39.834072 -407.191566) (xy 39.82207 -407.076094) (xy 39.818063 -406.96007) (xy 36.329254 -406.96007)
			(xy 36.315846 -406.981724) (xy 36.263477 -407.051071) (xy 36.204933 -407.115291) (xy 36.140713 -407.173835)
			(xy 36.071366 -407.226204) (xy 35.997482 -407.271951) (xy 35.919693 -407.310685) (xy 35.838661 -407.342077)
			(xy 35.755079 -407.365858) (xy 35.669659 -407.381826) (xy 35.58313 -407.389844) (xy 35.49623 -407.389844)
			(xy 35.409701 -407.381826) (xy 35.324281 -407.365858) (xy 35.240699 -407.342077) (xy 35.159667 -407.310685)
			(xy 35.081878 -407.271951) (xy 35.007994 -407.226204) (xy 34.938647 -407.173835) (xy 34.874427 -407.115291)
			(xy 34.815883 -407.051071) (xy 34.763514 -406.981724) (xy 34.717767 -406.90784) (xy 34.679033 -406.830051)
			(xy 34.647641 -406.749019) (xy 34.62386 -406.665437) (xy 34.607892 -406.580017) (xy 34.599874 -406.493488)
			(xy 31.399486 -406.493488) (xy 31.391468 -406.580017) (xy 31.3755 -406.665437) (xy 31.351719 -406.749019)
			(xy 31.320327 -406.830051) (xy 31.281593 -406.90784) (xy 31.235846 -406.981724) (xy 31.183477 -407.051071)
			(xy 31.124933 -407.115291) (xy 31.060713 -407.173835) (xy 30.991366 -407.226204) (xy 30.917482 -407.271951)
			(xy 30.839693 -407.310685) (xy 30.758661 -407.342077) (xy 30.675079 -407.365858) (xy 30.589659 -407.381826)
			(xy 30.50313 -407.389844) (xy 30.41623 -407.389844) (xy 30.329701 -407.381826) (xy 30.244281 -407.365858)
			(xy 30.160699 -407.342077) (xy 30.079667 -407.310685) (xy 30.001878 -407.271951) (xy 29.927994 -407.226204)
			(xy 29.858647 -407.173835) (xy 29.794427 -407.115291) (xy 29.735883 -407.051071) (xy 29.683514 -406.981724)
			(xy 29.637767 -406.90784) (xy 29.599033 -406.830051) (xy 29.567641 -406.749019) (xy 29.54386 -406.665437)
			(xy 29.527892 -406.580017) (xy 29.519874 -406.493488) (xy 29.254196 -406.493488) (xy 29.254196 -416.955732)
			(xy 73.130916 -416.955732) (xy 73.134987 -416.90011) (xy 73.147113 -416.845673) (xy 73.167036 -416.793582)
			(xy 73.194332 -416.744947) (xy 73.228418 -416.700804) (xy 73.268567 -416.662095) (xy 73.313925 -416.629644)
			(xy 73.363525 -416.604143) (xy 73.416309 -416.586136) (xy 73.471152 -416.576006) (xy 73.526886 -416.573969)
			(xy 73.582323 -416.580069) (xy 73.63628 -416.594175) (xy 73.687609 -416.615987) (xy 73.735215 -416.645041)
			(xy 73.778083 -416.680716) (xy 73.8153 -416.722253) (xy 73.846073 -416.768766) (xy 73.869745 -416.819263)
			(xy 73.885813 -416.87267) (xy 73.893933 -416.927846) (xy 73.894442 -416.955732) (xy 74.316842 -416.955732)
			(xy 74.320913 -416.90011) (xy 74.333039 -416.845673) (xy 74.352962 -416.793582) (xy 74.380258 -416.744947)
			(xy 74.414344 -416.700804) (xy 74.454493 -416.662095) (xy 74.499851 -416.629644) (xy 74.549451 -416.604143)
			(xy 74.602235 -416.586136) (xy 74.657078 -416.576006) (xy 74.712812 -416.573969) (xy 74.768249 -416.580069)
			(xy 74.822206 -416.594175) (xy 74.873535 -416.615987) (xy 74.921141 -416.645041) (xy 74.964009 -416.680716)
			(xy 75.001226 -416.722253) (xy 75.031999 -416.768766) (xy 75.055671 -416.819263) (xy 75.071739 -416.87267)
			(xy 75.079859 -416.927846) (xy 75.080368 -416.955732) (xy 75.079859 -416.983618) (xy 75.071739 -417.038794)
			(xy 75.055671 -417.092201) (xy 75.031999 -417.142698) (xy 75.001226 -417.189211) (xy 74.964009 -417.230748)
			(xy 74.921141 -417.266423) (xy 74.873535 -417.295477) (xy 74.822206 -417.317289) (xy 74.768249 -417.331395)
			(xy 74.712812 -417.337495) (xy 74.657078 -417.335458) (xy 74.602235 -417.325328) (xy 74.549451 -417.307321)
			(xy 74.499851 -417.28182) (xy 74.454493 -417.249369) (xy 74.414344 -417.21066) (xy 74.380258 -417.166517)
			(xy 74.352962 -417.117882) (xy 74.333039 -417.065791) (xy 74.320913 -417.011354) (xy 74.316842 -416.955732)
			(xy 73.894442 -416.955732) (xy 73.893933 -416.983618) (xy 73.885813 -417.038794) (xy 73.869745 -417.092201)
			(xy 73.846073 -417.142698) (xy 73.8153 -417.189211) (xy 73.778083 -417.230748) (xy 73.735215 -417.266423)
			(xy 73.687609 -417.295477) (xy 73.63628 -417.317289) (xy 73.582323 -417.331395) (xy 73.526886 -417.337495)
			(xy 73.471152 -417.335458) (xy 73.416309 -417.325328) (xy 73.363525 -417.307321) (xy 73.313925 -417.28182)
			(xy 73.268567 -417.249369) (xy 73.228418 -417.21066) (xy 73.194332 -417.166517) (xy 73.167036 -417.117882)
			(xy 73.147113 -417.065791) (xy 73.134987 -417.011354) (xy 73.130916 -416.955732) (xy 29.254196 -416.955732)
			(xy 29.254196 -417.800282) (xy 71.775826 -417.800282) (xy 71.779897 -417.74466) (xy 71.792023 -417.690223)
			(xy 71.811946 -417.638132) (xy 71.839242 -417.589497) (xy 71.873328 -417.545354) (xy 71.913477 -417.506645)
			(xy 71.958835 -417.474194) (xy 72.008435 -417.448693) (xy 72.061219 -417.430686) (xy 72.116062 -417.420556)
			(xy 72.171796 -417.418519) (xy 72.227233 -417.424619) (xy 72.28119 -417.438725) (xy 72.332519 -417.460537)
			(xy 72.380125 -417.489591) (xy 72.422993 -417.525266) (xy 72.46021 -417.566803) (xy 72.490983 -417.613316)
			(xy 72.514655 -417.663813) (xy 72.530723 -417.71722) (xy 72.538843 -417.772396) (xy 72.539352 -417.800282)
			(xy 72.538843 -417.828168) (xy 72.530723 -417.883344) (xy 72.514655 -417.936751) (xy 72.490983 -417.987248)
			(xy 72.46021 -418.033761) (xy 72.422993 -418.075298) (xy 72.380125 -418.110973) (xy 72.332519 -418.140027)
			(xy 72.28119 -418.161839) (xy 72.227233 -418.175945) (xy 72.171796 -418.182045) (xy 72.116062 -418.180008)
			(xy 72.061219 -418.169878) (xy 72.008435 -418.151871) (xy 71.958835 -418.12637) (xy 71.913477 -418.093919)
			(xy 71.873328 -418.05521) (xy 71.839242 -418.011067) (xy 71.811946 -417.962432) (xy 71.792023 -417.910341)
			(xy 71.779897 -417.855904) (xy 71.775826 -417.800282) (xy 29.254196 -417.800282) (xy 29.254196 -418.677513)
			(xy 47.978812 -418.677513) (xy 47.978812 -418.596403) (xy 47.986762 -418.515684) (xy 48.002585 -418.436133)
			(xy 48.02613 -418.358517) (xy 48.057169 -418.283581) (xy 48.095404 -418.212049) (xy 48.140466 -418.144609)
			(xy 48.191921 -418.08191) (xy 48.249274 -418.024557) (xy 48.311973 -417.973102) (xy 48.379413 -417.92804)
			(xy 48.450945 -417.889805) (xy 48.525881 -417.858766) (xy 48.603497 -417.835221) (xy 48.683048 -417.819398)
			(xy 48.763767 -417.811448) (xy 48.844877 -417.811448) (xy 48.925596 -417.819398) (xy 49.005147 -417.835221)
			(xy 49.082763 -417.858766) (xy 49.157699 -417.889805) (xy 49.229231 -417.92804) (xy 49.296671 -417.973102)
			(xy 49.35937 -418.024557) (xy 49.416723 -418.08191) (xy 49.468178 -418.144609) (xy 49.51324 -418.212049)
			(xy 49.551475 -418.283581) (xy 49.582514 -418.358517) (xy 49.606059 -418.436133) (xy 49.621882 -418.515684)
			(xy 49.629832 -418.596403) (xy 49.63033 -418.636958) (xy 49.629832 -418.677513) (xy 49.621882 -418.758232)
			(xy 49.606059 -418.837783) (xy 49.582514 -418.915399) (xy 49.551475 -418.990335) (xy 49.51324 -419.061867)
			(xy 49.468178 -419.129307) (xy 49.416723 -419.192006) (xy 49.35937 -419.249359) (xy 49.296671 -419.300814)
			(xy 49.229231 -419.345876) (xy 49.157699 -419.384111) (xy 49.082763 -419.41515) (xy 49.005147 -419.438695)
			(xy 48.925596 -419.454518) (xy 48.844877 -419.462468) (xy 48.763767 -419.462468) (xy 48.683048 -419.454518)
			(xy 48.603497 -419.438695) (xy 48.525881 -419.41515) (xy 48.450945 -419.384111) (xy 48.379413 -419.345876)
			(xy 48.311973 -419.300814) (xy 48.249274 -419.249359) (xy 48.191921 -419.192006) (xy 48.140466 -419.129307)
			(xy 48.095404 -419.061867) (xy 48.057169 -418.990335) (xy 48.02613 -418.915399) (xy 48.002585 -418.837783)
			(xy 47.986762 -418.758232) (xy 47.978812 -418.677513) (xy 29.254196 -418.677513) (xy 29.254196 -420.06012)
			(xy 86.877404 -420.06012) (xy 86.881424 -419.869469) (xy 86.893478 -419.679156) (xy 86.913544 -419.489521)
			(xy 86.941587 -419.3009) (xy 86.977556 -419.11363) (xy 87.021388 -418.928042) (xy 87.073005 -418.744467)
			(xy 87.132315 -418.563231) (xy 87.199213 -418.384656) (xy 87.273579 -418.209061) (xy 87.355281 -418.036756)
			(xy 87.444175 -417.868049) (xy 87.540101 -417.703239) (xy 87.64289 -417.54262) (xy 87.752359 -417.386477)
			(xy 87.868313 -417.235088) (xy 87.990547 -417.088721) (xy 88.118841 -416.947637) (xy 88.252969 -416.812088)
			(xy 88.392693 -416.682313) (xy 88.537763 -416.558543) (xy 88.687921 -416.441) (xy 88.842902 -416.329891)
			(xy 89.002429 -416.225414) (xy 89.166218 -416.127755) (xy 89.333978 -416.037088) (xy 89.505412 -415.953574)
			(xy 89.680214 -415.877361) (xy 89.858073 -415.808585) (xy 90.038674 -415.747367) (xy 90.221694 -415.693818)
			(xy 90.40681 -415.648032) (xy 90.593691 -415.61009) (xy 90.782006 -415.580061) (xy 90.971419 -415.557996)
			(xy 91.161593 -415.543937) (xy 91.352192 -415.537907) (xy 91.542875 -415.539917) (xy 91.733304 -415.549964)
			(xy 91.92314 -415.56803) (xy 92.112046 -415.594083) (xy 92.299685 -415.628076) (xy 92.485725 -415.669949)
			(xy 92.669834 -415.719628) (xy 92.851685 -415.777024) (xy 93.030955 -415.842035) (xy 93.207325 -415.914546)
			(xy 93.380481 -415.994427) (xy 93.550116 -416.081537) (xy 93.715928 -416.175721) (xy 93.877622 -416.276812)
			(xy 94.03491 -416.384628) (xy 94.187513 -416.49898) (xy 94.335161 -416.619663) (xy 94.477589 -416.746464)
			(xy 94.614545 -416.879155) (xy 94.745786 -417.017503) (xy 94.871078 -417.16126) (xy 94.990198 -417.310171)
			(xy 95.102934 -417.463972) (xy 95.209087 -417.622388) (xy 95.308467 -417.785139) (xy 95.400897 -417.951934)
			(xy 95.486214 -418.122478) (xy 95.564266 -418.296466) (xy 95.634913 -418.473591) (xy 95.698031 -418.653536)
			(xy 95.753507 -418.835982) (xy 95.801242 -419.020605) (xy 95.841152 -419.207075) (xy 95.873165 -419.395063)
			(xy 95.897225 -419.584233) (xy 95.913288 -419.774249) (xy 95.921327 -419.964773) (xy 95.92183 -420.06012)
			(xy 95.921327 -420.155467) (xy 95.913288 -420.345991) (xy 95.897225 -420.536007) (xy 95.873165 -420.725177)
			(xy 95.841152 -420.913165) (xy 95.801242 -421.099635) (xy 95.753507 -421.284258) (xy 95.698031 -421.466704)
			(xy 95.634913 -421.646649) (xy 95.564266 -421.823774) (xy 95.486214 -421.997762) (xy 95.400897 -422.168306)
			(xy 95.308467 -422.335101) (xy 95.209087 -422.497852) (xy 95.102934 -422.656268) (xy 94.990198 -422.810069)
			(xy 94.871078 -422.95898) (xy 94.745786 -423.102737) (xy 94.614545 -423.241085) (xy 94.477589 -423.373776)
			(xy 94.335161 -423.500577) (xy 94.187513 -423.62126) (xy 94.03491 -423.735612) (xy 93.877622 -423.843428)
			(xy 93.715928 -423.944519) (xy 93.550116 -424.038703) (xy 93.380481 -424.125813) (xy 93.207325 -424.205694)
			(xy 93.030955 -424.278205) (xy 92.851685 -424.343216) (xy 92.669834 -424.400612) (xy 92.485725 -424.450291)
			(xy 92.299685 -424.492164) (xy 92.112046 -424.526157) (xy 91.92314 -424.55221) (xy 91.733304 -424.570276)
			(xy 91.542875 -424.580323) (xy 91.352192 -424.582333) (xy 91.161593 -424.576303) (xy 90.971419 -424.562244)
			(xy 90.782006 -424.540179) (xy 90.593691 -424.51015) (xy 90.40681 -424.472208) (xy 90.221694 -424.426422)
			(xy 90.038674 -424.372873) (xy 89.858073 -424.311655) (xy 89.680214 -424.242879) (xy 89.505412 -424.166666)
			(xy 89.333978 -424.083152) (xy 89.166218 -423.992485) (xy 89.002429 -423.894826) (xy 88.842902 -423.790349)
			(xy 88.687921 -423.67924) (xy 88.537763 -423.561697) (xy 88.392693 -423.437927) (xy 88.252969 -423.308152)
			(xy 88.118841 -423.172603) (xy 87.990547 -423.031519) (xy 87.868313 -422.885152) (xy 87.752359 -422.733763)
			(xy 87.64289 -422.57762) (xy 87.540101 -422.417001) (xy 87.444175 -422.252191) (xy 87.355281 -422.083484)
			(xy 87.273579 -421.911179) (xy 87.199213 -421.735584) (xy 87.132315 -421.557009) (xy 87.073005 -421.375773)
			(xy 87.021388 -421.192198) (xy 86.977556 -421.00661) (xy 86.941587 -420.81934) (xy 86.913544 -420.630719)
			(xy 86.893478 -420.441084) (xy 86.881424 -420.250771) (xy 86.877404 -420.06012) (xy 29.254196 -420.06012)
			(xy 29.254196 -422.480079) (xy 56.548266 -422.480079) (xy 56.548266 -422.408757) (xy 56.556252 -422.337883)
			(xy 56.572122 -422.268348) (xy 56.595679 -422.201028) (xy 56.626624 -422.136769) (xy 56.66457 -422.076378)
			(xy 56.709039 -422.020616) (xy 56.759472 -421.970183) (xy 56.815234 -421.925714) (xy 56.875625 -421.887768)
			(xy 56.939884 -421.856823) (xy 57.007204 -421.833266) (xy 57.076739 -421.817396) (xy 57.147613 -421.80941)
			(xy 57.218935 -421.80941) (xy 57.289809 -421.817396) (xy 57.359344 -421.833266) (xy 57.426664 -421.856823)
			(xy 57.490923 -421.887768) (xy 57.551314 -421.925714) (xy 57.607076 -421.970183) (xy 57.657509 -422.020616)
			(xy 57.701978 -422.076378) (xy 57.739924 -422.136769) (xy 57.770869 -422.201028) (xy 57.794426 -422.268348)
			(xy 57.810296 -422.337883) (xy 57.818282 -422.408757) (xy 57.818782 -422.444418) (xy 57.818282 -422.480079)
			(xy 58.434978 -422.480079) (xy 58.434978 -422.408757) (xy 58.442964 -422.337883) (xy 58.458834 -422.268348)
			(xy 58.482391 -422.201028) (xy 58.513336 -422.136769) (xy 58.551282 -422.076378) (xy 58.595751 -422.020616)
			(xy 58.646184 -421.970183) (xy 58.701946 -421.925714) (xy 58.762337 -421.887768) (xy 58.826596 -421.856823)
			(xy 58.893916 -421.833266) (xy 58.963451 -421.817396) (xy 59.034325 -421.80941) (xy 59.105647 -421.80941)
			(xy 59.176521 -421.817396) (xy 59.246056 -421.833266) (xy 59.313376 -421.856823) (xy 59.377635 -421.887768)
			(xy 59.438026 -421.925714) (xy 59.493788 -421.970183) (xy 59.544221 -422.020616) (xy 59.58869 -422.076378)
			(xy 59.626636 -422.136769) (xy 59.657581 -422.201028) (xy 59.681138 -422.268348) (xy 59.697008 -422.337883)
			(xy 59.704994 -422.408757) (xy 59.705494 -422.444418) (xy 59.704994 -422.480079) (xy 59.697008 -422.550953)
			(xy 59.681138 -422.620488) (xy 59.657581 -422.687808) (xy 59.626636 -422.752067) (xy 59.58869 -422.812458)
			(xy 59.544221 -422.86822) (xy 59.493788 -422.918653) (xy 59.438026 -422.963122) (xy 59.377635 -423.001068)
			(xy 59.313376 -423.032013) (xy 59.246056 -423.05557) (xy 59.176521 -423.07144) (xy 59.105647 -423.079426)
			(xy 59.034325 -423.079426) (xy 58.963451 -423.07144) (xy 58.893916 -423.05557) (xy 58.826596 -423.032013)
			(xy 58.762337 -423.001068) (xy 58.701946 -422.963122) (xy 58.646184 -422.918653) (xy 58.595751 -422.86822)
			(xy 58.551282 -422.812458) (xy 58.513336 -422.752067) (xy 58.482391 -422.687808) (xy 58.458834 -422.620488)
			(xy 58.442964 -422.550953) (xy 58.434978 -422.480079) (xy 57.818282 -422.480079) (xy 57.810296 -422.550953)
			(xy 57.794426 -422.620488) (xy 57.770869 -422.687808) (xy 57.739924 -422.752067) (xy 57.701978 -422.812458)
			(xy 57.657509 -422.86822) (xy 57.607076 -422.918653) (xy 57.551314 -422.963122) (xy 57.490923 -423.001068)
			(xy 57.426664 -423.032013) (xy 57.359344 -423.05557) (xy 57.289809 -423.07144) (xy 57.218935 -423.079426)
			(xy 57.147613 -423.079426) (xy 57.076739 -423.07144) (xy 57.007204 -423.05557) (xy 56.939884 -423.032013)
			(xy 56.875625 -423.001068) (xy 56.815234 -422.963122) (xy 56.759472 -422.918653) (xy 56.709039 -422.86822)
			(xy 56.66457 -422.812458) (xy 56.626624 -422.752067) (xy 56.595679 -422.687808) (xy 56.572122 -422.620488)
			(xy 56.556252 -422.550953) (xy 56.548266 -422.480079) (xy 29.254196 -422.480079) (xy 29.254196 -424.313705)
			(xy 56.548266 -424.313705) (xy 56.548266 -424.242383) (xy 56.556252 -424.171509) (xy 56.572122 -424.101974)
			(xy 56.595679 -424.034654) (xy 56.626624 -423.970395) (xy 56.66457 -423.910004) (xy 56.709039 -423.854242)
			(xy 56.759472 -423.803809) (xy 56.815234 -423.75934) (xy 56.875625 -423.721394) (xy 56.939884 -423.690449)
			(xy 57.007204 -423.666892) (xy 57.076739 -423.651022) (xy 57.147613 -423.643036) (xy 57.218935 -423.643036)
			(xy 57.289809 -423.651022) (xy 57.359344 -423.666892) (xy 57.426664 -423.690449) (xy 57.490923 -423.721394)
			(xy 57.551314 -423.75934) (xy 57.607076 -423.803809) (xy 57.657509 -423.854242) (xy 57.701978 -423.910004)
			(xy 57.739924 -423.970395) (xy 57.770869 -424.034654) (xy 57.794426 -424.101974) (xy 57.810296 -424.171509)
			(xy 57.818282 -424.242383) (xy 57.818782 -424.278044) (xy 57.818282 -424.313705) (xy 58.434978 -424.313705)
			(xy 58.434978 -424.242383) (xy 58.442964 -424.171509) (xy 58.458834 -424.101974) (xy 58.482391 -424.034654)
			(xy 58.513336 -423.970395) (xy 58.551282 -423.910004) (xy 58.595751 -423.854242) (xy 58.646184 -423.803809)
			(xy 58.701946 -423.75934) (xy 58.762337 -423.721394) (xy 58.826596 -423.690449) (xy 58.893916 -423.666892)
			(xy 58.963451 -423.651022) (xy 59.034325 -423.643036) (xy 59.105647 -423.643036) (xy 59.176521 -423.651022)
			(xy 59.246056 -423.666892) (xy 59.313376 -423.690449) (xy 59.377635 -423.721394) (xy 59.438026 -423.75934)
			(xy 59.493788 -423.803809) (xy 59.544221 -423.854242) (xy 59.58869 -423.910004) (xy 59.626636 -423.970395)
			(xy 59.657581 -424.034654) (xy 59.681138 -424.101974) (xy 59.697008 -424.171509) (xy 59.704994 -424.242383)
			(xy 59.705494 -424.278044) (xy 59.704994 -424.313705) (xy 60.67602 -424.313705) (xy 60.67602 -424.242383)
			(xy 60.684006 -424.171509) (xy 60.699876 -424.101974) (xy 60.723433 -424.034654) (xy 60.754378 -423.970395)
			(xy 60.792324 -423.910004) (xy 60.836793 -423.854242) (xy 60.887226 -423.803809) (xy 60.942988 -423.75934)
			(xy 61.003379 -423.721394) (xy 61.067638 -423.690449) (xy 61.134958 -423.666892) (xy 61.204493 -423.651022)
			(xy 61.275367 -423.643036) (xy 61.346689 -423.643036) (xy 61.417563 -423.651022) (xy 61.487098 -423.666892)
			(xy 61.554418 -423.690449) (xy 61.618677 -423.721394) (xy 61.679068 -423.75934) (xy 61.73483 -423.803809)
			(xy 61.785263 -423.854242) (xy 61.829732 -423.910004) (xy 61.867678 -423.970395) (xy 61.898623 -424.034654)
			(xy 61.92218 -424.101974) (xy 61.93805 -424.171509) (xy 61.946036 -424.242383) (xy 61.946536 -424.278044)
			(xy 61.946036 -424.313705) (xy 62.580004 -424.313705) (xy 62.580004 -424.242383) (xy 62.58799 -424.171509)
			(xy 62.60386 -424.101974) (xy 62.627417 -424.034654) (xy 62.658362 -423.970395) (xy 62.696308 -423.910004)
			(xy 62.740777 -423.854242) (xy 62.79121 -423.803809) (xy 62.846972 -423.75934) (xy 62.907363 -423.721394)
			(xy 62.971622 -423.690449) (xy 63.038942 -423.666892) (xy 63.108477 -423.651022) (xy 63.179351 -423.643036)
			(xy 63.250673 -423.643036) (xy 63.321547 -423.651022) (xy 63.391082 -423.666892) (xy 63.458402 -423.690449)
			(xy 63.522661 -423.721394) (xy 63.583052 -423.75934) (xy 63.638814 -423.803809) (xy 63.689247 -423.854242)
			(xy 63.733716 -423.910004) (xy 63.771662 -423.970395) (xy 63.802607 -424.034654) (xy 63.826164 -424.101974)
			(xy 63.842034 -424.171509) (xy 63.85002 -424.242383) (xy 63.85052 -424.278044) (xy 63.85002 -424.313705)
			(xy 63.842034 -424.384579) (xy 63.826164 -424.454114) (xy 63.802607 -424.521434) (xy 63.771662 -424.585693)
			(xy 63.733716 -424.646084) (xy 63.689247 -424.701846) (xy 63.638814 -424.752279) (xy 63.583052 -424.796748)
			(xy 63.522661 -424.834694) (xy 63.458402 -424.865639) (xy 63.391082 -424.889196) (xy 63.321547 -424.905066)
			(xy 63.250673 -424.913052) (xy 63.179351 -424.913052) (xy 63.108477 -424.905066) (xy 63.038942 -424.889196)
			(xy 62.971622 -424.865639) (xy 62.907363 -424.834694) (xy 62.846972 -424.796748) (xy 62.79121 -424.752279)
			(xy 62.740777 -424.701846) (xy 62.696308 -424.646084) (xy 62.658362 -424.585693) (xy 62.627417 -424.521434)
			(xy 62.60386 -424.454114) (xy 62.58799 -424.384579) (xy 62.580004 -424.313705) (xy 61.946036 -424.313705)
			(xy 61.93805 -424.384579) (xy 61.92218 -424.454114) (xy 61.898623 -424.521434) (xy 61.867678 -424.585693)
			(xy 61.829732 -424.646084) (xy 61.785263 -424.701846) (xy 61.73483 -424.752279) (xy 61.679068 -424.796748)
			(xy 61.618677 -424.834694) (xy 61.554418 -424.865639) (xy 61.487098 -424.889196) (xy 61.417563 -424.905066)
			(xy 61.346689 -424.913052) (xy 61.275367 -424.913052) (xy 61.204493 -424.905066) (xy 61.134958 -424.889196)
			(xy 61.067638 -424.865639) (xy 61.003379 -424.834694) (xy 60.942988 -424.796748) (xy 60.887226 -424.752279)
			(xy 60.836793 -424.701846) (xy 60.792324 -424.646084) (xy 60.754378 -424.585693) (xy 60.723433 -424.521434)
			(xy 60.699876 -424.454114) (xy 60.684006 -424.384579) (xy 60.67602 -424.313705) (xy 59.704994 -424.313705)
			(xy 59.697008 -424.384579) (xy 59.681138 -424.454114) (xy 59.657581 -424.521434) (xy 59.626636 -424.585693)
			(xy 59.58869 -424.646084) (xy 59.544221 -424.701846) (xy 59.493788 -424.752279) (xy 59.438026 -424.796748)
			(xy 59.377635 -424.834694) (xy 59.313376 -424.865639) (xy 59.246056 -424.889196) (xy 59.176521 -424.905066)
			(xy 59.105647 -424.913052) (xy 59.034325 -424.913052) (xy 58.963451 -424.905066) (xy 58.893916 -424.889196)
			(xy 58.826596 -424.865639) (xy 58.762337 -424.834694) (xy 58.701946 -424.796748) (xy 58.646184 -424.752279)
			(xy 58.595751 -424.701846) (xy 58.551282 -424.646084) (xy 58.513336 -424.585693) (xy 58.482391 -424.521434)
			(xy 58.458834 -424.454114) (xy 58.442964 -424.384579) (xy 58.434978 -424.313705) (xy 57.818282 -424.313705)
			(xy 57.810296 -424.384579) (xy 57.794426 -424.454114) (xy 57.770869 -424.521434) (xy 57.739924 -424.585693)
			(xy 57.701978 -424.646084) (xy 57.657509 -424.701846) (xy 57.607076 -424.752279) (xy 57.551314 -424.796748)
			(xy 57.490923 -424.834694) (xy 57.426664 -424.865639) (xy 57.359344 -424.889196) (xy 57.289809 -424.905066)
			(xy 57.218935 -424.913052) (xy 57.147613 -424.913052) (xy 57.076739 -424.905066) (xy 57.007204 -424.889196)
			(xy 56.939884 -424.865639) (xy 56.875625 -424.834694) (xy 56.815234 -424.796748) (xy 56.759472 -424.752279)
			(xy 56.709039 -424.701846) (xy 56.66457 -424.646084) (xy 56.626624 -424.585693) (xy 56.595679 -424.521434)
			(xy 56.572122 -424.454114) (xy 56.556252 -424.384579) (xy 56.548266 -424.313705) (xy 29.254196 -424.313705)
			(xy 29.254196 -426.214641) (xy 56.548266 -426.214641) (xy 56.548266 -426.143319) (xy 56.556252 -426.072445)
			(xy 56.572122 -426.00291) (xy 56.595679 -425.93559) (xy 56.626624 -425.871331) (xy 56.66457 -425.81094)
			(xy 56.709039 -425.755178) (xy 56.759472 -425.704745) (xy 56.815234 -425.660276) (xy 56.875625 -425.62233)
			(xy 56.939884 -425.591385) (xy 57.007204 -425.567828) (xy 57.076739 -425.551958) (xy 57.147613 -425.543972)
			(xy 57.218935 -425.543972) (xy 57.289809 -425.551958) (xy 57.359344 -425.567828) (xy 57.426664 -425.591385)
			(xy 57.490923 -425.62233) (xy 57.551314 -425.660276) (xy 57.607076 -425.704745) (xy 57.657509 -425.755178)
			(xy 57.701978 -425.81094) (xy 57.739924 -425.871331) (xy 57.770869 -425.93559) (xy 57.794426 -426.00291)
			(xy 57.810296 -426.072445) (xy 57.818282 -426.143319) (xy 57.818782 -426.17898) (xy 57.818282 -426.214641)
			(xy 58.434978 -426.214641) (xy 58.434978 -426.143319) (xy 58.442964 -426.072445) (xy 58.458834 -426.00291)
			(xy 58.482391 -425.93559) (xy 58.513336 -425.871331) (xy 58.551282 -425.81094) (xy 58.595751 -425.755178)
			(xy 58.646184 -425.704745) (xy 58.701946 -425.660276) (xy 58.762337 -425.62233) (xy 58.826596 -425.591385)
			(xy 58.893916 -425.567828) (xy 58.963451 -425.551958) (xy 59.034325 -425.543972) (xy 59.105647 -425.543972)
			(xy 59.176521 -425.551958) (xy 59.246056 -425.567828) (xy 59.313376 -425.591385) (xy 59.377635 -425.62233)
			(xy 59.438026 -425.660276) (xy 59.493788 -425.704745) (xy 59.544221 -425.755178) (xy 59.58869 -425.81094)
			(xy 59.626636 -425.871331) (xy 59.657581 -425.93559) (xy 59.681138 -426.00291) (xy 59.697008 -426.072445)
			(xy 59.704994 -426.143319) (xy 59.705494 -426.17898) (xy 59.704994 -426.214641) (xy 60.67602 -426.214641)
			(xy 60.67602 -426.143319) (xy 60.684006 -426.072445) (xy 60.699876 -426.00291) (xy 60.723433 -425.93559)
			(xy 60.754378 -425.871331) (xy 60.792324 -425.81094) (xy 60.836793 -425.755178) (xy 60.887226 -425.704745)
			(xy 60.942988 -425.660276) (xy 61.003379 -425.62233) (xy 61.067638 -425.591385) (xy 61.134958 -425.567828)
			(xy 61.204493 -425.551958) (xy 61.275367 -425.543972) (xy 61.346689 -425.543972) (xy 61.417563 -425.551958)
			(xy 61.487098 -425.567828) (xy 61.554418 -425.591385) (xy 61.618677 -425.62233) (xy 61.679068 -425.660276)
			(xy 61.73483 -425.704745) (xy 61.785263 -425.755178) (xy 61.829732 -425.81094) (xy 61.867678 -425.871331)
			(xy 61.898623 -425.93559) (xy 61.92218 -426.00291) (xy 61.93805 -426.072445) (xy 61.946036 -426.143319)
			(xy 61.946536 -426.17898) (xy 61.946036 -426.214641) (xy 62.580004 -426.214641) (xy 62.580004 -426.143319)
			(xy 62.58799 -426.072445) (xy 62.60386 -426.00291) (xy 62.627417 -425.93559) (xy 62.658362 -425.871331)
			(xy 62.696308 -425.81094) (xy 62.740777 -425.755178) (xy 62.79121 -425.704745) (xy 62.846972 -425.660276)
			(xy 62.907363 -425.62233) (xy 62.971622 -425.591385) (xy 63.038942 -425.567828) (xy 63.108477 -425.551958)
			(xy 63.179351 -425.543972) (xy 63.250673 -425.543972) (xy 63.321547 -425.551958) (xy 63.391082 -425.567828)
			(xy 63.458402 -425.591385) (xy 63.522661 -425.62233) (xy 63.583052 -425.660276) (xy 63.638814 -425.704745)
			(xy 63.689247 -425.755178) (xy 63.733716 -425.81094) (xy 63.771662 -425.871331) (xy 63.802607 -425.93559)
			(xy 63.826164 -426.00291) (xy 63.842034 -426.072445) (xy 63.85002 -426.143319) (xy 63.85052 -426.17898)
			(xy 63.85002 -426.214641) (xy 63.842034 -426.285515) (xy 63.826164 -426.35505) (xy 63.802607 -426.42237)
			(xy 63.771662 -426.486629) (xy 63.733716 -426.54702) (xy 63.689247 -426.602782) (xy 63.638814 -426.653215)
			(xy 63.583052 -426.697684) (xy 63.522661 -426.73563) (xy 63.458402 -426.766575) (xy 63.391082 -426.790132)
			(xy 63.321547 -426.806002) (xy 63.250673 -426.813988) (xy 63.179351 -426.813988) (xy 63.108477 -426.806002)
			(xy 63.038942 -426.790132) (xy 62.971622 -426.766575) (xy 62.907363 -426.73563) (xy 62.846972 -426.697684)
			(xy 62.79121 -426.653215) (xy 62.740777 -426.602782) (xy 62.696308 -426.54702) (xy 62.658362 -426.486629)
			(xy 62.627417 -426.42237) (xy 62.60386 -426.35505) (xy 62.58799 -426.285515) (xy 62.580004 -426.214641)
			(xy 61.946036 -426.214641) (xy 61.93805 -426.285515) (xy 61.92218 -426.35505) (xy 61.898623 -426.42237)
			(xy 61.867678 -426.486629) (xy 61.829732 -426.54702) (xy 61.785263 -426.602782) (xy 61.73483 -426.653215)
			(xy 61.679068 -426.697684) (xy 61.618677 -426.73563) (xy 61.554418 -426.766575) (xy 61.487098 -426.790132)
			(xy 61.417563 -426.806002) (xy 61.346689 -426.813988) (xy 61.275367 -426.813988) (xy 61.204493 -426.806002)
			(xy 61.134958 -426.790132) (xy 61.067638 -426.766575) (xy 61.003379 -426.73563) (xy 60.942988 -426.697684)
			(xy 60.887226 -426.653215) (xy 60.836793 -426.602782) (xy 60.792324 -426.54702) (xy 60.754378 -426.486629)
			(xy 60.723433 -426.42237) (xy 60.699876 -426.35505) (xy 60.684006 -426.285515) (xy 60.67602 -426.214641)
			(xy 59.704994 -426.214641) (xy 59.697008 -426.285515) (xy 59.681138 -426.35505) (xy 59.657581 -426.42237)
			(xy 59.626636 -426.486629) (xy 59.58869 -426.54702) (xy 59.544221 -426.602782) (xy 59.493788 -426.653215)
			(xy 59.438026 -426.697684) (xy 59.377635 -426.73563) (xy 59.313376 -426.766575) (xy 59.246056 -426.790132)
			(xy 59.176521 -426.806002) (xy 59.105647 -426.813988) (xy 59.034325 -426.813988) (xy 58.963451 -426.806002)
			(xy 58.893916 -426.790132) (xy 58.826596 -426.766575) (xy 58.762337 -426.73563) (xy 58.701946 -426.697684)
			(xy 58.646184 -426.653215) (xy 58.595751 -426.602782) (xy 58.551282 -426.54702) (xy 58.513336 -426.486629)
			(xy 58.482391 -426.42237) (xy 58.458834 -426.35505) (xy 58.442964 -426.285515) (xy 58.434978 -426.214641)
			(xy 57.818282 -426.214641) (xy 57.810296 -426.285515) (xy 57.794426 -426.35505) (xy 57.770869 -426.42237)
			(xy 57.739924 -426.486629) (xy 57.701978 -426.54702) (xy 57.657509 -426.602782) (xy 57.607076 -426.653215)
			(xy 57.551314 -426.697684) (xy 57.490923 -426.73563) (xy 57.426664 -426.766575) (xy 57.359344 -426.790132)
			(xy 57.289809 -426.806002) (xy 57.218935 -426.813988) (xy 57.147613 -426.813988) (xy 57.076739 -426.806002)
			(xy 57.007204 -426.790132) (xy 56.939884 -426.766575) (xy 56.875625 -426.73563) (xy 56.815234 -426.697684)
			(xy 56.759472 -426.653215) (xy 56.709039 -426.602782) (xy 56.66457 -426.54702) (xy 56.626624 -426.486629)
			(xy 56.595679 -426.42237) (xy 56.572122 -426.35505) (xy 56.556252 -426.285515) (xy 56.548266 -426.214641)
			(xy 29.254196 -426.214641) (xy 29.254196 -427.889771) (xy 56.548266 -427.889771) (xy 56.548266 -427.818449)
			(xy 56.556252 -427.747575) (xy 56.572122 -427.67804) (xy 56.595679 -427.61072) (xy 56.626624 -427.546461)
			(xy 56.66457 -427.48607) (xy 56.709039 -427.430308) (xy 56.759472 -427.379875) (xy 56.815234 -427.335406)
			(xy 56.875625 -427.29746) (xy 56.939884 -427.266515) (xy 57.007204 -427.242958) (xy 57.076739 -427.227088)
			(xy 57.147613 -427.219102) (xy 57.218935 -427.219102) (xy 57.289809 -427.227088) (xy 57.359344 -427.242958)
			(xy 57.426664 -427.266515) (xy 57.490923 -427.29746) (xy 57.551314 -427.335406) (xy 57.607076 -427.379875)
			(xy 57.657509 -427.430308) (xy 57.701978 -427.48607) (xy 57.739924 -427.546461) (xy 57.770869 -427.61072)
			(xy 57.794426 -427.67804) (xy 57.810296 -427.747575) (xy 57.818282 -427.818449) (xy 57.818782 -427.85411)
			(xy 57.818282 -427.889771) (xy 58.434978 -427.889771) (xy 58.434978 -427.818449) (xy 58.442964 -427.747575)
			(xy 58.458834 -427.67804) (xy 58.482391 -427.61072) (xy 58.513336 -427.546461) (xy 58.551282 -427.48607)
			(xy 58.595751 -427.430308) (xy 58.646184 -427.379875) (xy 58.701946 -427.335406) (xy 58.762337 -427.29746)
			(xy 58.826596 -427.266515) (xy 58.893916 -427.242958) (xy 58.963451 -427.227088) (xy 59.034325 -427.219102)
			(xy 59.105647 -427.219102) (xy 59.176521 -427.227088) (xy 59.246056 -427.242958) (xy 59.313376 -427.266515)
			(xy 59.377635 -427.29746) (xy 59.438026 -427.335406) (xy 59.493788 -427.379875) (xy 59.544221 -427.430308)
			(xy 59.58869 -427.48607) (xy 59.626636 -427.546461) (xy 59.657581 -427.61072) (xy 59.681138 -427.67804)
			(xy 59.697008 -427.747575) (xy 59.704994 -427.818449) (xy 59.705494 -427.85411) (xy 59.704994 -427.889771)
			(xy 60.67602 -427.889771) (xy 60.67602 -427.818449) (xy 60.684006 -427.747575) (xy 60.699876 -427.67804)
			(xy 60.723433 -427.61072) (xy 60.754378 -427.546461) (xy 60.792324 -427.48607) (xy 60.836793 -427.430308)
			(xy 60.887226 -427.379875) (xy 60.942988 -427.335406) (xy 61.003379 -427.29746) (xy 61.067638 -427.266515)
			(xy 61.134958 -427.242958) (xy 61.204493 -427.227088) (xy 61.275367 -427.219102) (xy 61.346689 -427.219102)
			(xy 61.417563 -427.227088) (xy 61.487098 -427.242958) (xy 61.554418 -427.266515) (xy 61.618677 -427.29746)
			(xy 61.679068 -427.335406) (xy 61.73483 -427.379875) (xy 61.785263 -427.430308) (xy 61.829732 -427.48607)
			(xy 61.867678 -427.546461) (xy 61.898623 -427.61072) (xy 61.92218 -427.67804) (xy 61.93805 -427.747575)
			(xy 61.946036 -427.818449) (xy 61.946536 -427.85411) (xy 61.946036 -427.889771) (xy 62.580004 -427.889771)
			(xy 62.580004 -427.818449) (xy 62.58799 -427.747575) (xy 62.60386 -427.67804) (xy 62.627417 -427.61072)
			(xy 62.658362 -427.546461) (xy 62.696308 -427.48607) (xy 62.740777 -427.430308) (xy 62.79121 -427.379875)
			(xy 62.846972 -427.335406) (xy 62.907363 -427.29746) (xy 62.971622 -427.266515) (xy 63.038942 -427.242958)
			(xy 63.108477 -427.227088) (xy 63.179351 -427.219102) (xy 63.250673 -427.219102) (xy 63.321547 -427.227088)
			(xy 63.391082 -427.242958) (xy 63.458402 -427.266515) (xy 63.522661 -427.29746) (xy 63.583052 -427.335406)
			(xy 63.638814 -427.379875) (xy 63.689247 -427.430308) (xy 63.733716 -427.48607) (xy 63.771662 -427.546461)
			(xy 63.802607 -427.61072) (xy 63.826164 -427.67804) (xy 63.842034 -427.747575) (xy 63.85002 -427.818449)
			(xy 63.85052 -427.85411) (xy 63.85002 -427.889771) (xy 63.842034 -427.960645) (xy 63.826164 -428.03018)
			(xy 63.802607 -428.0975) (xy 63.771662 -428.161759) (xy 63.733716 -428.22215) (xy 63.689247 -428.277912)
			(xy 63.638814 -428.328345) (xy 63.583052 -428.372814) (xy 63.522661 -428.41076) (xy 63.458402 -428.441705)
			(xy 63.391082 -428.465262) (xy 63.321547 -428.481132) (xy 63.250673 -428.489118) (xy 63.179351 -428.489118)
			(xy 63.108477 -428.481132) (xy 63.038942 -428.465262) (xy 62.971622 -428.441705) (xy 62.907363 -428.41076)
			(xy 62.846972 -428.372814) (xy 62.79121 -428.328345) (xy 62.740777 -428.277912) (xy 62.696308 -428.22215)
			(xy 62.658362 -428.161759) (xy 62.627417 -428.0975) (xy 62.60386 -428.03018) (xy 62.58799 -427.960645)
			(xy 62.580004 -427.889771) (xy 61.946036 -427.889771) (xy 61.93805 -427.960645) (xy 61.92218 -428.03018)
			(xy 61.898623 -428.0975) (xy 61.867678 -428.161759) (xy 61.829732 -428.22215) (xy 61.785263 -428.277912)
			(xy 61.73483 -428.328345) (xy 61.679068 -428.372814) (xy 61.618677 -428.41076) (xy 61.554418 -428.441705)
			(xy 61.487098 -428.465262) (xy 61.417563 -428.481132) (xy 61.346689 -428.489118) (xy 61.275367 -428.489118)
			(xy 61.204493 -428.481132) (xy 61.134958 -428.465262) (xy 61.067638 -428.441705) (xy 61.003379 -428.41076)
			(xy 60.942988 -428.372814) (xy 60.887226 -428.328345) (xy 60.836793 -428.277912) (xy 60.792324 -428.22215)
			(xy 60.754378 -428.161759) (xy 60.723433 -428.0975) (xy 60.699876 -428.03018) (xy 60.684006 -427.960645)
			(xy 60.67602 -427.889771) (xy 59.704994 -427.889771) (xy 59.697008 -427.960645) (xy 59.681138 -428.03018)
			(xy 59.657581 -428.0975) (xy 59.626636 -428.161759) (xy 59.58869 -428.22215) (xy 59.544221 -428.277912)
			(xy 59.493788 -428.328345) (xy 59.438026 -428.372814) (xy 59.377635 -428.41076) (xy 59.313376 -428.441705)
			(xy 59.246056 -428.465262) (xy 59.176521 -428.481132) (xy 59.105647 -428.489118) (xy 59.034325 -428.489118)
			(xy 58.963451 -428.481132) (xy 58.893916 -428.465262) (xy 58.826596 -428.441705) (xy 58.762337 -428.41076)
			(xy 58.701946 -428.372814) (xy 58.646184 -428.328345) (xy 58.595751 -428.277912) (xy 58.551282 -428.22215)
			(xy 58.513336 -428.161759) (xy 58.482391 -428.0975) (xy 58.458834 -428.03018) (xy 58.442964 -427.960645)
			(xy 58.434978 -427.889771) (xy 57.818282 -427.889771) (xy 57.810296 -427.960645) (xy 57.794426 -428.03018)
			(xy 57.770869 -428.0975) (xy 57.739924 -428.161759) (xy 57.701978 -428.22215) (xy 57.657509 -428.277912)
			(xy 57.607076 -428.328345) (xy 57.551314 -428.372814) (xy 57.490923 -428.41076) (xy 57.426664 -428.441705)
			(xy 57.359344 -428.465262) (xy 57.289809 -428.481132) (xy 57.218935 -428.489118) (xy 57.147613 -428.489118)
			(xy 57.076739 -428.481132) (xy 57.007204 -428.465262) (xy 56.939884 -428.441705) (xy 56.875625 -428.41076)
			(xy 56.815234 -428.372814) (xy 56.759472 -428.328345) (xy 56.709039 -428.277912) (xy 56.66457 -428.22215)
			(xy 56.626624 -428.161759) (xy 56.595679 -428.0975) (xy 56.572122 -428.03018) (xy 56.556252 -427.960645)
			(xy 56.548266 -427.889771) (xy 29.254196 -427.889771) (xy 29.254196 -429.900943) (xy 56.504832 -429.900943)
			(xy 56.504832 -429.829621) (xy 56.512818 -429.758747) (xy 56.528688 -429.689212) (xy 56.552245 -429.621892)
			(xy 56.58319 -429.557633) (xy 56.621136 -429.497242) (xy 56.665605 -429.44148) (xy 56.716038 -429.391047)
			(xy 56.7718 -429.346578) (xy 56.832191 -429.308632) (xy 56.89645 -429.277687) (xy 56.96377 -429.25413)
			(xy 57.033305 -429.23826) (xy 57.104179 -429.230274) (xy 57.175501 -429.230274) (xy 57.246375 -429.23826)
			(xy 57.31591 -429.25413) (xy 57.38323 -429.277687) (xy 57.447489 -429.308632) (xy 57.50788 -429.346578)
			(xy 57.563642 -429.391047) (xy 57.614075 -429.44148) (xy 57.658544 -429.497242) (xy 57.69649 -429.557633)
			(xy 57.727435 -429.621892) (xy 57.750992 -429.689212) (xy 57.766862 -429.758747) (xy 57.774848 -429.829621)
			(xy 57.775348 -429.865282) (xy 57.774848 -429.900943) (xy 58.391544 -429.900943) (xy 58.391544 -429.829621)
			(xy 58.39953 -429.758747) (xy 58.4154 -429.689212) (xy 58.438957 -429.621892) (xy 58.469902 -429.557633)
			(xy 58.507848 -429.497242) (xy 58.552317 -429.44148) (xy 58.60275 -429.391047) (xy 58.658512 -429.346578)
			(xy 58.718903 -429.308632) (xy 58.783162 -429.277687) (xy 58.850482 -429.25413) (xy 58.920017 -429.23826)
			(xy 58.990891 -429.230274) (xy 59.062213 -429.230274) (xy 59.133087 -429.23826) (xy 59.202622 -429.25413)
			(xy 59.269942 -429.277687) (xy 59.334201 -429.308632) (xy 59.394592 -429.346578) (xy 59.450354 -429.391047)
			(xy 59.500787 -429.44148) (xy 59.545256 -429.497242) (xy 59.583202 -429.557633) (xy 59.614147 -429.621892)
			(xy 59.637704 -429.689212) (xy 59.653574 -429.758747) (xy 59.66156 -429.829621) (xy 59.66206 -429.865282)
			(xy 59.66156 -429.900943) (xy 60.632586 -429.900943) (xy 60.632586 -429.829621) (xy 60.640572 -429.758747)
			(xy 60.656442 -429.689212) (xy 60.679999 -429.621892) (xy 60.710944 -429.557633) (xy 60.74889 -429.497242)
			(xy 60.793359 -429.44148) (xy 60.843792 -429.391047) (xy 60.899554 -429.346578) (xy 60.959945 -429.308632)
			(xy 61.024204 -429.277687) (xy 61.091524 -429.25413) (xy 61.161059 -429.23826) (xy 61.231933 -429.230274)
			(xy 61.303255 -429.230274) (xy 61.374129 -429.23826) (xy 61.443664 -429.25413) (xy 61.510984 -429.277687)
			(xy 61.575243 -429.308632) (xy 61.635634 -429.346578) (xy 61.691396 -429.391047) (xy 61.741829 -429.44148)
			(xy 61.786298 -429.497242) (xy 61.824244 -429.557633) (xy 61.855189 -429.621892) (xy 61.878746 -429.689212)
			(xy 61.894616 -429.758747) (xy 61.902602 -429.829621) (xy 61.903102 -429.865282) (xy 61.902602 -429.900943)
			(xy 62.53657 -429.900943) (xy 62.53657 -429.829621) (xy 62.544556 -429.758747) (xy 62.560426 -429.689212)
			(xy 62.583983 -429.621892) (xy 62.614928 -429.557633) (xy 62.652874 -429.497242) (xy 62.697343 -429.44148)
			(xy 62.747776 -429.391047) (xy 62.803538 -429.346578) (xy 62.863929 -429.308632) (xy 62.928188 -429.277687)
			(xy 62.995508 -429.25413) (xy 63.065043 -429.23826) (xy 63.135917 -429.230274) (xy 63.207239 -429.230274)
			(xy 63.278113 -429.23826) (xy 63.347648 -429.25413) (xy 63.414968 -429.277687) (xy 63.479227 -429.308632)
			(xy 63.539618 -429.346578) (xy 63.59538 -429.391047) (xy 63.645813 -429.44148) (xy 63.690282 -429.497242)
			(xy 63.728228 -429.557633) (xy 63.759173 -429.621892) (xy 63.78273 -429.689212) (xy 63.7986 -429.758747)
			(xy 63.806586 -429.829621) (xy 63.807086 -429.865282) (xy 63.806586 -429.900943) (xy 63.7986 -429.971817)
			(xy 63.78273 -430.041352) (xy 63.759173 -430.108672) (xy 63.739385 -430.149762) (xy 72.868035 -430.149762)
			(xy 72.872042 -429.947012) (xy 72.884055 -429.744578) (xy 72.904056 -429.542777) (xy 72.932015 -429.341923)
			(xy 72.967886 -429.142331) (xy 73.011615 -428.944312) (xy 73.063133 -428.748175) (xy 73.122359 -428.554227)
			(xy 73.189201 -428.362769) (xy 73.263555 -428.174102) (xy 73.345304 -427.98852) (xy 73.434322 -427.806312)
			(xy 73.530468 -427.627763) (xy 73.633593 -427.453152) (xy 73.743536 -427.282752) (xy 73.860125 -427.116828)
			(xy 73.983178 -426.955639) (xy 74.112503 -426.799438) (xy 74.247898 -426.648468) (xy 74.389151 -426.502964)
			(xy 74.536043 -426.363155) (xy 74.688343 -426.229258) (xy 74.845814 -426.101483) (xy 75.008211 -425.980028)
			(xy 75.175278 -425.865084) (xy 75.346757 -425.75683) (xy 75.522378 -425.655435) (xy 75.701868 -425.561057)
			(xy 75.884946 -425.473845) (xy 76.071327 -425.393933) (xy 76.26072 -425.321446) (xy 76.452828 -425.256499)
			(xy 76.647352 -425.199191) (xy 76.843988 -425.149614) (xy 77.04243 -425.107843) (xy 77.242367 -425.073945)
			(xy 77.443486 -425.047973) (xy 77.645475 -425.029966) (xy 77.848018 -425.019953) (xy 78.050798 -425.017949)
			(xy 78.253499 -425.023959) (xy 78.455804 -425.037971) (xy 78.657398 -425.059966) (xy 78.857965 -425.089907)
			(xy 79.057193 -425.127748) (xy 79.254771 -425.173431) (xy 79.450389 -425.226884) (xy 79.643743 -425.288023)
			(xy 79.834531 -425.356754) (xy 80.022454 -425.432968) (xy 80.20722 -425.516547) (xy 80.388539 -425.60736)
			(xy 80.56613 -425.705265) (xy 80.739713 -425.81011) (xy 80.909019 -425.921731) (xy 81.073784 -426.039953)
			(xy 81.233749 -426.164593) (xy 81.388665 -426.295454) (xy 81.53829 -426.432334) (xy 81.68239 -426.575018)
			(xy 81.820742 -426.723284) (xy 81.953127 -426.8769) (xy 82.079341 -427.035625) (xy 82.199185 -427.199214)
			(xy 82.312473 -427.367409) (xy 82.419028 -427.539948) (xy 82.518683 -427.716563) (xy 82.611283 -427.896976)
			(xy 82.696683 -428.080907) (xy 82.77475 -428.268068) (xy 82.845362 -428.458168) (xy 82.908408 -428.650908)
			(xy 82.963791 -428.845989) (xy 83.011423 -429.043106) (xy 83.051231 -429.24195) (xy 83.083153 -429.442212)
			(xy 83.107137 -429.643578) (xy 83.123148 -429.845735) (xy 83.131159 -430.048367) (xy 83.13166 -430.149762)
			(xy 83.131159 -430.251157) (xy 83.123148 -430.453789) (xy 83.107137 -430.655946) (xy 83.083153 -430.857312)
			(xy 83.051231 -431.057574) (xy 83.011423 -431.256418) (xy 82.963791 -431.453535) (xy 82.908408 -431.648616)
			(xy 82.845362 -431.841356) (xy 82.77475 -432.031456) (xy 82.696683 -432.218617) (xy 82.611283 -432.402548)
			(xy 82.518683 -432.582961) (xy 82.419028 -432.759576) (xy 82.312473 -432.932115) (xy 82.199185 -433.10031)
			(xy 82.079341 -433.263899) (xy 81.953127 -433.422624) (xy 81.820742 -433.57624) (xy 81.68239 -433.724506)
			(xy 81.53829 -433.86719) (xy 81.388665 -434.00407) (xy 81.233749 -434.134931) (xy 81.073784 -434.259571)
			(xy 80.909019 -434.377793) (xy 80.739713 -434.489414) (xy 80.56613 -434.594259) (xy 80.388539 -434.692164)
			(xy 80.20722 -434.782977) (xy 80.022454 -434.866556) (xy 79.834531 -434.94277) (xy 79.643743 -435.011501)
			(xy 79.450389 -435.07264) (xy 79.254771 -435.126093) (xy 79.057193 -435.171776) (xy 78.857965 -435.209617)
			(xy 78.657398 -435.239558) (xy 78.455804 -435.261553) (xy 78.253499 -435.275565) (xy 78.050798 -435.281575)
			(xy 77.848018 -435.279571) (xy 77.645475 -435.269558) (xy 77.443486 -435.251551) (xy 77.242367 -435.225579)
			(xy 77.04243 -435.191681) (xy 76.843988 -435.14991) (xy 76.647352 -435.100333) (xy 76.452828 -435.043025)
			(xy 76.26072 -434.978078) (xy 76.071327 -434.905591) (xy 75.884946 -434.825679) (xy 75.701868 -434.738467)
			(xy 75.522378 -434.644089) (xy 75.346757 -434.542694) (xy 75.175278 -434.43444) (xy 75.008211 -434.319496)
			(xy 74.845814 -434.198041) (xy 74.688343 -434.070266) (xy 74.536043 -433.936369) (xy 74.389151 -433.79656)
			(xy 74.247898 -433.651056) (xy 74.112503 -433.500086) (xy 73.983178 -433.343885) (xy 73.860125 -433.182696)
			(xy 73.743536 -433.016772) (xy 73.633593 -432.846372) (xy 73.530468 -432.671761) (xy 73.434322 -432.493212)
			(xy 73.345304 -432.311004) (xy 73.263555 -432.125422) (xy 73.189201 -431.936755) (xy 73.122359 -431.745297)
			(xy 73.063133 -431.551349) (xy 73.011615 -431.355212) (xy 72.967886 -431.157193) (xy 72.932015 -430.957601)
			(xy 72.904056 -430.756747) (xy 72.884055 -430.554946) (xy 72.872042 -430.352512) (xy 72.868035 -430.149762)
			(xy 63.739385 -430.149762) (xy 63.728228 -430.172931) (xy 63.690282 -430.233322) (xy 63.645813 -430.289084)
			(xy 63.59538 -430.339517) (xy 63.539618 -430.383986) (xy 63.479227 -430.421932) (xy 63.414968 -430.452877)
			(xy 63.347648 -430.476434) (xy 63.278113 -430.492304) (xy 63.207239 -430.50029) (xy 63.135917 -430.50029)
			(xy 63.065043 -430.492304) (xy 62.995508 -430.476434) (xy 62.928188 -430.452877) (xy 62.863929 -430.421932)
			(xy 62.803538 -430.383986) (xy 62.747776 -430.339517) (xy 62.697343 -430.289084) (xy 62.652874 -430.233322)
			(xy 62.614928 -430.172931) (xy 62.583983 -430.108672) (xy 62.560426 -430.041352) (xy 62.544556 -429.971817)
			(xy 62.53657 -429.900943) (xy 61.902602 -429.900943) (xy 61.894616 -429.971817) (xy 61.878746 -430.041352)
			(xy 61.855189 -430.108672) (xy 61.824244 -430.172931) (xy 61.786298 -430.233322) (xy 61.741829 -430.289084)
			(xy 61.691396 -430.339517) (xy 61.635634 -430.383986) (xy 61.575243 -430.421932) (xy 61.510984 -430.452877)
			(xy 61.443664 -430.476434) (xy 61.374129 -430.492304) (xy 61.303255 -430.50029) (xy 61.231933 -430.50029)
			(xy 61.161059 -430.492304) (xy 61.091524 -430.476434) (xy 61.024204 -430.452877) (xy 60.959945 -430.421932)
			(xy 60.899554 -430.383986) (xy 60.843792 -430.339517) (xy 60.793359 -430.289084) (xy 60.74889 -430.233322)
			(xy 60.710944 -430.172931) (xy 60.679999 -430.108672) (xy 60.656442 -430.041352) (xy 60.640572 -429.971817)
			(xy 60.632586 -429.900943) (xy 59.66156 -429.900943) (xy 59.653574 -429.971817) (xy 59.637704 -430.041352)
			(xy 59.614147 -430.108672) (xy 59.583202 -430.172931) (xy 59.545256 -430.233322) (xy 59.500787 -430.289084)
			(xy 59.450354 -430.339517) (xy 59.394592 -430.383986) (xy 59.334201 -430.421932) (xy 59.269942 -430.452877)
			(xy 59.202622 -430.476434) (xy 59.133087 -430.492304) (xy 59.062213 -430.50029) (xy 58.990891 -430.50029)
			(xy 58.920017 -430.492304) (xy 58.850482 -430.476434) (xy 58.783162 -430.452877) (xy 58.718903 -430.421932)
			(xy 58.658512 -430.383986) (xy 58.60275 -430.339517) (xy 58.552317 -430.289084) (xy 58.507848 -430.233322)
			(xy 58.469902 -430.172931) (xy 58.438957 -430.108672) (xy 58.4154 -430.041352) (xy 58.39953 -429.971817)
			(xy 58.391544 -429.900943) (xy 57.774848 -429.900943) (xy 57.766862 -429.971817) (xy 57.750992 -430.041352)
			(xy 57.727435 -430.108672) (xy 57.69649 -430.172931) (xy 57.658544 -430.233322) (xy 57.614075 -430.289084)
			(xy 57.563642 -430.339517) (xy 57.50788 -430.383986) (xy 57.447489 -430.421932) (xy 57.38323 -430.452877)
			(xy 57.31591 -430.476434) (xy 57.246375 -430.492304) (xy 57.175501 -430.50029) (xy 57.104179 -430.50029)
			(xy 57.033305 -430.492304) (xy 56.96377 -430.476434) (xy 56.89645 -430.452877) (xy 56.832191 -430.421932)
			(xy 56.7718 -430.383986) (xy 56.716038 -430.339517) (xy 56.665605 -430.289084) (xy 56.621136 -430.233322)
			(xy 56.58319 -430.172931) (xy 56.552245 -430.108672) (xy 56.528688 -430.041352) (xy 56.512818 -429.971817)
			(xy 56.504832 -429.900943) (xy 29.254196 -429.900943) (xy 29.254196 -431.791465) (xy 56.504832 -431.791465)
			(xy 56.504832 -431.720143) (xy 56.512818 -431.649269) (xy 56.528688 -431.579734) (xy 56.552245 -431.512414)
			(xy 56.58319 -431.448155) (xy 56.621136 -431.387764) (xy 56.665605 -431.332002) (xy 56.716038 -431.281569)
			(xy 56.7718 -431.2371) (xy 56.832191 -431.199154) (xy 56.89645 -431.168209) (xy 56.96377 -431.144652)
			(xy 57.033305 -431.128782) (xy 57.104179 -431.120796) (xy 57.175501 -431.120796) (xy 57.246375 -431.128782)
			(xy 57.31591 -431.144652) (xy 57.38323 -431.168209) (xy 57.447489 -431.199154) (xy 57.50788 -431.2371)
			(xy 57.563642 -431.281569) (xy 57.614075 -431.332002) (xy 57.658544 -431.387764) (xy 57.69649 -431.448155)
			(xy 57.727435 -431.512414) (xy 57.750992 -431.579734) (xy 57.766862 -431.649269) (xy 57.774848 -431.720143)
			(xy 57.775348 -431.755804) (xy 57.774848 -431.791465) (xy 58.391544 -431.791465) (xy 58.391544 -431.720143)
			(xy 58.39953 -431.649269) (xy 58.4154 -431.579734) (xy 58.438957 -431.512414) (xy 58.469902 -431.448155)
			(xy 58.507848 -431.387764) (xy 58.552317 -431.332002) (xy 58.60275 -431.281569) (xy 58.658512 -431.2371)
			(xy 58.718903 -431.199154) (xy 58.783162 -431.168209) (xy 58.850482 -431.144652) (xy 58.920017 -431.128782)
			(xy 58.990891 -431.120796) (xy 59.062213 -431.120796) (xy 59.133087 -431.128782) (xy 59.202622 -431.144652)
			(xy 59.269942 -431.168209) (xy 59.334201 -431.199154) (xy 59.394592 -431.2371) (xy 59.450354 -431.281569)
			(xy 59.500787 -431.332002) (xy 59.545256 -431.387764) (xy 59.583202 -431.448155) (xy 59.614147 -431.512414)
			(xy 59.637704 -431.579734) (xy 59.653574 -431.649269) (xy 59.66156 -431.720143) (xy 59.66206 -431.755804)
			(xy 59.66156 -431.791465) (xy 60.632586 -431.791465) (xy 60.632586 -431.720143) (xy 60.640572 -431.649269)
			(xy 60.656442 -431.579734) (xy 60.679999 -431.512414) (xy 60.710944 -431.448155) (xy 60.74889 -431.387764)
			(xy 60.793359 -431.332002) (xy 60.843792 -431.281569) (xy 60.899554 -431.2371) (xy 60.959945 -431.199154)
			(xy 61.024204 -431.168209) (xy 61.091524 -431.144652) (xy 61.161059 -431.128782) (xy 61.231933 -431.120796)
			(xy 61.303255 -431.120796) (xy 61.374129 -431.128782) (xy 61.443664 -431.144652) (xy 61.510984 -431.168209)
			(xy 61.575243 -431.199154) (xy 61.635634 -431.2371) (xy 61.691396 -431.281569) (xy 61.741829 -431.332002)
			(xy 61.786298 -431.387764) (xy 61.824244 -431.448155) (xy 61.855189 -431.512414) (xy 61.878746 -431.579734)
			(xy 61.894616 -431.649269) (xy 61.902602 -431.720143) (xy 61.903102 -431.755804) (xy 61.902602 -431.791465)
			(xy 62.53657 -431.791465) (xy 62.53657 -431.720143) (xy 62.544556 -431.649269) (xy 62.560426 -431.579734)
			(xy 62.583983 -431.512414) (xy 62.614928 -431.448155) (xy 62.652874 -431.387764) (xy 62.697343 -431.332002)
			(xy 62.747776 -431.281569) (xy 62.803538 -431.2371) (xy 62.863929 -431.199154) (xy 62.928188 -431.168209)
			(xy 62.995508 -431.144652) (xy 63.065043 -431.128782) (xy 63.135917 -431.120796) (xy 63.207239 -431.120796)
			(xy 63.278113 -431.128782) (xy 63.347648 -431.144652) (xy 63.414968 -431.168209) (xy 63.479227 -431.199154)
			(xy 63.539618 -431.2371) (xy 63.59538 -431.281569) (xy 63.645813 -431.332002) (xy 63.690282 -431.387764)
			(xy 63.728228 -431.448155) (xy 63.759173 -431.512414) (xy 63.78273 -431.579734) (xy 63.7986 -431.649269)
			(xy 63.806586 -431.720143) (xy 63.807086 -431.755804) (xy 63.806586 -431.791465) (xy 63.7986 -431.862339)
			(xy 63.78273 -431.931874) (xy 63.759173 -431.999194) (xy 63.728228 -432.063453) (xy 63.690282 -432.123844)
			(xy 63.645813 -432.179606) (xy 63.59538 -432.230039) (xy 63.539618 -432.274508) (xy 63.479227 -432.312454)
			(xy 63.414968 -432.343399) (xy 63.347648 -432.366956) (xy 63.278113 -432.382826) (xy 63.207239 -432.390812)
			(xy 63.135917 -432.390812) (xy 63.065043 -432.382826) (xy 62.995508 -432.366956) (xy 62.928188 -432.343399)
			(xy 62.863929 -432.312454) (xy 62.803538 -432.274508) (xy 62.747776 -432.230039) (xy 62.697343 -432.179606)
			(xy 62.652874 -432.123844) (xy 62.614928 -432.063453) (xy 62.583983 -431.999194) (xy 62.560426 -431.931874)
			(xy 62.544556 -431.862339) (xy 62.53657 -431.791465) (xy 61.902602 -431.791465) (xy 61.894616 -431.862339)
			(xy 61.878746 -431.931874) (xy 61.855189 -431.999194) (xy 61.824244 -432.063453) (xy 61.786298 -432.123844)
			(xy 61.741829 -432.179606) (xy 61.691396 -432.230039) (xy 61.635634 -432.274508) (xy 61.575243 -432.312454)
			(xy 61.510984 -432.343399) (xy 61.443664 -432.366956) (xy 61.374129 -432.382826) (xy 61.303255 -432.390812)
			(xy 61.231933 -432.390812) (xy 61.161059 -432.382826) (xy 61.091524 -432.366956) (xy 61.024204 -432.343399)
			(xy 60.959945 -432.312454) (xy 60.899554 -432.274508) (xy 60.843792 -432.230039) (xy 60.793359 -432.179606)
			(xy 60.74889 -432.123844) (xy 60.710944 -432.063453) (xy 60.679999 -431.999194) (xy 60.656442 -431.931874)
			(xy 60.640572 -431.862339) (xy 60.632586 -431.791465) (xy 59.66156 -431.791465) (xy 59.653574 -431.862339)
			(xy 59.637704 -431.931874) (xy 59.614147 -431.999194) (xy 59.583202 -432.063453) (xy 59.545256 -432.123844)
			(xy 59.500787 -432.179606) (xy 59.450354 -432.230039) (xy 59.394592 -432.274508) (xy 59.334201 -432.312454)
			(xy 59.269942 -432.343399) (xy 59.202622 -432.366956) (xy 59.133087 -432.382826) (xy 59.062213 -432.390812)
			(xy 58.990891 -432.390812) (xy 58.920017 -432.382826) (xy 58.850482 -432.366956) (xy 58.783162 -432.343399)
			(xy 58.718903 -432.312454) (xy 58.658512 -432.274508) (xy 58.60275 -432.230039) (xy 58.552317 -432.179606)
			(xy 58.507848 -432.123844) (xy 58.469902 -432.063453) (xy 58.438957 -431.999194) (xy 58.4154 -431.931874)
			(xy 58.39953 -431.862339) (xy 58.391544 -431.791465) (xy 57.774848 -431.791465) (xy 57.766862 -431.862339)
			(xy 57.750992 -431.931874) (xy 57.727435 -431.999194) (xy 57.69649 -432.063453) (xy 57.658544 -432.123844)
			(xy 57.614075 -432.179606) (xy 57.563642 -432.230039) (xy 57.50788 -432.274508) (xy 57.447489 -432.312454)
			(xy 57.38323 -432.343399) (xy 57.31591 -432.366956) (xy 57.246375 -432.382826) (xy 57.175501 -432.390812)
			(xy 57.104179 -432.390812) (xy 57.033305 -432.382826) (xy 56.96377 -432.366956) (xy 56.89645 -432.343399)
			(xy 56.832191 -432.312454) (xy 56.7718 -432.274508) (xy 56.716038 -432.230039) (xy 56.665605 -432.179606)
			(xy 56.621136 -432.123844) (xy 56.58319 -432.063453) (xy 56.552245 -431.999194) (xy 56.528688 -431.931874)
			(xy 56.512818 -431.862339) (xy 56.504832 -431.791465) (xy 29.254196 -431.791465) (xy 29.254196 -433.832609)
			(xy 56.504832 -433.832609) (xy 56.504832 -433.761287) (xy 56.512818 -433.690413) (xy 56.528688 -433.620878)
			(xy 56.552245 -433.553558) (xy 56.58319 -433.489299) (xy 56.621136 -433.428908) (xy 56.665605 -433.373146)
			(xy 56.716038 -433.322713) (xy 56.7718 -433.278244) (xy 56.832191 -433.240298) (xy 56.89645 -433.209353)
			(xy 56.96377 -433.185796) (xy 57.033305 -433.169926) (xy 57.104179 -433.16194) (xy 57.175501 -433.16194)
			(xy 57.246375 -433.169926) (xy 57.31591 -433.185796) (xy 57.38323 -433.209353) (xy 57.447489 -433.240298)
			(xy 57.50788 -433.278244) (xy 57.563642 -433.322713) (xy 57.614075 -433.373146) (xy 57.658544 -433.428908)
			(xy 57.69649 -433.489299) (xy 57.727435 -433.553558) (xy 57.750992 -433.620878) (xy 57.766862 -433.690413)
			(xy 57.774848 -433.761287) (xy 57.775348 -433.796948) (xy 57.774848 -433.832609) (xy 58.391544 -433.832609)
			(xy 58.391544 -433.761287) (xy 58.39953 -433.690413) (xy 58.4154 -433.620878) (xy 58.438957 -433.553558)
			(xy 58.469902 -433.489299) (xy 58.507848 -433.428908) (xy 58.552317 -433.373146) (xy 58.60275 -433.322713)
			(xy 58.658512 -433.278244) (xy 58.718903 -433.240298) (xy 58.783162 -433.209353) (xy 58.850482 -433.185796)
			(xy 58.920017 -433.169926) (xy 58.990891 -433.16194) (xy 59.062213 -433.16194) (xy 59.133087 -433.169926)
			(xy 59.202622 -433.185796) (xy 59.269942 -433.209353) (xy 59.334201 -433.240298) (xy 59.394592 -433.278244)
			(xy 59.450354 -433.322713) (xy 59.500787 -433.373146) (xy 59.545256 -433.428908) (xy 59.583202 -433.489299)
			(xy 59.614147 -433.553558) (xy 59.637704 -433.620878) (xy 59.653574 -433.690413) (xy 59.66156 -433.761287)
			(xy 59.66206 -433.796948) (xy 59.66156 -433.832609) (xy 60.632586 -433.832609) (xy 60.632586 -433.761287)
			(xy 60.640572 -433.690413) (xy 60.656442 -433.620878) (xy 60.679999 -433.553558) (xy 60.710944 -433.489299)
			(xy 60.74889 -433.428908) (xy 60.793359 -433.373146) (xy 60.843792 -433.322713) (xy 60.899554 -433.278244)
			(xy 60.959945 -433.240298) (xy 61.024204 -433.209353) (xy 61.091524 -433.185796) (xy 61.161059 -433.169926)
			(xy 61.231933 -433.16194) (xy 61.303255 -433.16194) (xy 61.374129 -433.169926) (xy 61.443664 -433.185796)
			(xy 61.510984 -433.209353) (xy 61.575243 -433.240298) (xy 61.635634 -433.278244) (xy 61.691396 -433.322713)
			(xy 61.741829 -433.373146) (xy 61.786298 -433.428908) (xy 61.824244 -433.489299) (xy 61.855189 -433.553558)
			(xy 61.878746 -433.620878) (xy 61.894616 -433.690413) (xy 61.902602 -433.761287) (xy 61.903102 -433.796948)
			(xy 61.902602 -433.832609) (xy 62.53657 -433.832609) (xy 62.53657 -433.761287) (xy 62.544556 -433.690413)
			(xy 62.560426 -433.620878) (xy 62.583983 -433.553558) (xy 62.614928 -433.489299) (xy 62.652874 -433.428908)
			(xy 62.697343 -433.373146) (xy 62.747776 -433.322713) (xy 62.803538 -433.278244) (xy 62.863929 -433.240298)
			(xy 62.928188 -433.209353) (xy 62.995508 -433.185796) (xy 63.065043 -433.169926) (xy 63.135917 -433.16194)
			(xy 63.207239 -433.16194) (xy 63.278113 -433.169926) (xy 63.347648 -433.185796) (xy 63.414968 -433.209353)
			(xy 63.479227 -433.240298) (xy 63.539618 -433.278244) (xy 63.59538 -433.322713) (xy 63.645813 -433.373146)
			(xy 63.690282 -433.428908) (xy 63.728228 -433.489299) (xy 63.759173 -433.553558) (xy 63.78273 -433.620878)
			(xy 63.7986 -433.690413) (xy 63.806586 -433.761287) (xy 63.807086 -433.796948) (xy 63.806586 -433.832609)
			(xy 63.7986 -433.903483) (xy 63.78273 -433.973018) (xy 63.759173 -434.040338) (xy 63.728228 -434.104597)
			(xy 63.690282 -434.164988) (xy 63.645813 -434.22075) (xy 63.59538 -434.271183) (xy 63.539618 -434.315652)
			(xy 63.479227 -434.353598) (xy 63.414968 -434.384543) (xy 63.347648 -434.4081) (xy 63.278113 -434.42397)
			(xy 63.207239 -434.431956) (xy 63.135917 -434.431956) (xy 63.065043 -434.42397) (xy 62.995508 -434.4081)
			(xy 62.928188 -434.384543) (xy 62.863929 -434.353598) (xy 62.803538 -434.315652) (xy 62.747776 -434.271183)
			(xy 62.697343 -434.22075) (xy 62.652874 -434.164988) (xy 62.614928 -434.104597) (xy 62.583983 -434.040338)
			(xy 62.560426 -433.973018) (xy 62.544556 -433.903483) (xy 62.53657 -433.832609) (xy 61.902602 -433.832609)
			(xy 61.894616 -433.903483) (xy 61.878746 -433.973018) (xy 61.855189 -434.040338) (xy 61.824244 -434.104597)
			(xy 61.786298 -434.164988) (xy 61.741829 -434.22075) (xy 61.691396 -434.271183) (xy 61.635634 -434.315652)
			(xy 61.575243 -434.353598) (xy 61.510984 -434.384543) (xy 61.443664 -434.4081) (xy 61.374129 -434.42397)
			(xy 61.303255 -434.431956) (xy 61.231933 -434.431956) (xy 61.161059 -434.42397) (xy 61.091524 -434.4081)
			(xy 61.024204 -434.384543) (xy 60.959945 -434.353598) (xy 60.899554 -434.315652) (xy 60.843792 -434.271183)
			(xy 60.793359 -434.22075) (xy 60.74889 -434.164988) (xy 60.710944 -434.104597) (xy 60.679999 -434.040338)
			(xy 60.656442 -433.973018) (xy 60.640572 -433.903483) (xy 60.632586 -433.832609) (xy 59.66156 -433.832609)
			(xy 59.653574 -433.903483) (xy 59.637704 -433.973018) (xy 59.614147 -434.040338) (xy 59.583202 -434.104597)
			(xy 59.545256 -434.164988) (xy 59.500787 -434.22075) (xy 59.450354 -434.271183) (xy 59.394592 -434.315652)
			(xy 59.334201 -434.353598) (xy 59.269942 -434.384543) (xy 59.202622 -434.4081) (xy 59.133087 -434.42397)
			(xy 59.062213 -434.431956) (xy 58.990891 -434.431956) (xy 58.920017 -434.42397) (xy 58.850482 -434.4081)
			(xy 58.783162 -434.384543) (xy 58.718903 -434.353598) (xy 58.658512 -434.315652) (xy 58.60275 -434.271183)
			(xy 58.552317 -434.22075) (xy 58.507848 -434.164988) (xy 58.469902 -434.104597) (xy 58.438957 -434.040338)
			(xy 58.4154 -433.973018) (xy 58.39953 -433.903483) (xy 58.391544 -433.832609) (xy 57.774848 -433.832609)
			(xy 57.766862 -433.903483) (xy 57.750992 -433.973018) (xy 57.727435 -434.040338) (xy 57.69649 -434.104597)
			(xy 57.658544 -434.164988) (xy 57.614075 -434.22075) (xy 57.563642 -434.271183) (xy 57.50788 -434.315652)
			(xy 57.447489 -434.353598) (xy 57.38323 -434.384543) (xy 57.31591 -434.4081) (xy 57.246375 -434.42397)
			(xy 57.175501 -434.431956) (xy 57.104179 -434.431956) (xy 57.033305 -434.42397) (xy 56.96377 -434.4081)
			(xy 56.89645 -434.384543) (xy 56.832191 -434.353598) (xy 56.7718 -434.315652) (xy 56.716038 -434.271183)
			(xy 56.665605 -434.22075) (xy 56.621136 -434.164988) (xy 56.58319 -434.104597) (xy 56.552245 -434.040338)
			(xy 56.528688 -433.973018) (xy 56.512818 -433.903483) (xy 56.504832 -433.832609) (xy 29.254196 -433.832609)
			(xy 29.254196 -435.742435) (xy 56.504832 -435.742435) (xy 56.504832 -435.671113) (xy 56.512818 -435.600239)
			(xy 56.528688 -435.530704) (xy 56.552245 -435.463384) (xy 56.58319 -435.399125) (xy 56.621136 -435.338734)
			(xy 56.665605 -435.282972) (xy 56.716038 -435.232539) (xy 56.7718 -435.18807) (xy 56.832191 -435.150124)
			(xy 56.89645 -435.119179) (xy 56.96377 -435.095622) (xy 57.033305 -435.079752) (xy 57.104179 -435.071766)
			(xy 57.175501 -435.071766) (xy 57.246375 -435.079752) (xy 57.31591 -435.095622) (xy 57.38323 -435.119179)
			(xy 57.447489 -435.150124) (xy 57.50788 -435.18807) (xy 57.563642 -435.232539) (xy 57.614075 -435.282972)
			(xy 57.658544 -435.338734) (xy 57.69649 -435.399125) (xy 57.727435 -435.463384) (xy 57.750992 -435.530704)
			(xy 57.766862 -435.600239) (xy 57.774848 -435.671113) (xy 57.775348 -435.706774) (xy 57.774848 -435.742435)
			(xy 58.391544 -435.742435) (xy 58.391544 -435.671113) (xy 58.39953 -435.600239) (xy 58.4154 -435.530704)
			(xy 58.438957 -435.463384) (xy 58.469902 -435.399125) (xy 58.507848 -435.338734) (xy 58.552317 -435.282972)
			(xy 58.60275 -435.232539) (xy 58.658512 -435.18807) (xy 58.718903 -435.150124) (xy 58.783162 -435.119179)
			(xy 58.850482 -435.095622) (xy 58.920017 -435.079752) (xy 58.990891 -435.071766) (xy 59.062213 -435.071766)
			(xy 59.133087 -435.079752) (xy 59.202622 -435.095622) (xy 59.269942 -435.119179) (xy 59.334201 -435.150124)
			(xy 59.394592 -435.18807) (xy 59.450354 -435.232539) (xy 59.500787 -435.282972) (xy 59.545256 -435.338734)
			(xy 59.583202 -435.399125) (xy 59.614147 -435.463384) (xy 59.637704 -435.530704) (xy 59.653574 -435.600239)
			(xy 59.66156 -435.671113) (xy 59.66206 -435.706774) (xy 59.66156 -435.742435) (xy 60.632586 -435.742435)
			(xy 60.632586 -435.671113) (xy 60.640572 -435.600239) (xy 60.656442 -435.530704) (xy 60.679999 -435.463384)
			(xy 60.710944 -435.399125) (xy 60.74889 -435.338734) (xy 60.793359 -435.282972) (xy 60.843792 -435.232539)
			(xy 60.899554 -435.18807) (xy 60.959945 -435.150124) (xy 61.024204 -435.119179) (xy 61.091524 -435.095622)
			(xy 61.161059 -435.079752) (xy 61.231933 -435.071766) (xy 61.303255 -435.071766) (xy 61.374129 -435.079752)
			(xy 61.443664 -435.095622) (xy 61.510984 -435.119179) (xy 61.575243 -435.150124) (xy 61.635634 -435.18807)
			(xy 61.691396 -435.232539) (xy 61.741829 -435.282972) (xy 61.786298 -435.338734) (xy 61.824244 -435.399125)
			(xy 61.855189 -435.463384) (xy 61.878746 -435.530704) (xy 61.894616 -435.600239) (xy 61.902602 -435.671113)
			(xy 61.903102 -435.706774) (xy 61.902602 -435.742435) (xy 62.53657 -435.742435) (xy 62.53657 -435.671113)
			(xy 62.544556 -435.600239) (xy 62.560426 -435.530704) (xy 62.583983 -435.463384) (xy 62.614928 -435.399125)
			(xy 62.652874 -435.338734) (xy 62.697343 -435.282972) (xy 62.747776 -435.232539) (xy 62.803538 -435.18807)
			(xy 62.863929 -435.150124) (xy 62.928188 -435.119179) (xy 62.995508 -435.095622) (xy 63.065043 -435.079752)
			(xy 63.135917 -435.071766) (xy 63.207239 -435.071766) (xy 63.278113 -435.079752) (xy 63.347648 -435.095622)
			(xy 63.414968 -435.119179) (xy 63.479227 -435.150124) (xy 63.539618 -435.18807) (xy 63.59538 -435.232539)
			(xy 63.645813 -435.282972) (xy 63.690282 -435.338734) (xy 63.728228 -435.399125) (xy 63.759173 -435.463384)
			(xy 63.78273 -435.530704) (xy 63.7986 -435.600239) (xy 63.806586 -435.671113) (xy 63.807086 -435.706774)
			(xy 63.806586 -435.742435) (xy 63.7986 -435.813309) (xy 63.78273 -435.882844) (xy 63.759173 -435.950164)
			(xy 63.728228 -436.014423) (xy 63.690282 -436.074814) (xy 63.645813 -436.130576) (xy 63.59538 -436.181009)
			(xy 63.539618 -436.225478) (xy 63.479227 -436.263424) (xy 63.414968 -436.294369) (xy 63.347648 -436.317926)
			(xy 63.278113 -436.333796) (xy 63.207239 -436.341782) (xy 63.135917 -436.341782) (xy 63.065043 -436.333796)
			(xy 62.995508 -436.317926) (xy 62.928188 -436.294369) (xy 62.863929 -436.263424) (xy 62.803538 -436.225478)
			(xy 62.747776 -436.181009) (xy 62.697343 -436.130576) (xy 62.652874 -436.074814) (xy 62.614928 -436.014423)
			(xy 62.583983 -435.950164) (xy 62.560426 -435.882844) (xy 62.544556 -435.813309) (xy 62.53657 -435.742435)
			(xy 61.902602 -435.742435) (xy 61.894616 -435.813309) (xy 61.878746 -435.882844) (xy 61.855189 -435.950164)
			(xy 61.824244 -436.014423) (xy 61.786298 -436.074814) (xy 61.741829 -436.130576) (xy 61.691396 -436.181009)
			(xy 61.635634 -436.225478) (xy 61.575243 -436.263424) (xy 61.510984 -436.294369) (xy 61.443664 -436.317926)
			(xy 61.374129 -436.333796) (xy 61.303255 -436.341782) (xy 61.231933 -436.341782) (xy 61.161059 -436.333796)
			(xy 61.091524 -436.317926) (xy 61.024204 -436.294369) (xy 60.959945 -436.263424) (xy 60.899554 -436.225478)
			(xy 60.843792 -436.181009) (xy 60.793359 -436.130576) (xy 60.74889 -436.074814) (xy 60.710944 -436.014423)
			(xy 60.679999 -435.950164) (xy 60.656442 -435.882844) (xy 60.640572 -435.813309) (xy 60.632586 -435.742435)
			(xy 59.66156 -435.742435) (xy 59.653574 -435.813309) (xy 59.637704 -435.882844) (xy 59.614147 -435.950164)
			(xy 59.583202 -436.014423) (xy 59.545256 -436.074814) (xy 59.500787 -436.130576) (xy 59.450354 -436.181009)
			(xy 59.394592 -436.225478) (xy 59.334201 -436.263424) (xy 59.269942 -436.294369) (xy 59.202622 -436.317926)
			(xy 59.133087 -436.333796) (xy 59.062213 -436.341782) (xy 58.990891 -436.341782) (xy 58.920017 -436.333796)
			(xy 58.850482 -436.317926) (xy 58.783162 -436.294369) (xy 58.718903 -436.263424) (xy 58.658512 -436.225478)
			(xy 58.60275 -436.181009) (xy 58.552317 -436.130576) (xy 58.507848 -436.074814) (xy 58.469902 -436.014423)
			(xy 58.438957 -435.950164) (xy 58.4154 -435.882844) (xy 58.39953 -435.813309) (xy 58.391544 -435.742435)
			(xy 57.774848 -435.742435) (xy 57.766862 -435.813309) (xy 57.750992 -435.882844) (xy 57.727435 -435.950164)
			(xy 57.69649 -436.014423) (xy 57.658544 -436.074814) (xy 57.614075 -436.130576) (xy 57.563642 -436.181009)
			(xy 57.50788 -436.225478) (xy 57.447489 -436.263424) (xy 57.38323 -436.294369) (xy 57.31591 -436.317926)
			(xy 57.246375 -436.333796) (xy 57.175501 -436.341782) (xy 57.104179 -436.341782) (xy 57.033305 -436.333796)
			(xy 56.96377 -436.317926) (xy 56.89645 -436.294369) (xy 56.832191 -436.263424) (xy 56.7718 -436.225478)
			(xy 56.716038 -436.181009) (xy 56.665605 -436.130576) (xy 56.621136 -436.074814) (xy 56.58319 -436.014423)
			(xy 56.552245 -435.950164) (xy 56.528688 -435.882844) (xy 56.512818 -435.813309) (xy 56.504832 -435.742435)
			(xy 29.254196 -435.742435) (xy 29.254196 -436.828946) (xy 29.25473 -436.845566) (xy 29.263311 -436.877679)
			(xy 29.279904 -436.906481) (xy 29.29128 -436.918608) (xy 31.071312 -438.698386) (xy 31.295086 -438.92216)
			(xy 42.456862 -438.92216) (xy 43.338411 -439.803709) (xy 47.842668 -439.803709) (xy 47.842668 -439.722599)
			(xy 47.850618 -439.64188) (xy 47.866441 -439.562329) (xy 47.889986 -439.484713) (xy 47.921025 -439.409777)
			(xy 47.95926 -439.338245) (xy 48.004322 -439.270805) (xy 48.055777 -439.208106) (xy 48.11313 -439.150753)
			(xy 48.175829 -439.099298) (xy 48.243269 -439.054236) (xy 48.314801 -439.016001) (xy 48.389737 -438.984962)
			(xy 48.467353 -438.961417) (xy 48.546904 -438.945594) (xy 48.627623 -438.937644) (xy 48.708733 -438.937644)
			(xy 48.789452 -438.945594) (xy 48.869003 -438.961417) (xy 48.946619 -438.984962) (xy 49.021555 -439.016001)
			(xy 49.093087 -439.054236) (xy 49.160527 -439.099298) (xy 49.223226 -439.150753) (xy 49.280579 -439.208106)
			(xy 49.332034 -439.270805) (xy 49.377096 -439.338245) (xy 49.415331 -439.409777) (xy 49.44637 -439.484713)
			(xy 49.469915 -439.562329) (xy 49.485738 -439.64188) (xy 49.493688 -439.722599) (xy 49.494186 -439.763154)
			(xy 49.493688 -439.803709) (xy 49.485738 -439.884428) (xy 49.469915 -439.963979) (xy 49.44637 -440.041595)
			(xy 49.415331 -440.116531) (xy 49.377096 -440.188063) (xy 49.332034 -440.255503) (xy 49.280579 -440.318202)
			(xy 49.223226 -440.375555) (xy 49.160527 -440.42701) (xy 49.093087 -440.472072) (xy 49.021555 -440.510307)
			(xy 48.946619 -440.541346) (xy 48.869003 -440.564891) (xy 48.789452 -440.580714) (xy 48.708733 -440.588664)
			(xy 48.627623 -440.588664) (xy 48.546904 -440.580714) (xy 48.467353 -440.564891) (xy 48.389737 -440.541346)
			(xy 48.314801 -440.510307) (xy 48.243269 -440.472072) (xy 48.175829 -440.42701) (xy 48.11313 -440.375555)
			(xy 48.055777 -440.318202) (xy 48.004322 -440.255503) (xy 47.95926 -440.188063) (xy 47.921025 -440.116531)
			(xy 47.889986 -440.041595) (xy 47.866441 -439.963979) (xy 47.850618 -439.884428) (xy 47.842668 -439.803709)
			(xy 43.338411 -439.803709) (xy 44.115736 -440.581034) (xy 44.147232 -440.590178) (xy 44.173634 -440.598253)
			(xy 44.223962 -440.620954) (xy 44.270493 -440.650671) (xy 44.312255 -440.686783) (xy 44.348377 -440.728538)
			(xy 44.378105 -440.775062) (xy 44.400817 -440.825384) (xy 44.408852 -440.851798) (xy 44.417996 -440.883294)
			(xy 44.683426 -441.148724) (xy 45.036444 -441.501784) (xy 69.392798 -441.501784) (xy 69.396869 -441.446162)
			(xy 69.408995 -441.391725) (xy 69.428918 -441.339634) (xy 69.456214 -441.290999) (xy 69.4903 -441.246856)
			(xy 69.530449 -441.208147) (xy 69.575807 -441.175696) (xy 69.625407 -441.150195) (xy 69.678191 -441.132188)
			(xy 69.733034 -441.122058) (xy 69.788768 -441.120021) (xy 69.844205 -441.126121) (xy 69.898162 -441.140227)
			(xy 69.949491 -441.162039) (xy 69.997097 -441.191093) (xy 70.039965 -441.226768) (xy 70.077182 -441.268305)
			(xy 70.107955 -441.314818) (xy 70.131627 -441.365315) (xy 70.147695 -441.418722) (xy 70.155815 -441.473898)
			(xy 70.156324 -441.501784) (xy 70.155815 -441.52967) (xy 70.152368 -441.553092) (xy 70.662544 -441.553092)
			(xy 70.666615 -441.49747) (xy 70.678741 -441.443033) (xy 70.698664 -441.390942) (xy 70.72596 -441.342307)
			(xy 70.760046 -441.298164) (xy 70.800195 -441.259455) (xy 70.845553 -441.227004) (xy 70.895153 -441.201503)
			(xy 70.947937 -441.183496) (xy 71.00278 -441.173366) (xy 71.058514 -441.171329) (xy 71.113951 -441.177429)
			(xy 71.167908 -441.191535) (xy 71.219237 -441.213347) (xy 71.266843 -441.242401) (xy 71.309711 -441.278076)
			(xy 71.346928 -441.319613) (xy 71.377701 -441.366126) (xy 71.401373 -441.416623) (xy 71.417441 -441.47003)
			(xy 71.425561 -441.525206) (xy 71.42607 -441.553092) (xy 71.425759 -441.57011) (xy 71.902064 -441.57011)
			(xy 71.906135 -441.514488) (xy 71.918261 -441.460051) (xy 71.938184 -441.40796) (xy 71.96548 -441.359325)
			(xy 71.999566 -441.315182) (xy 72.039715 -441.276473) (xy 72.085073 -441.244022) (xy 72.134673 -441.218521)
			(xy 72.187457 -441.200514) (xy 72.2423 -441.190384) (xy 72.298034 -441.188347) (xy 72.353471 -441.194447)
			(xy 72.407428 -441.208553) (xy 72.458757 -441.230365) (xy 72.506363 -441.259419) (xy 72.549231 -441.295094)
			(xy 72.586448 -441.336631) (xy 72.617221 -441.383144) (xy 72.640893 -441.433641) (xy 72.656961 -441.487048)
			(xy 72.665081 -441.542224) (xy 72.66559 -441.57011) (xy 72.665081 -441.597996) (xy 72.659092 -441.63869)
			(xy 73.150728 -441.63869) (xy 73.154799 -441.583068) (xy 73.166925 -441.528631) (xy 73.186848 -441.47654)
			(xy 73.214144 -441.427905) (xy 73.24823 -441.383762) (xy 73.288379 -441.345053) (xy 73.333737 -441.312602)
			(xy 73.383337 -441.287101) (xy 73.436121 -441.269094) (xy 73.490964 -441.258964) (xy 73.546698 -441.256927)
			(xy 73.602135 -441.263027) (xy 73.656092 -441.277133) (xy 73.707421 -441.298945) (xy 73.755027 -441.327999)
			(xy 73.797895 -441.363674) (xy 73.835112 -441.405211) (xy 73.865885 -441.451724) (xy 73.889557 -441.502221)
			(xy 73.905625 -441.555628) (xy 73.913745 -441.610804) (xy 73.914254 -441.63869) (xy 73.913745 -441.666576)
			(xy 73.905625 -441.721752) (xy 73.889557 -441.775159) (xy 73.865885 -441.825656) (xy 73.835112 -441.872169)
			(xy 73.797895 -441.913706) (xy 73.755027 -441.949381) (xy 73.707421 -441.978435) (xy 73.656092 -442.000247)
			(xy 73.602135 -442.014353) (xy 73.546698 -442.020453) (xy 73.490964 -442.018416) (xy 73.436121 -442.008286)
			(xy 73.383337 -441.990279) (xy 73.333737 -441.964778) (xy 73.288379 -441.932327) (xy 73.24823 -441.893618)
			(xy 73.214144 -441.849475) (xy 73.186848 -441.80084) (xy 73.166925 -441.748749) (xy 73.154799 -441.694312)
			(xy 73.150728 -441.63869) (xy 72.659092 -441.63869) (xy 72.656961 -441.653172) (xy 72.640893 -441.706579)
			(xy 72.617221 -441.757076) (xy 72.586448 -441.803589) (xy 72.549231 -441.845126) (xy 72.506363 -441.880801)
			(xy 72.458757 -441.909855) (xy 72.407428 -441.931667) (xy 72.353471 -441.945773) (xy 72.298034 -441.951873)
			(xy 72.2423 -441.949836) (xy 72.187457 -441.939706) (xy 72.134673 -441.921699) (xy 72.085073 -441.896198)
			(xy 72.039715 -441.863747) (xy 71.999566 -441.825038) (xy 71.96548 -441.780895) (xy 71.938184 -441.73226)
			(xy 71.918261 -441.680169) (xy 71.906135 -441.625732) (xy 71.902064 -441.57011) (xy 71.425759 -441.57011)
			(xy 71.425561 -441.580978) (xy 71.417441 -441.636154) (xy 71.401373 -441.689561) (xy 71.377701 -441.740058)
			(xy 71.346928 -441.786571) (xy 71.309711 -441.828108) (xy 71.266843 -441.863783) (xy 71.219237 -441.892837)
			(xy 71.167908 -441.914649) (xy 71.113951 -441.928755) (xy 71.058514 -441.934855) (xy 71.00278 -441.932818)
			(xy 70.947937 -441.922688) (xy 70.895153 -441.904681) (xy 70.845553 -441.87918) (xy 70.800195 -441.846729)
			(xy 70.760046 -441.80802) (xy 70.72596 -441.763877) (xy 70.698664 -441.715242) (xy 70.678741 -441.663151)
			(xy 70.666615 -441.608714) (xy 70.662544 -441.553092) (xy 70.152368 -441.553092) (xy 70.147695 -441.584846)
			(xy 70.131627 -441.638253) (xy 70.107955 -441.68875) (xy 70.077182 -441.735263) (xy 70.039965 -441.7768)
			(xy 69.997097 -441.812475) (xy 69.949491 -441.841529) (xy 69.898162 -441.863341) (xy 69.844205 -441.877447)
			(xy 69.788768 -441.883547) (xy 69.733034 -441.88151) (xy 69.678191 -441.87138) (xy 69.625407 -441.853373)
			(xy 69.575807 -441.827872) (xy 69.530449 -441.795421) (xy 69.4903 -441.756712) (xy 69.456214 -441.712569)
			(xy 69.428918 -441.663934) (xy 69.408995 -441.611843) (xy 69.396869 -441.557406) (xy 69.392798 -441.501784)
			(xy 45.036444 -441.501784) (xy 46.796452 -443.262004) (xy 46.808599 -443.273357) (xy 46.837394 -443.289954)
			(xy 46.869497 -443.298555) (xy 46.886114 -443.299088) (xy 87.373206 -443.299088) (xy 93.2561 -449.181982)
			(xy 93.2561 -449.923916) (xy 92.317062 -450.863208) (xy 92.198952 -450.981318) (xy 92.183561 -450.997318)
			(xy 92.15806 -451.033655) (xy 92.139262 -451.073871) (xy 92.12774 -451.116742) (xy 92.123844 -451.160963)
			(xy 92.127692 -451.205188) (xy 92.139168 -451.248071) (xy 92.157922 -451.288308) (xy 92.183384 -451.324672)
			(xy 92.214778 -451.356058) (xy 92.25115 -451.381511) (xy 92.271088 -451.391274) (xy 92.307207 -451.40739)
			(xy 92.375957 -451.446499) (xy 92.439947 -451.492991) (xy 92.498386 -451.546292) (xy 92.550554 -451.605744)
			(xy 92.595807 -451.670615) (xy 92.633588 -451.740105) (xy 92.663429 -451.813355) (xy 92.674694 -451.851268)
			(xy 92.684669 -451.888399) (xy 92.697515 -451.964207) (xy 92.702112 -452.040958) (xy 92.698408 -452.117757)
			(xy 92.686445 -452.193709) (xy 92.666364 -452.267929) (xy 92.638398 -452.339551) (xy 92.602872 -452.40774)
			(xy 92.560203 -452.471702) (xy 92.510886 -452.530691) (xy 92.455497 -452.584019) (xy 92.394681 -452.631064)
			(xy 92.329147 -452.671279) (xy 92.25966 -452.704193) (xy 92.18703 -452.729424) (xy 92.112102 -452.746678)
			(xy 92.073984 -452.751698) (xy 92.037622 -452.755555) (xy 91.964504 -452.756703) (xy 91.891654 -452.750346)
			(xy 91.81984 -452.73655) (xy 91.74982 -452.715462) (xy 91.682332 -452.687304) (xy 91.618088 -452.652372)
			(xy 91.557766 -452.611036) (xy 91.502001 -452.563731) (xy 91.451382 -452.510956) (xy 91.406442 -452.453267)
			(xy 91.38666 -452.422514) (xy 91.37773 -452.409116) (xy 91.354379 -452.386962) (xy 91.326223 -452.371362)
			(xy 91.295058 -452.36331) (xy 91.278964 -452.362824) (xy 90.870786 -452.362824) (xy 90.854134 -452.36332)
			(xy 90.821965 -452.371944) (xy 90.793124 -452.388601) (xy 90.769577 -452.412154) (xy 90.75293 -452.441)
			(xy 90.744315 -452.473171) (xy 90.743786 -452.489824) (xy 90.743786 -452.536052) (xy 90.80246 -452.60641)
			(xy 90.847926 -452.614792) (xy 90.885588 -452.622193) (xy 90.959173 -452.644033) (xy 91.029981 -452.673664)
			(xy 91.09719 -452.710741) (xy 91.160018 -452.754835) (xy 91.166001 -452.76008) (xy 93.154506 -452.76008)
			(xy 93.158522 -452.64381) (xy 93.170549 -452.528095) (xy 93.190531 -452.413485) (xy 93.218373 -452.300526)
			(xy 93.253942 -452.189758) (xy 93.297068 -452.081707) (xy 93.347545 -451.976889) (xy 93.405134 -451.875804)
			(xy 93.46956 -451.778932) (xy 93.540515 -451.686736) (xy 93.617662 -451.599655) (xy 93.700633 -451.518104)
			(xy 93.789033 -451.442472) (xy 93.88244 -451.373118) (xy 93.980409 -451.310375) (xy 94.082473 -451.254539)
			(xy 94.188147 -451.205878) (xy 94.296926 -451.164624) (xy 94.408291 -451.130973) (xy 94.521714 -451.105085)
			(xy 94.636651 -451.087084) (xy 94.752557 -451.077055) (xy 94.868879 -451.075047) (xy 94.985062 -451.081069)
			(xy 95.100553 -451.095092) (xy 95.214801 -451.11705) (xy 95.327262 -451.146837) (xy 95.4374 -451.184312)
			(xy 95.54469 -451.229297) (xy 95.648621 -451.281576) (xy 95.748697 -451.340901) (xy 95.844443 -451.406989)
			(xy 95.9354 -451.479525) (xy 96.021136 -451.558164) (xy 96.101243 -451.64253) (xy 96.175339 -451.732222)
			(xy 96.243069 -451.826812) (xy 96.304113 -451.92585) (xy 96.358178 -452.028863) (xy 96.405008 -452.13536)
			(xy 96.444379 -452.244835) (xy 96.476103 -452.356765) (xy 96.500029 -452.470617) (xy 96.516043 -452.585849)
			(xy 96.52407 -452.701911) (xy 96.524572 -452.76008) (xy 96.52407 -452.818249) (xy 96.516043 -452.934311)
			(xy 96.500029 -453.049543) (xy 96.476103 -453.163395) (xy 96.444379 -453.275325) (xy 96.405008 -453.3848)
			(xy 96.358178 -453.491297) (xy 96.304113 -453.59431) (xy 96.243069 -453.693348) (xy 96.175339 -453.787938)
			(xy 96.101243 -453.87763) (xy 96.021136 -453.961996) (xy 95.9354 -454.040635) (xy 95.844443 -454.113171)
			(xy 95.748697 -454.179259) (xy 95.648621 -454.238584) (xy 95.54469 -454.290863) (xy 95.4374 -454.335848)
			(xy 95.327262 -454.373323) (xy 95.214801 -454.40311) (xy 95.100553 -454.425068) (xy 94.985062 -454.439091)
			(xy 94.868879 -454.445113) (xy 94.752557 -454.443105) (xy 94.636651 -454.433076) (xy 94.521714 -454.415075)
			(xy 94.408291 -454.389187) (xy 94.296926 -454.355536) (xy 94.188147 -454.314282) (xy 94.082473 -454.265621)
			(xy 93.980409 -454.209785) (xy 93.88244 -454.147042) (xy 93.789033 -454.077688) (xy 93.700633 -454.002056)
			(xy 93.617662 -453.920505) (xy 93.540515 -453.833424) (xy 93.46956 -453.741228) (xy 93.405134 -453.644356)
			(xy 93.347545 -453.543271) (xy 93.297068 -453.438453) (xy 93.253942 -453.330402) (xy 93.218373 -453.219634)
			(xy 93.190531 -453.106675) (xy 93.170549 -452.992065) (xy 93.158522 -452.87635) (xy 93.154506 -452.76008)
			(xy 91.166001 -452.76008) (xy 91.217738 -452.805434) (xy 91.269678 -452.861949) (xy 91.315235 -452.923725)
			(xy 91.353881 -452.990045) (xy 91.385166 -453.060137) (xy 91.408727 -453.133189) (xy 91.424292 -453.208353)
			(xy 91.431678 -453.284754) (xy 91.430801 -453.361507) (xy 91.42167 -453.437719) (xy 91.404391 -453.512507)
			(xy 91.379166 -453.585001) (xy 91.346287 -453.654361) (xy 91.306135 -453.719779) (xy 91.283028 -453.750426)
			(xy 91.259364 -453.780236) (xy 91.206659 -453.835148) (xy 91.148393 -453.884122) (xy 91.085233 -453.926597)
			(xy 91.0179 -453.962088) (xy 90.947163 -453.990189) (xy 90.873832 -454.01058) (xy 90.798743 -454.023028)
			(xy 90.722754 -454.027389) (xy 90.646733 -454.023616) (xy 90.57155 -454.011749) (xy 90.498063 -453.991926)
			(xy 90.427111 -453.964373) (xy 90.359506 -453.929404) (xy 90.296019 -453.887418) (xy 90.237377 -453.838897)
			(xy 90.184248 -453.784393) (xy 90.13724 -453.72453) (xy 90.11666 -453.692514) (xy 90.10773 -453.679116)
			(xy 90.084379 -453.656962) (xy 90.056223 -453.641362) (xy 90.025058 -453.63331) (xy 90.008964 -453.632824)
			(xy 89.83853 -453.632824) (xy 88.653366 -454.817988) (xy 85.284564 -454.817988) (xy 83.26628 -452.799704)
			(xy 83.01228 -452.545958) (xy 83.01228 -449.856098) (xy 81.72577 -448.569588) (xy 44.684442 -448.569588)
			(xy 39.177214 -443.06236) (xy 37.300408 -443.06236) (xy 37.277703 -443.062834) (xy 37.233006 -443.070852)
			(xy 37.190447 -443.086686) (xy 37.15138 -443.109833) (xy 37.117049 -443.139555) (xy 37.088548 -443.174907)
			(xy 37.066784 -443.214761) (xy 37.052451 -443.257849) (xy 37.046005 -443.302799) (xy 37.047652 -443.348178)
			(xy 37.057338 -443.392543) (xy 37.074756 -443.434479) (xy 37.09935 -443.472652) (xy 37.11448 -443.489588)
			(xy 39.88308 -446.258442) (xy 39.88308 -450.044566) (xy 39.88428 -450.067008) (xy 39.893593 -450.110971)
			(xy 39.910485 -450.152614) (xy 39.934431 -450.19064) (xy 39.964686 -450.223868) (xy 40.000309 -450.251263)
			(xy 40.040191 -450.271973) (xy 40.083091 -450.285353) (xy 40.127675 -450.290987) (xy 40.172555 -450.2887)
			(xy 40.216335 -450.278563) (xy 40.257653 -450.260891) (xy 40.295223 -450.236235) (xy 40.311832 -450.221096)
			(xy 40.353381 -450.180285) (xy 40.441278 -450.103864) (xy 40.534255 -450.033712) (xy 40.631867 -449.970165)
			(xy 40.733643 -449.913529) (xy 40.839097 -449.864075) (xy 40.947722 -449.822041) (xy 41.058996 -449.787629)
			(xy 41.172386 -449.761003) (xy 41.287347 -449.742292) (xy 41.403328 -449.731584) (xy 41.519771 -449.728933)
			(xy 41.636119 -449.73435) (xy 41.751813 -449.747809) (xy 41.866297 -449.769246) (xy 41.979022 -449.798558)
			(xy 42.089447 -449.835604) (xy 42.197043 -449.880207) (xy 42.301292 -449.932151) (xy 42.401695 -449.991189)
			(xy 42.497769 -450.057037) (xy 42.501584 -450.06006) (xy 43.327577 -450.06006) (xy 43.331612 -449.984356)
			(xy 43.343671 -449.909511) (xy 43.363617 -449.83637) (xy 43.391224 -449.765765) (xy 43.42618 -449.698494)
			(xy 43.468088 -449.635319) (xy 43.516474 -449.576957) (xy 43.57079 -449.524069) (xy 43.630419 -449.477254)
			(xy 43.694687 -449.437042) (xy 43.762864 -449.40389) (xy 43.83418 -449.378172) (xy 43.907825 -449.36018)
			(xy 43.982965 -449.350118) (xy 44.058749 -449.348099) (xy 44.134319 -449.354148) (xy 44.208817 -449.368195)
			(xy 44.2814 -449.390081) (xy 44.351246 -449.419558) (xy 44.417563 -449.456293) (xy 44.479599 -449.499868)
			(xy 44.536652 -449.54979) (xy 44.588076 -449.605494) (xy 44.633287 -449.666349) (xy 44.671774 -449.731664)
			(xy 44.7031 -449.8007) (xy 44.72691 -449.872675) (xy 44.742935 -449.946773) (xy 44.750994 -450.022154)
			(xy 44.751498 -450.06006) (xy 45.867577 -450.06006) (xy 45.871612 -449.984356) (xy 45.883671 -449.909511)
			(xy 45.903617 -449.83637) (xy 45.931224 -449.765765) (xy 45.96618 -449.698494) (xy 46.008088 -449.635319)
			(xy 46.056474 -449.576957) (xy 46.11079 -449.524069) (xy 46.170419 -449.477254) (xy 46.234687 -449.437042)
			(xy 46.302864 -449.40389) (xy 46.37418 -449.378172) (xy 46.447825 -449.36018) (xy 46.522965 -449.350118)
			(xy 46.598749 -449.348099) (xy 46.674319 -449.354148) (xy 46.748817 -449.368195) (xy 46.8214 -449.390081)
			(xy 46.891246 -449.419558) (xy 46.957563 -449.456293) (xy 47.019599 -449.499868) (xy 47.076652 -449.54979)
			(xy 47.128076 -449.605494) (xy 47.173287 -449.666349) (xy 47.211774 -449.731664) (xy 47.2431 -449.8007)
			(xy 47.26691 -449.872675) (xy 47.282935 -449.946773) (xy 47.290994 -450.022154) (xy 47.291498 -450.06006)
			(xy 48.407577 -450.06006) (xy 48.411612 -449.984356) (xy 48.423671 -449.909511) (xy 48.443617 -449.83637)
			(xy 48.471224 -449.765765) (xy 48.50618 -449.698494) (xy 48.548088 -449.635319) (xy 48.596474 -449.576957)
			(xy 48.65079 -449.524069) (xy 48.710419 -449.477254) (xy 48.774687 -449.437042) (xy 48.842864 -449.40389)
			(xy 48.91418 -449.378172) (xy 48.987825 -449.36018) (xy 49.062965 -449.350118) (xy 49.138749 -449.348099)
			(xy 49.214319 -449.354148) (xy 49.288817 -449.368195) (xy 49.3614 -449.390081) (xy 49.431246 -449.419558)
			(xy 49.497563 -449.456293) (xy 49.559599 -449.499868) (xy 49.616652 -449.54979) (xy 49.668076 -449.605494)
			(xy 49.713287 -449.666349) (xy 49.751774 -449.731664) (xy 49.7831 -449.8007) (xy 49.80691 -449.872675)
			(xy 49.822935 -449.946773) (xy 49.830994 -450.022154) (xy 49.831498 -450.06006) (xy 50.947577 -450.06006)
			(xy 50.951612 -449.984356) (xy 50.963671 -449.909511) (xy 50.983617 -449.83637) (xy 51.011224 -449.765765)
			(xy 51.04618 -449.698494) (xy 51.088088 -449.635319) (xy 51.136474 -449.576957) (xy 51.19079 -449.524069)
			(xy 51.250419 -449.477254) (xy 51.314687 -449.437042) (xy 51.382864 -449.40389) (xy 51.45418 -449.378172)
			(xy 51.527825 -449.36018) (xy 51.602965 -449.350118) (xy 51.678749 -449.348099) (xy 51.754319 -449.354148)
			(xy 51.828817 -449.368195) (xy 51.9014 -449.390081) (xy 51.971246 -449.419558) (xy 52.037563 -449.456293)
			(xy 52.099599 -449.499868) (xy 52.156652 -449.54979) (xy 52.208076 -449.605494) (xy 52.253287 -449.666349)
			(xy 52.291774 -449.731664) (xy 52.3231 -449.8007) (xy 52.34691 -449.872675) (xy 52.362935 -449.946773)
			(xy 52.370994 -450.022154) (xy 52.371498 -450.06006) (xy 53.487577 -450.06006) (xy 53.491612 -449.984356)
			(xy 53.503671 -449.909511) (xy 53.523617 -449.83637) (xy 53.551224 -449.765765) (xy 53.58618 -449.698494)
			(xy 53.628088 -449.635319) (xy 53.676474 -449.576957) (xy 53.73079 -449.524069) (xy 53.790419 -449.477254)
			(xy 53.854687 -449.437042) (xy 53.922864 -449.40389) (xy 53.99418 -449.378172) (xy 54.067825 -449.36018)
			(xy 54.142965 -449.350118) (xy 54.218749 -449.348099) (xy 54.294319 -449.354148) (xy 54.368817 -449.368195)
			(xy 54.4414 -449.390081) (xy 54.511246 -449.419558) (xy 54.577563 -449.456293) (xy 54.639599 -449.499868)
			(xy 54.696652 -449.54979) (xy 54.748076 -449.605494) (xy 54.793287 -449.666349) (xy 54.831774 -449.731664)
			(xy 54.8631 -449.8007) (xy 54.88691 -449.872675) (xy 54.902935 -449.946773) (xy 54.910994 -450.022154)
			(xy 54.911498 -450.06006) (xy 56.027577 -450.06006) (xy 56.031612 -449.984356) (xy 56.043671 -449.909511)
			(xy 56.063617 -449.83637) (xy 56.091224 -449.765765) (xy 56.12618 -449.698494) (xy 56.168088 -449.635319)
			(xy 56.216474 -449.576957) (xy 56.27079 -449.524069) (xy 56.330419 -449.477254) (xy 56.394687 -449.437042)
			(xy 56.462864 -449.40389) (xy 56.53418 -449.378172) (xy 56.607825 -449.36018) (xy 56.682965 -449.350118)
			(xy 56.758749 -449.348099) (xy 56.834319 -449.354148) (xy 56.908817 -449.368195) (xy 56.9814 -449.390081)
			(xy 57.051246 -449.419558) (xy 57.117563 -449.456293) (xy 57.179599 -449.499868) (xy 57.236652 -449.54979)
			(xy 57.288076 -449.605494) (xy 57.333287 -449.666349) (xy 57.371774 -449.731664) (xy 57.4031 -449.8007)
			(xy 57.42691 -449.872675) (xy 57.442935 -449.946773) (xy 57.450994 -450.022154) (xy 57.451498 -450.06006)
			(xy 58.567577 -450.06006) (xy 58.571612 -449.984356) (xy 58.583671 -449.909511) (xy 58.603617 -449.83637)
			(xy 58.631224 -449.765765) (xy 58.66618 -449.698494) (xy 58.708088 -449.635319) (xy 58.756474 -449.576957)
			(xy 58.81079 -449.524069) (xy 58.870419 -449.477254) (xy 58.934687 -449.437042) (xy 59.002864 -449.40389)
			(xy 59.07418 -449.378172) (xy 59.147825 -449.36018) (xy 59.222965 -449.350118) (xy 59.298749 -449.348099)
			(xy 59.374319 -449.354148) (xy 59.448817 -449.368195) (xy 59.5214 -449.390081) (xy 59.591246 -449.419558)
			(xy 59.657563 -449.456293) (xy 59.719599 -449.499868) (xy 59.776652 -449.54979) (xy 59.828076 -449.605494)
			(xy 59.873287 -449.666349) (xy 59.911774 -449.731664) (xy 59.9431 -449.8007) (xy 59.96691 -449.872675)
			(xy 59.982935 -449.946773) (xy 59.990994 -450.022154) (xy 59.991498 -450.06006) (xy 61.107577 -450.06006)
			(xy 61.111612 -449.984356) (xy 61.123671 -449.909511) (xy 61.143617 -449.83637) (xy 61.171224 -449.765765)
			(xy 61.20618 -449.698494) (xy 61.248088 -449.635319) (xy 61.296474 -449.576957) (xy 61.35079 -449.524069)
			(xy 61.410419 -449.477254) (xy 61.474687 -449.437042) (xy 61.542864 -449.40389) (xy 61.61418 -449.378172)
			(xy 61.687825 -449.36018) (xy 61.762965 -449.350118) (xy 61.838749 -449.348099) (xy 61.914319 -449.354148)
			(xy 61.988817 -449.368195) (xy 62.0614 -449.390081) (xy 62.131246 -449.419558) (xy 62.197563 -449.456293)
			(xy 62.259599 -449.499868) (xy 62.316652 -449.54979) (xy 62.368076 -449.605494) (xy 62.413287 -449.666349)
			(xy 62.451774 -449.731664) (xy 62.4831 -449.8007) (xy 62.50691 -449.872675) (xy 62.522935 -449.946773)
			(xy 62.530994 -450.022154) (xy 62.531498 -450.06006) (xy 62.530994 -450.097966) (xy 62.522935 -450.173347)
			(xy 62.50691 -450.247445) (xy 62.4831 -450.31942) (xy 62.451774 -450.388456) (xy 62.413287 -450.453771)
			(xy 62.368076 -450.514626) (xy 62.316652 -450.57033) (xy 62.259599 -450.620252) (xy 62.197563 -450.663827)
			(xy 62.131246 -450.700562) (xy 62.0614 -450.730039) (xy 61.988817 -450.751925) (xy 61.914319 -450.765972)
			(xy 61.838749 -450.772021) (xy 61.762965 -450.770002) (xy 61.687825 -450.75994) (xy 61.61418 -450.741948)
			(xy 61.542864 -450.71623) (xy 61.474687 -450.683078) (xy 61.410419 -450.642866) (xy 61.35079 -450.596051)
			(xy 61.296474 -450.543163) (xy 61.248088 -450.484801) (xy 61.20618 -450.421626) (xy 61.171224 -450.354355)
			(xy 61.143617 -450.28375) (xy 61.123671 -450.210609) (xy 61.111612 -450.135764) (xy 61.107577 -450.06006)
			(xy 59.991498 -450.06006) (xy 59.990994 -450.097966) (xy 59.982935 -450.173347) (xy 59.96691 -450.247445)
			(xy 59.9431 -450.31942) (xy 59.911774 -450.388456) (xy 59.873287 -450.453771) (xy 59.828076 -450.514626)
			(xy 59.776652 -450.57033) (xy 59.719599 -450.620252) (xy 59.657563 -450.663827) (xy 59.591246 -450.700562)
			(xy 59.5214 -450.730039) (xy 59.448817 -450.751925) (xy 59.374319 -450.765972) (xy 59.298749 -450.772021)
			(xy 59.222965 -450.770002) (xy 59.147825 -450.75994) (xy 59.07418 -450.741948) (xy 59.002864 -450.71623)
			(xy 58.934687 -450.683078) (xy 58.870419 -450.642866) (xy 58.81079 -450.596051) (xy 58.756474 -450.543163)
			(xy 58.708088 -450.484801) (xy 58.66618 -450.421626) (xy 58.631224 -450.354355) (xy 58.603617 -450.28375)
			(xy 58.583671 -450.210609) (xy 58.571612 -450.135764) (xy 58.567577 -450.06006) (xy 57.451498 -450.06006)
			(xy 57.450994 -450.097966) (xy 57.442935 -450.173347) (xy 57.42691 -450.247445) (xy 57.4031 -450.31942)
			(xy 57.371774 -450.388456) (xy 57.333287 -450.453771) (xy 57.288076 -450.514626) (xy 57.236652 -450.57033)
			(xy 57.179599 -450.620252) (xy 57.117563 -450.663827) (xy 57.051246 -450.700562) (xy 56.9814 -450.730039)
			(xy 56.908817 -450.751925) (xy 56.834319 -450.765972) (xy 56.758749 -450.772021) (xy 56.682965 -450.770002)
			(xy 56.607825 -450.75994) (xy 56.53418 -450.741948) (xy 56.462864 -450.71623) (xy 56.394687 -450.683078)
			(xy 56.330419 -450.642866) (xy 56.27079 -450.596051) (xy 56.216474 -450.543163) (xy 56.168088 -450.484801)
			(xy 56.12618 -450.421626) (xy 56.091224 -450.354355) (xy 56.063617 -450.28375) (xy 56.043671 -450.210609)
			(xy 56.031612 -450.135764) (xy 56.027577 -450.06006) (xy 54.911498 -450.06006) (xy 54.910994 -450.097966)
			(xy 54.902935 -450.173347) (xy 54.88691 -450.247445) (xy 54.8631 -450.31942) (xy 54.831774 -450.388456)
			(xy 54.793287 -450.453771) (xy 54.748076 -450.514626) (xy 54.696652 -450.57033) (xy 54.639599 -450.620252)
			(xy 54.577563 -450.663827) (xy 54.511246 -450.700562) (xy 54.4414 -450.730039) (xy 54.368817 -450.751925)
			(xy 54.294319 -450.765972) (xy 54.218749 -450.772021) (xy 54.142965 -450.770002) (xy 54.067825 -450.75994)
			(xy 53.99418 -450.741948) (xy 53.922864 -450.71623) (xy 53.854687 -450.683078) (xy 53.790419 -450.642866)
			(xy 53.73079 -450.596051) (xy 53.676474 -450.543163) (xy 53.628088 -450.484801) (xy 53.58618 -450.421626)
			(xy 53.551224 -450.354355) (xy 53.523617 -450.28375) (xy 53.503671 -450.210609) (xy 53.491612 -450.135764)
			(xy 53.487577 -450.06006) (xy 52.371498 -450.06006) (xy 52.370994 -450.097966) (xy 52.362935 -450.173347)
			(xy 52.34691 -450.247445) (xy 52.3231 -450.31942) (xy 52.291774 -450.388456) (xy 52.253287 -450.453771)
			(xy 52.208076 -450.514626) (xy 52.156652 -450.57033) (xy 52.099599 -450.620252) (xy 52.037563 -450.663827)
			(xy 51.971246 -450.700562) (xy 51.9014 -450.730039) (xy 51.828817 -450.751925) (xy 51.754319 -450.765972)
			(xy 51.678749 -450.772021) (xy 51.602965 -450.770002) (xy 51.527825 -450.75994) (xy 51.45418 -450.741948)
			(xy 51.382864 -450.71623) (xy 51.314687 -450.683078) (xy 51.250419 -450.642866) (xy 51.19079 -450.596051)
			(xy 51.136474 -450.543163) (xy 51.088088 -450.484801) (xy 51.04618 -450.421626) (xy 51.011224 -450.354355)
			(xy 50.983617 -450.28375) (xy 50.963671 -450.210609) (xy 50.951612 -450.135764) (xy 50.947577 -450.06006)
			(xy 49.831498 -450.06006) (xy 49.830994 -450.097966) (xy 49.822935 -450.173347) (xy 49.80691 -450.247445)
			(xy 49.7831 -450.31942) (xy 49.751774 -450.388456) (xy 49.713287 -450.453771) (xy 49.668076 -450.514626)
			(xy 49.616652 -450.57033) (xy 49.559599 -450.620252) (xy 49.497563 -450.663827) (xy 49.431246 -450.700562)
			(xy 49.3614 -450.730039) (xy 49.288817 -450.751925) (xy 49.214319 -450.765972) (xy 49.138749 -450.772021)
			(xy 49.062965 -450.770002) (xy 48.987825 -450.75994) (xy 48.91418 -450.741948) (xy 48.842864 -450.71623)
			(xy 48.774687 -450.683078) (xy 48.710419 -450.642866) (xy 48.65079 -450.596051) (xy 48.596474 -450.543163)
			(xy 48.548088 -450.484801) (xy 48.50618 -450.421626) (xy 48.471224 -450.354355) (xy 48.443617 -450.28375)
			(xy 48.423671 -450.210609) (xy 48.411612 -450.135764) (xy 48.407577 -450.06006) (xy 47.291498 -450.06006)
			(xy 47.290994 -450.097966) (xy 47.282935 -450.173347) (xy 47.26691 -450.247445) (xy 47.2431 -450.31942)
			(xy 47.211774 -450.388456) (xy 47.173287 -450.453771) (xy 47.128076 -450.514626) (xy 47.076652 -450.57033)
			(xy 47.019599 -450.620252) (xy 46.957563 -450.663827) (xy 46.891246 -450.700562) (xy 46.8214 -450.730039)
			(xy 46.748817 -450.751925) (xy 46.674319 -450.765972) (xy 46.598749 -450.772021) (xy 46.522965 -450.770002)
			(xy 46.447825 -450.75994) (xy 46.37418 -450.741948) (xy 46.302864 -450.71623) (xy 46.234687 -450.683078)
			(xy 46.170419 -450.642866) (xy 46.11079 -450.596051) (xy 46.056474 -450.543163) (xy 46.008088 -450.484801)
			(xy 45.96618 -450.421626) (xy 45.931224 -450.354355) (xy 45.903617 -450.28375) (xy 45.883671 -450.210609)
			(xy 45.871612 -450.135764) (xy 45.867577 -450.06006) (xy 44.751498 -450.06006) (xy 44.750994 -450.097966)
			(xy 44.742935 -450.173347) (xy 44.72691 -450.247445) (xy 44.7031 -450.31942) (xy 44.671774 -450.388456)
			(xy 44.633287 -450.453771) (xy 44.588076 -450.514626) (xy 44.536652 -450.57033) (xy 44.479599 -450.620252)
			(xy 44.417563 -450.663827) (xy 44.351246 -450.700562) (xy 44.2814 -450.730039) (xy 44.208817 -450.751925)
			(xy 44.134319 -450.765972) (xy 44.058749 -450.772021) (xy 43.982965 -450.770002) (xy 43.907825 -450.75994)
			(xy 43.83418 -450.741948) (xy 43.762864 -450.71623) (xy 43.694687 -450.683078) (xy 43.630419 -450.642866)
			(xy 43.57079 -450.596051) (xy 43.516474 -450.543163) (xy 43.468088 -450.484801) (xy 43.42618 -450.421626)
			(xy 43.391224 -450.354355) (xy 43.363617 -450.28375) (xy 43.343671 -450.210609) (xy 43.331612 -450.135764)
			(xy 43.327577 -450.06006) (xy 42.501584 -450.06006) (xy 42.589054 -450.129378) (xy 42.675111 -450.207866)
			(xy 42.755527 -450.292124) (xy 42.829917 -450.381747) (xy 42.897923 -450.476305) (xy 42.95922 -450.575345)
			(xy 43.013512 -450.678391) (xy 43.06054 -450.784949) (xy 43.100077 -450.894507) (xy 43.131934 -451.00654)
			(xy 43.155958 -451.120509) (xy 43.172034 -451.235868) (xy 43.180084 -451.352064) (xy 43.18007 -451.468538)
			(xy 43.171992 -451.584731) (xy 43.155889 -451.700086) (xy 43.131837 -451.81405) (xy 43.099954 -451.926075)
			(xy 43.06039 -452.035624) (xy 43.013337 -452.14217) (xy 42.95902 -452.245203) (xy 42.8977 -452.344229)
			(xy 42.829671 -452.438771) (xy 42.75526 -452.528376) (xy 42.674823 -452.612615) (xy 42.588748 -452.691082)
			(xy 42.50164 -452.76008) (xy 43.327577 -452.76008) (xy 43.331612 -452.684376) (xy 43.343671 -452.609531)
			(xy 43.363617 -452.53639) (xy 43.391224 -452.465785) (xy 43.42618 -452.398514) (xy 43.468088 -452.335339)
			(xy 43.516474 -452.276977) (xy 43.57079 -452.224089) (xy 43.630419 -452.177274) (xy 43.694687 -452.137062)
			(xy 43.762864 -452.10391) (xy 43.83418 -452.078192) (xy 43.907825 -452.0602) (xy 43.982965 -452.050138)
			(xy 44.058749 -452.048119) (xy 44.134319 -452.054168) (xy 44.208817 -452.068215) (xy 44.2814 -452.090101)
			(xy 44.351246 -452.119578) (xy 44.417563 -452.156313) (xy 44.479599 -452.199888) (xy 44.536652 -452.24981)
			(xy 44.588076 -452.305514) (xy 44.633287 -452.366369) (xy 44.671774 -452.431684) (xy 44.7031 -452.50072)
			(xy 44.72691 -452.572695) (xy 44.742935 -452.646793) (xy 44.750994 -452.722174) (xy 44.751498 -452.76008)
			(xy 45.867577 -452.76008) (xy 45.871612 -452.684376) (xy 45.883671 -452.609531) (xy 45.903617 -452.53639)
			(xy 45.931224 -452.465785) (xy 45.96618 -452.398514) (xy 46.008088 -452.335339) (xy 46.056474 -452.276977)
			(xy 46.11079 -452.224089) (xy 46.170419 -452.177274) (xy 46.234687 -452.137062) (xy 46.302864 -452.10391)
			(xy 46.37418 -452.078192) (xy 46.447825 -452.0602) (xy 46.522965 -452.050138) (xy 46.598749 -452.048119)
			(xy 46.674319 -452.054168) (xy 46.748817 -452.068215) (xy 46.8214 -452.090101) (xy 46.891246 -452.119578)
			(xy 46.957563 -452.156313) (xy 47.019599 -452.199888) (xy 47.076652 -452.24981) (xy 47.128076 -452.305514)
			(xy 47.173287 -452.366369) (xy 47.211774 -452.431684) (xy 47.2431 -452.50072) (xy 47.26691 -452.572695)
			(xy 47.282935 -452.646793) (xy 47.290994 -452.722174) (xy 47.291498 -452.76008) (xy 48.407577 -452.76008)
			(xy 48.411612 -452.684376) (xy 48.423671 -452.609531) (xy 48.443617 -452.53639) (xy 48.471224 -452.465785)
			(xy 48.50618 -452.398514) (xy 48.548088 -452.335339) (xy 48.596474 -452.276977) (xy 48.65079 -452.224089)
			(xy 48.710419 -452.177274) (xy 48.774687 -452.137062) (xy 48.842864 -452.10391) (xy 48.91418 -452.078192)
			(xy 48.987825 -452.0602) (xy 49.062965 -452.050138) (xy 49.138749 -452.048119) (xy 49.214319 -452.054168)
			(xy 49.288817 -452.068215) (xy 49.3614 -452.090101) (xy 49.431246 -452.119578) (xy 49.497563 -452.156313)
			(xy 49.559599 -452.199888) (xy 49.616652 -452.24981) (xy 49.668076 -452.305514) (xy 49.713287 -452.366369)
			(xy 49.751774 -452.431684) (xy 49.7831 -452.50072) (xy 49.80691 -452.572695) (xy 49.822935 -452.646793)
			(xy 49.830994 -452.722174) (xy 49.831498 -452.76008) (xy 50.947577 -452.76008) (xy 50.951612 -452.684376)
			(xy 50.963671 -452.609531) (xy 50.983617 -452.53639) (xy 51.011224 -452.465785) (xy 51.04618 -452.398514)
			(xy 51.088088 -452.335339) (xy 51.136474 -452.276977) (xy 51.19079 -452.224089) (xy 51.250419 -452.177274)
			(xy 51.314687 -452.137062) (xy 51.382864 -452.10391) (xy 51.45418 -452.078192) (xy 51.527825 -452.0602)
			(xy 51.602965 -452.050138) (xy 51.678749 -452.048119) (xy 51.754319 -452.054168) (xy 51.828817 -452.068215)
			(xy 51.9014 -452.090101) (xy 51.971246 -452.119578) (xy 52.037563 -452.156313) (xy 52.099599 -452.199888)
			(xy 52.156652 -452.24981) (xy 52.208076 -452.305514) (xy 52.253287 -452.366369) (xy 52.291774 -452.431684)
			(xy 52.3231 -452.50072) (xy 52.34691 -452.572695) (xy 52.362935 -452.646793) (xy 52.370994 -452.722174)
			(xy 52.371498 -452.76008) (xy 53.487577 -452.76008) (xy 53.491612 -452.684376) (xy 53.503671 -452.609531)
			(xy 53.523617 -452.53639) (xy 53.551224 -452.465785) (xy 53.58618 -452.398514) (xy 53.628088 -452.335339)
			(xy 53.676474 -452.276977) (xy 53.73079 -452.224089) (xy 53.790419 -452.177274) (xy 53.854687 -452.137062)
			(xy 53.922864 -452.10391) (xy 53.99418 -452.078192) (xy 54.067825 -452.0602) (xy 54.142965 -452.050138)
			(xy 54.218749 -452.048119) (xy 54.294319 -452.054168) (xy 54.368817 -452.068215) (xy 54.4414 -452.090101)
			(xy 54.511246 -452.119578) (xy 54.577563 -452.156313) (xy 54.639599 -452.199888) (xy 54.696652 -452.24981)
			(xy 54.748076 -452.305514) (xy 54.793287 -452.366369) (xy 54.831774 -452.431684) (xy 54.8631 -452.50072)
			(xy 54.88691 -452.572695) (xy 54.902935 -452.646793) (xy 54.910994 -452.722174) (xy 54.911498 -452.76008)
			(xy 56.027577 -452.76008) (xy 56.031612 -452.684376) (xy 56.043671 -452.609531) (xy 56.063617 -452.53639)
			(xy 56.091224 -452.465785) (xy 56.12618 -452.398514) (xy 56.168088 -452.335339) (xy 56.216474 -452.276977)
			(xy 56.27079 -452.224089) (xy 56.330419 -452.177274) (xy 56.394687 -452.137062) (xy 56.462864 -452.10391)
			(xy 56.53418 -452.078192) (xy 56.607825 -452.0602) (xy 56.682965 -452.050138) (xy 56.758749 -452.048119)
			(xy 56.834319 -452.054168) (xy 56.908817 -452.068215) (xy 56.9814 -452.090101) (xy 57.051246 -452.119578)
			(xy 57.117563 -452.156313) (xy 57.179599 -452.199888) (xy 57.236652 -452.24981) (xy 57.288076 -452.305514)
			(xy 57.333287 -452.366369) (xy 57.371774 -452.431684) (xy 57.4031 -452.50072) (xy 57.42691 -452.572695)
			(xy 57.442935 -452.646793) (xy 57.450994 -452.722174) (xy 57.451498 -452.76008) (xy 58.567577 -452.76008)
			(xy 58.571612 -452.684376) (xy 58.583671 -452.609531) (xy 58.603617 -452.53639) (xy 58.631224 -452.465785)
			(xy 58.66618 -452.398514) (xy 58.708088 -452.335339) (xy 58.756474 -452.276977) (xy 58.81079 -452.224089)
			(xy 58.870419 -452.177274) (xy 58.934687 -452.137062) (xy 59.002864 -452.10391) (xy 59.07418 -452.078192)
			(xy 59.147825 -452.0602) (xy 59.222965 -452.050138) (xy 59.298749 -452.048119) (xy 59.374319 -452.054168)
			(xy 59.448817 -452.068215) (xy 59.5214 -452.090101) (xy 59.591246 -452.119578) (xy 59.657563 -452.156313)
			(xy 59.719599 -452.199888) (xy 59.776652 -452.24981) (xy 59.828076 -452.305514) (xy 59.873287 -452.366369)
			(xy 59.911774 -452.431684) (xy 59.9431 -452.50072) (xy 59.96691 -452.572695) (xy 59.982935 -452.646793)
			(xy 59.990994 -452.722174) (xy 59.991498 -452.76008) (xy 61.107577 -452.76008) (xy 61.111612 -452.684376)
			(xy 61.123671 -452.609531) (xy 61.143617 -452.53639) (xy 61.171224 -452.465785) (xy 61.20618 -452.398514)
			(xy 61.248088 -452.335339) (xy 61.296474 -452.276977) (xy 61.35079 -452.224089) (xy 61.410419 -452.177274)
			(xy 61.474687 -452.137062) (xy 61.542864 -452.10391) (xy 61.61418 -452.078192) (xy 61.687825 -452.0602)
			(xy 61.762965 -452.050138) (xy 61.838749 -452.048119) (xy 61.914319 -452.054168) (xy 61.988817 -452.068215)
			(xy 62.0614 -452.090101) (xy 62.131246 -452.119578) (xy 62.197563 -452.156313) (xy 62.259599 -452.199888)
			(xy 62.316652 -452.24981) (xy 62.368076 -452.305514) (xy 62.413287 -452.366369) (xy 62.451774 -452.431684)
			(xy 62.4831 -452.50072) (xy 62.50691 -452.572695) (xy 62.522935 -452.646793) (xy 62.530994 -452.722174)
			(xy 62.531498 -452.76008) (xy 62.530994 -452.797986) (xy 62.522935 -452.873367) (xy 62.50691 -452.947465)
			(xy 62.4831 -453.01944) (xy 62.451774 -453.088476) (xy 62.413287 -453.153791) (xy 62.368076 -453.214646)
			(xy 62.316652 -453.27035) (xy 62.259599 -453.320272) (xy 62.197563 -453.363847) (xy 62.131246 -453.400582)
			(xy 62.0614 -453.430059) (xy 61.988817 -453.451945) (xy 61.914319 -453.465992) (xy 61.838749 -453.472041)
			(xy 61.762965 -453.470022) (xy 61.687825 -453.45996) (xy 61.61418 -453.441968) (xy 61.542864 -453.41625)
			(xy 61.474687 -453.383098) (xy 61.410419 -453.342886) (xy 61.35079 -453.296071) (xy 61.296474 -453.243183)
			(xy 61.248088 -453.184821) (xy 61.20618 -453.121646) (xy 61.171224 -453.054375) (xy 61.143617 -452.98377)
			(xy 61.123671 -452.910629) (xy 61.111612 -452.835784) (xy 61.107577 -452.76008) (xy 59.991498 -452.76008)
			(xy 59.990994 -452.797986) (xy 59.982935 -452.873367) (xy 59.96691 -452.947465) (xy 59.9431 -453.01944)
			(xy 59.911774 -453.088476) (xy 59.873287 -453.153791) (xy 59.828076 -453.214646) (xy 59.776652 -453.27035)
			(xy 59.719599 -453.320272) (xy 59.657563 -453.363847) (xy 59.591246 -453.400582) (xy 59.5214 -453.430059)
			(xy 59.448817 -453.451945) (xy 59.374319 -453.465992) (xy 59.298749 -453.472041) (xy 59.222965 -453.470022)
			(xy 59.147825 -453.45996) (xy 59.07418 -453.441968) (xy 59.002864 -453.41625) (xy 58.934687 -453.383098)
			(xy 58.870419 -453.342886) (xy 58.81079 -453.296071) (xy 58.756474 -453.243183) (xy 58.708088 -453.184821)
			(xy 58.66618 -453.121646) (xy 58.631224 -453.054375) (xy 58.603617 -452.98377) (xy 58.583671 -452.910629)
			(xy 58.571612 -452.835784) (xy 58.567577 -452.76008) (xy 57.451498 -452.76008) (xy 57.450994 -452.797986)
			(xy 57.442935 -452.873367) (xy 57.42691 -452.947465) (xy 57.4031 -453.01944) (xy 57.371774 -453.088476)
			(xy 57.333287 -453.153791) (xy 57.288076 -453.214646) (xy 57.236652 -453.27035) (xy 57.179599 -453.320272)
			(xy 57.117563 -453.363847) (xy 57.051246 -453.400582) (xy 56.9814 -453.430059) (xy 56.908817 -453.451945)
			(xy 56.834319 -453.465992) (xy 56.758749 -453.472041) (xy 56.682965 -453.470022) (xy 56.607825 -453.45996)
			(xy 56.53418 -453.441968) (xy 56.462864 -453.41625) (xy 56.394687 -453.383098) (xy 56.330419 -453.342886)
			(xy 56.27079 -453.296071) (xy 56.216474 -453.243183) (xy 56.168088 -453.184821) (xy 56.12618 -453.121646)
			(xy 56.091224 -453.054375) (xy 56.063617 -452.98377) (xy 56.043671 -452.910629) (xy 56.031612 -452.835784)
			(xy 56.027577 -452.76008) (xy 54.911498 -452.76008) (xy 54.910994 -452.797986) (xy 54.902935 -452.873367)
			(xy 54.88691 -452.947465) (xy 54.8631 -453.01944) (xy 54.831774 -453.088476) (xy 54.793287 -453.153791)
			(xy 54.748076 -453.214646) (xy 54.696652 -453.27035) (xy 54.639599 -453.320272) (xy 54.577563 -453.363847)
			(xy 54.511246 -453.400582) (xy 54.4414 -453.430059) (xy 54.368817 -453.451945) (xy 54.294319 -453.465992)
			(xy 54.218749 -453.472041) (xy 54.142965 -453.470022) (xy 54.067825 -453.45996) (xy 53.99418 -453.441968)
			(xy 53.922864 -453.41625) (xy 53.854687 -453.383098) (xy 53.790419 -453.342886) (xy 53.73079 -453.296071)
			(xy 53.676474 -453.243183) (xy 53.628088 -453.184821) (xy 53.58618 -453.121646) (xy 53.551224 -453.054375)
			(xy 53.523617 -452.98377) (xy 53.503671 -452.910629) (xy 53.491612 -452.835784) (xy 53.487577 -452.76008)
			(xy 52.371498 -452.76008) (xy 52.370994 -452.797986) (xy 52.362935 -452.873367) (xy 52.34691 -452.947465)
			(xy 52.3231 -453.01944) (xy 52.291774 -453.088476) (xy 52.253287 -453.153791) (xy 52.208076 -453.214646)
			(xy 52.156652 -453.27035) (xy 52.099599 -453.320272) (xy 52.037563 -453.363847) (xy 51.971246 -453.400582)
			(xy 51.9014 -453.430059) (xy 51.828817 -453.451945) (xy 51.754319 -453.465992) (xy 51.678749 -453.472041)
			(xy 51.602965 -453.470022) (xy 51.527825 -453.45996) (xy 51.45418 -453.441968) (xy 51.382864 -453.41625)
			(xy 51.314687 -453.383098) (xy 51.250419 -453.342886) (xy 51.19079 -453.296071) (xy 51.136474 -453.243183)
			(xy 51.088088 -453.184821) (xy 51.04618 -453.121646) (xy 51.011224 -453.054375) (xy 50.983617 -452.98377)
			(xy 50.963671 -452.910629) (xy 50.951612 -452.835784) (xy 50.947577 -452.76008) (xy 49.831498 -452.76008)
			(xy 49.830994 -452.797986) (xy 49.822935 -452.873367) (xy 49.80691 -452.947465) (xy 49.7831 -453.01944)
			(xy 49.751774 -453.088476) (xy 49.713287 -453.153791) (xy 49.668076 -453.214646) (xy 49.616652 -453.27035)
			(xy 49.559599 -453.320272) (xy 49.497563 -453.363847) (xy 49.431246 -453.400582) (xy 49.3614 -453.430059)
			(xy 49.288817 -453.451945) (xy 49.214319 -453.465992) (xy 49.138749 -453.472041) (xy 49.062965 -453.470022)
			(xy 48.987825 -453.45996) (xy 48.91418 -453.441968) (xy 48.842864 -453.41625) (xy 48.774687 -453.383098)
			(xy 48.710419 -453.342886) (xy 48.65079 -453.296071) (xy 48.596474 -453.243183) (xy 48.548088 -453.184821)
			(xy 48.50618 -453.121646) (xy 48.471224 -453.054375) (xy 48.443617 -452.98377) (xy 48.423671 -452.910629)
			(xy 48.411612 -452.835784) (xy 48.407577 -452.76008) (xy 47.291498 -452.76008) (xy 47.290994 -452.797986)
			(xy 47.282935 -452.873367) (xy 47.26691 -452.947465) (xy 47.2431 -453.01944) (xy 47.211774 -453.088476)
			(xy 47.173287 -453.153791) (xy 47.128076 -453.214646) (xy 47.076652 -453.27035) (xy 47.019599 -453.320272)
			(xy 46.957563 -453.363847) (xy 46.891246 -453.400582) (xy 46.8214 -453.430059) (xy 46.748817 -453.451945)
			(xy 46.674319 -453.465992) (xy 46.598749 -453.472041) (xy 46.522965 -453.470022) (xy 46.447825 -453.45996)
			(xy 46.37418 -453.441968) (xy 46.302864 -453.41625) (xy 46.234687 -453.383098) (xy 46.170419 -453.342886)
			(xy 46.11079 -453.296071) (xy 46.056474 -453.243183) (xy 46.008088 -453.184821) (xy 45.96618 -453.121646)
			(xy 45.931224 -453.054375) (xy 45.903617 -452.98377) (xy 45.883671 -452.910629) (xy 45.871612 -452.835784)
			(xy 45.867577 -452.76008) (xy 44.751498 -452.76008) (xy 44.750994 -452.797986) (xy 44.742935 -452.873367)
			(xy 44.72691 -452.947465) (xy 44.7031 -453.01944) (xy 44.671774 -453.088476) (xy 44.633287 -453.153791)
			(xy 44.588076 -453.214646) (xy 44.536652 -453.27035) (xy 44.479599 -453.320272) (xy 44.417563 -453.363847)
			(xy 44.351246 -453.400582) (xy 44.2814 -453.430059) (xy 44.208817 -453.451945) (xy 44.134319 -453.465992)
			(xy 44.058749 -453.472041) (xy 43.982965 -453.470022) (xy 43.907825 -453.45996) (xy 43.83418 -453.441968)
			(xy 43.762864 -453.41625) (xy 43.694687 -453.383098) (xy 43.630419 -453.342886) (xy 43.57079 -453.296071)
			(xy 43.516474 -453.243183) (xy 43.468088 -453.184821) (xy 43.42618 -453.121646) (xy 43.391224 -453.054375)
			(xy 43.363617 -452.98377) (xy 43.343671 -452.910629) (xy 43.331612 -452.835784) (xy 43.327577 -452.76008)
			(xy 42.50164 -452.76008) (xy 42.497446 -452.763402) (xy 42.401356 -452.829226) (xy 42.300939 -452.88824)
			(xy 42.196677 -452.94016) (xy 42.089071 -452.984737) (xy 41.978637 -453.021757) (xy 41.865905 -453.051041)
			(xy 41.751415 -453.072451) (xy 41.635719 -453.085883) (xy 41.519369 -453.091272) (xy 41.402926 -453.088592)
			(xy 41.286948 -453.077858) (xy 41.171992 -453.059119) (xy 41.058608 -453.032466) (xy 40.947342 -452.998027)
			(xy 40.838728 -452.955967) (xy 40.733286 -452.906488) (xy 40.631523 -452.849828) (xy 40.533926 -452.786258)
			(xy 40.440966 -452.716083) (xy 40.353087 -452.639641) (xy 40.311578 -452.59879) (xy 40.294918 -452.58372)
			(xy 40.257347 -452.559102) (xy 40.216035 -452.541468) (xy 40.172268 -452.531366) (xy 40.127407 -452.529111)
			(xy 40.082847 -452.534772) (xy 40.039974 -452.548174) (xy 40.000124 -452.5689) (xy 39.964534 -452.596305)
			(xy 39.934313 -452.629536) (xy 39.910399 -452.667559) (xy 39.893539 -452.709193) (xy 39.884255 -452.753141)
			(xy 39.88308 -452.775574) (xy 39.88308 -452.946262) (xy 41.448482 -454.511664) (xy 73.46061 -454.511664)
			(xy 83.458812 -464.509866) (xy 86.877404 -464.509866) (xy 86.881424 -464.319215) (xy 86.893478 -464.128902)
			(xy 86.913544 -463.939267) (xy 86.941587 -463.750646) (xy 86.977556 -463.563376) (xy 87.021388 -463.377788)
			(xy 87.073005 -463.194213) (xy 87.132315 -463.012977) (xy 87.199213 -462.834402) (xy 87.273579 -462.658807)
			(xy 87.355281 -462.486502) (xy 87.444175 -462.317795) (xy 87.540101 -462.152985) (xy 87.64289 -461.992366)
			(xy 87.752359 -461.836223) (xy 87.868313 -461.684834) (xy 87.990547 -461.538467) (xy 88.118841 -461.397383)
			(xy 88.252969 -461.261834) (xy 88.392693 -461.132059) (xy 88.537763 -461.008289) (xy 88.687921 -460.890746)
			(xy 88.842902 -460.779637) (xy 89.002429 -460.67516) (xy 89.166218 -460.577501) (xy 89.333978 -460.486834)
			(xy 89.505412 -460.40332) (xy 89.680214 -460.327107) (xy 89.858073 -460.258331) (xy 90.038674 -460.197113)
			(xy 90.221694 -460.143564) (xy 90.40681 -460.097778) (xy 90.593691 -460.059836) (xy 90.782006 -460.029807)
			(xy 90.971419 -460.007742) (xy 91.161593 -459.993683) (xy 91.352192 -459.987653) (xy 91.542875 -459.989663)
			(xy 91.733304 -459.99971) (xy 91.92314 -460.017776) (xy 92.112046 -460.043829) (xy 92.299685 -460.077822)
			(xy 92.485725 -460.119695) (xy 92.669834 -460.169374) (xy 92.851685 -460.22677) (xy 93.030955 -460.291781)
			(xy 93.207325 -460.364292) (xy 93.380481 -460.444173) (xy 93.550116 -460.531283) (xy 93.715928 -460.625467)
			(xy 93.877622 -460.726558) (xy 94.03491 -460.834374) (xy 94.187513 -460.948726) (xy 94.335161 -461.069409)
			(xy 94.477589 -461.19621) (xy 94.614545 -461.328901) (xy 94.745786 -461.467249) (xy 94.871078 -461.611006)
			(xy 94.990198 -461.759917) (xy 95.102934 -461.913718) (xy 95.209087 -462.072134) (xy 95.308467 -462.234885)
			(xy 95.400897 -462.40168) (xy 95.486214 -462.572224) (xy 95.564266 -462.746212) (xy 95.634913 -462.923337)
			(xy 95.698031 -463.103282) (xy 95.753507 -463.285728) (xy 95.801242 -463.470351) (xy 95.841152 -463.656821)
			(xy 95.873165 -463.844809) (xy 95.897225 -464.033979) (xy 95.913288 -464.223995) (xy 95.921327 -464.414519)
			(xy 95.92183 -464.509866) (xy 95.921327 -464.605213) (xy 95.913288 -464.795737) (xy 95.897225 -464.985753)
			(xy 95.873165 -465.174923) (xy 95.841152 -465.362911) (xy 95.801242 -465.549381) (xy 95.753507 -465.734004)
			(xy 95.698031 -465.91645) (xy 95.634913 -466.096395) (xy 95.564266 -466.27352) (xy 95.486214 -466.447508)
			(xy 95.400897 -466.618052) (xy 95.308467 -466.784847) (xy 95.209087 -466.947598) (xy 95.102934 -467.106014)
			(xy 94.990198 -467.259815) (xy 94.871078 -467.408726) (xy 94.745786 -467.552483) (xy 94.614545 -467.690831)
			(xy 94.477589 -467.823522) (xy 94.335161 -467.950323) (xy 94.187513 -468.071006) (xy 94.03491 -468.185358)
			(xy 93.877622 -468.293174) (xy 93.715928 -468.394265) (xy 93.550116 -468.488449) (xy 93.380481 -468.575559)
			(xy 93.207325 -468.65544) (xy 93.030955 -468.727951) (xy 92.851685 -468.792962) (xy 92.669834 -468.850358)
			(xy 92.485725 -468.900037) (xy 92.299685 -468.94191) (xy 92.112046 -468.975903) (xy 91.92314 -469.001956)
			(xy 91.733304 -469.020022) (xy 91.542875 -469.030069) (xy 91.352192 -469.032079) (xy 91.161593 -469.026049)
			(xy 90.971419 -469.01199) (xy 90.782006 -468.989925) (xy 90.593691 -468.959896) (xy 90.40681 -468.921954)
			(xy 90.221694 -468.876168) (xy 90.038674 -468.822619) (xy 89.858073 -468.761401) (xy 89.680214 -468.692625)
			(xy 89.505412 -468.616412) (xy 89.333978 -468.532898) (xy 89.166218 -468.442231) (xy 89.002429 -468.344572)
			(xy 88.842902 -468.240095) (xy 88.687921 -468.128986) (xy 88.537763 -468.011443) (xy 88.392693 -467.887673)
			(xy 88.252969 -467.757898) (xy 88.118841 -467.622349) (xy 87.990547 -467.481265) (xy 87.868313 -467.334898)
			(xy 87.752359 -467.183509) (xy 87.64289 -467.027366) (xy 87.540101 -466.866747) (xy 87.444175 -466.701937)
			(xy 87.355281 -466.53323) (xy 87.273579 -466.360925) (xy 87.199213 -466.18533) (xy 87.132315 -466.006755)
			(xy 87.073005 -465.825519) (xy 87.021388 -465.641944) (xy 86.977556 -465.456356) (xy 86.941587 -465.269086)
			(xy 86.913544 -465.080465) (xy 86.893478 -464.89083) (xy 86.881424 -464.700517) (xy 86.877404 -464.509866)
			(xy 83.458812 -464.509866) (xy 85.801708 -466.852762) (xy 85.801708 -483.299516) (xy 87.360506 -484.858314)
			(xy 87.551768 -485.049322) (xy 87.583264 -485.058466) (xy 87.609663 -485.066544) (xy 87.659982 -485.089251)
			(xy 87.706503 -485.118973) (xy 87.748254 -485.15509) (xy 87.784364 -485.196847) (xy 87.814079 -485.243373)
			(xy 87.836777 -485.293696) (xy 87.844884 -485.320086) (xy 87.854028 -485.351582) (xy 89.753948 -487.251502)
			(xy 91.911676 -487.251502) (xy 91.915747 -487.19588) (xy 91.927873 -487.141443) (xy 91.947796 -487.089352)
			(xy 91.975092 -487.040717) (xy 92.009178 -486.996574) (xy 92.049327 -486.957865) (xy 92.094685 -486.925414)
			(xy 92.144285 -486.899913) (xy 92.197069 -486.881906) (xy 92.251912 -486.871776) (xy 92.307646 -486.869739)
			(xy 92.363083 -486.875839) (xy 92.41704 -486.889945) (xy 92.468369 -486.911757) (xy 92.515975 -486.940811)
			(xy 92.558843 -486.976486) (xy 92.565839 -486.984294) (xy 95.986344 -486.984294) (xy 95.990415 -486.928672)
			(xy 96.002541 -486.874235) (xy 96.022464 -486.822144) (xy 96.04976 -486.773509) (xy 96.083846 -486.729366)
			(xy 96.123995 -486.690657) (xy 96.169353 -486.658206) (xy 96.218953 -486.632705) (xy 96.271737 -486.614698)
			(xy 96.32658 -486.604568) (xy 96.382314 -486.602531) (xy 96.437751 -486.608631) (xy 96.491708 -486.622737)
			(xy 96.543037 -486.644549) (xy 96.590643 -486.673603) (xy 96.633511 -486.709278) (xy 96.670728 -486.750815)
			(xy 96.701501 -486.797328) (xy 96.725173 -486.847825) (xy 96.741241 -486.901232) (xy 96.749361 -486.956408)
			(xy 96.74987 -486.984294) (xy 96.749361 -487.01218) (xy 96.741241 -487.067356) (xy 96.725173 -487.120763)
			(xy 96.701501 -487.17126) (xy 96.670728 -487.217773) (xy 96.633511 -487.25931) (xy 96.590643 -487.294985)
			(xy 96.543037 -487.324039) (xy 96.491708 -487.345851) (xy 96.437751 -487.359957) (xy 96.382314 -487.366057)
			(xy 96.32658 -487.36402) (xy 96.271737 -487.35389) (xy 96.218953 -487.335883) (xy 96.169353 -487.310382)
			(xy 96.123995 -487.277931) (xy 96.083846 -487.239222) (xy 96.04976 -487.195079) (xy 96.022464 -487.146444)
			(xy 96.002541 -487.094353) (xy 95.990415 -487.039916) (xy 95.986344 -486.984294) (xy 92.565839 -486.984294)
			(xy 92.59606 -487.018023) (xy 92.626833 -487.064536) (xy 92.650505 -487.115033) (xy 92.666573 -487.16844)
			(xy 92.674693 -487.223616) (xy 92.675202 -487.251502) (xy 92.674693 -487.279388) (xy 92.666573 -487.334564)
			(xy 92.650505 -487.387971) (xy 92.626833 -487.438468) (xy 92.59606 -487.484981) (xy 92.593604 -487.487722)
			(xy 94.810832 -487.487722) (xy 94.814903 -487.4321) (xy 94.827029 -487.377663) (xy 94.846952 -487.325572)
			(xy 94.874248 -487.276937) (xy 94.908334 -487.232794) (xy 94.948483 -487.194085) (xy 94.993841 -487.161634)
			(xy 95.043441 -487.136133) (xy 95.096225 -487.118126) (xy 95.151068 -487.107996) (xy 95.206802 -487.105959)
			(xy 95.262239 -487.112059) (xy 95.316196 -487.126165) (xy 95.367525 -487.147977) (xy 95.415131 -487.177031)
			(xy 95.457999 -487.212706) (xy 95.495216 -487.254243) (xy 95.525989 -487.300756) (xy 95.549661 -487.351253)
			(xy 95.565729 -487.40466) (xy 95.573849 -487.459836) (xy 95.574358 -487.487722) (xy 95.573849 -487.515608)
			(xy 95.565729 -487.570784) (xy 95.549661 -487.624191) (xy 95.525989 -487.674688) (xy 95.495216 -487.721201)
			(xy 95.457999 -487.762738) (xy 95.415131 -487.798413) (xy 95.367525 -487.827467) (xy 95.316196 -487.849279)
			(xy 95.262239 -487.863385) (xy 95.206802 -487.869485) (xy 95.151068 -487.867448) (xy 95.096225 -487.857318)
			(xy 95.043441 -487.839311) (xy 94.993841 -487.81381) (xy 94.948483 -487.781359) (xy 94.908334 -487.74265)
			(xy 94.874248 -487.698507) (xy 94.846952 -487.649872) (xy 94.827029 -487.597781) (xy 94.814903 -487.543344)
			(xy 94.810832 -487.487722) (xy 92.593604 -487.487722) (xy 92.558843 -487.526518) (xy 92.515975 -487.562193)
			(xy 92.468369 -487.591247) (xy 92.41704 -487.613059) (xy 92.363083 -487.627165) (xy 92.307646 -487.633265)
			(xy 92.251912 -487.631228) (xy 92.197069 -487.621098) (xy 92.144285 -487.603091) (xy 92.094685 -487.57759)
			(xy 92.049327 -487.545139) (xy 92.009178 -487.50643) (xy 91.975092 -487.462287) (xy 91.947796 -487.413652)
			(xy 91.927873 -487.361561) (xy 91.915747 -487.307124) (xy 91.911676 -487.251502) (xy 89.753948 -487.251502)
			(xy 90.26017 -487.757724) (xy 90.275886 -487.772806) (xy 90.311483 -487.797903) (xy 90.350838 -487.816562)
			(xy 90.392799 -487.828238) (xy 90.436135 -487.83259) (xy 90.47958 -487.829488) (xy 90.521859 -487.819025)
			(xy 90.561735 -487.801506) (xy 90.59804 -487.777445) (xy 90.629711 -487.747546) (xy 90.655821 -487.712685)
			(xy 90.666062 -487.693462) (xy 90.677864 -487.668923) (xy 90.707391 -487.623175) (xy 90.743122 -487.582089)
			(xy 90.784331 -487.5465) (xy 90.830181 -487.517131) (xy 90.87974 -487.494578) (xy 90.932002 -487.4793)
			(xy 90.985905 -487.471606) (xy 91.040355 -487.471653) (xy 91.094244 -487.47944) (xy 91.14648 -487.494809)
			(xy 91.196 -487.517448) (xy 91.241799 -487.546896) (xy 91.282946 -487.582557) (xy 91.318606 -487.623704)
			(xy 91.348054 -487.669503) (xy 91.370692 -487.719024) (xy 91.386061 -487.771259) (xy 91.393847 -487.825149)
			(xy 91.393894 -487.879599) (xy 91.3862 -487.933502) (xy 91.37092 -487.985764) (xy 91.348367 -488.035323)
			(xy 91.318997 -488.081172) (xy 91.283408 -488.122381) (xy 91.267828 -488.13593) (xy 93.533974 -488.13593)
			(xy 93.538045 -488.080308) (xy 93.550171 -488.025871) (xy 93.570094 -487.97378) (xy 93.59739 -487.925145)
			(xy 93.631476 -487.881002) (xy 93.671625 -487.842293) (xy 93.716983 -487.809842) (xy 93.766583 -487.784341)
			(xy 93.819367 -487.766334) (xy 93.87421 -487.756204) (xy 93.929944 -487.754167) (xy 93.985381 -487.760267)
			(xy 94.039338 -487.774373) (xy 94.090667 -487.796185) (xy 94.138273 -487.825239) (xy 94.181141 -487.860914)
			(xy 94.218358 -487.902451) (xy 94.249131 -487.948964) (xy 94.272803 -487.999461) (xy 94.288871 -488.052868)
			(xy 94.296991 -488.108044) (xy 94.2975 -488.13593) (xy 94.296991 -488.163816) (xy 94.288871 -488.218992)
			(xy 94.272803 -488.272399) (xy 94.249131 -488.322896) (xy 94.218358 -488.369409) (xy 94.181141 -488.410946)
			(xy 94.138273 -488.446621) (xy 94.090667 -488.475675) (xy 94.039338 -488.497487) (xy 93.985381 -488.511593)
			(xy 93.929944 -488.517693) (xy 93.87421 -488.515656) (xy 93.819367 -488.505526) (xy 93.766583 -488.487519)
			(xy 93.716983 -488.462018) (xy 93.671625 -488.429567) (xy 93.631476 -488.390858) (xy 93.59739 -488.346715)
			(xy 93.570094 -488.29808) (xy 93.550171 -488.245989) (xy 93.538045 -488.191552) (xy 93.533974 -488.13593)
			(xy 91.267828 -488.13593) (xy 91.242322 -488.158111) (xy 91.196573 -488.187638) (xy 91.17203 -488.19943)
			(xy 91.15283 -488.209714) (xy 91.117964 -488.235813) (xy 91.088059 -488.267475) (xy 91.063993 -488.303774)
			(xy 91.04647 -488.343646) (xy 91.036004 -488.385922) (xy 91.032902 -488.429363) (xy 91.037254 -488.472697)
			(xy 91.048933 -488.514655) (xy 91.067596 -488.554005) (xy 91.070827 -488.558586) (xy 91.924376 -488.558586)
			(xy 91.928447 -488.502964) (xy 91.940573 -488.448527) (xy 91.960496 -488.396436) (xy 91.987792 -488.347801)
			(xy 92.021878 -488.303658) (xy 92.062027 -488.264949) (xy 92.107385 -488.232498) (xy 92.156985 -488.206997)
			(xy 92.209769 -488.18899) (xy 92.264612 -488.17886) (xy 92.320346 -488.176823) (xy 92.375783 -488.182923)
			(xy 92.42974 -488.197029) (xy 92.481069 -488.218841) (xy 92.528675 -488.247895) (xy 92.571543 -488.28357)
			(xy 92.60876 -488.325107) (xy 92.639533 -488.37162) (xy 92.663205 -488.422117) (xy 92.679273 -488.475524)
			(xy 92.687393 -488.5307) (xy 92.687902 -488.558586) (xy 92.687393 -488.586472) (xy 92.679273 -488.641648)
			(xy 92.663205 -488.695055) (xy 92.639533 -488.745552) (xy 92.60876 -488.792065) (xy 92.571543 -488.833602)
			(xy 92.528675 -488.869277) (xy 92.481069 -488.898331) (xy 92.42974 -488.920143) (xy 92.375783 -488.934249)
			(xy 92.320346 -488.940349) (xy 92.264612 -488.938312) (xy 92.209769 -488.928182) (xy 92.156985 -488.910175)
			(xy 92.107385 -488.884674) (xy 92.062027 -488.852223) (xy 92.021878 -488.813514) (xy 91.987792 -488.769371)
			(xy 91.960496 -488.720736) (xy 91.940573 -488.668645) (xy 91.928447 -488.614208) (xy 91.924376 -488.558586)
			(xy 91.070827 -488.558586) (xy 91.092698 -488.589596) (xy 91.107768 -488.605322) (xy 91.32062 -488.818174)
			(xy 93.012768 -490.510576) (xy 93.012768 -492.874554) (xy 93.265752 -493.127538) (xy 93.265752 -495.798094)
			(xy 93.266912 -495.820455) (xy 93.276107 -495.864272) (xy 93.292839 -495.905799) (xy 93.316589 -495.943751)
			(xy 93.346623 -495.976954) (xy 93.382012 -496.00438) (xy 93.421658 -496.025179) (xy 93.464337 -496.038708)
			(xy 93.508725 -496.044549) (xy 93.553451 -496.04252) (xy 93.597128 -496.032684) (xy 93.638406 -496.015346)
			(xy 93.676007 -495.991042) (xy 93.692726 -495.976148) (xy 93.735559 -495.937009) (xy 93.825783 -495.86404)
			(xy 93.920815 -495.797452) (xy 94.020203 -495.737562) (xy 94.123477 -495.684653) (xy 94.230147 -495.638976)
			(xy 94.339708 -495.600747) (xy 94.45164 -495.570149) (xy 94.565411 -495.547326) (xy 94.680484 -495.532385)
			(xy 94.796312 -495.525399) (xy 94.912346 -495.5264) (xy 95.028036 -495.535384) (xy 95.142834 -495.552307)
			(xy 95.256195 -495.57709) (xy 95.367582 -495.609614) (xy 95.476467 -495.649727) (xy 95.582333 -495.697238)
			(xy 95.684679 -495.751921) (xy 95.78302 -495.813517) (xy 95.876888 -495.881734) (xy 95.96584 -495.956249)
			(xy 96.049454 -496.036709) (xy 96.127332 -496.122732) (xy 96.199106 -496.21391) (xy 96.264436 -496.30981)
			(xy 96.323011 -496.409979) (xy 96.374555 -496.513942) (xy 96.418822 -496.621205) (xy 96.455603 -496.73126)
			(xy 96.484724 -496.843585) (xy 96.506046 -496.957647) (xy 96.519468 -497.072907) (xy 96.524928 -497.188817)
			(xy 96.522398 -497.304828) (xy 96.51189 -497.42039) (xy 96.493456 -497.534955) (xy 96.467181 -497.647979)
			(xy 96.433191 -497.758928) (xy 96.391647 -497.867275) (xy 96.342746 -497.972506) (xy 96.286719 -498.074122)
			(xy 96.223832 -498.171642) (xy 96.154383 -498.264604) (xy 96.078703 -498.352566) (xy 95.997148 -498.435112)
			(xy 95.910107 -498.51185) (xy 95.817991 -498.582416) (xy 95.721237 -498.646476) (xy 95.620305 -498.703726)
			(xy 95.515672 -498.753896) (xy 95.407835 -498.796745) (xy 95.297305 -498.832073) (xy 95.184606 -498.859711)
			(xy 95.070273 -498.879528) (xy 94.954846 -498.891431) (xy 94.838874 -498.895362) (xy 94.722907 -498.891303)
			(xy 94.607493 -498.879274) (xy 94.493182 -498.859331) (xy 94.380513 -498.83157) (xy 94.270022 -498.79612)
			(xy 94.162232 -498.753152) (xy 94.057654 -498.702868) (xy 93.956785 -498.645507) (xy 93.860102 -498.58134)
			(xy 93.768064 -498.510673) (xy 93.681107 -498.433839) (xy 93.599643 -498.351204) (xy 93.524059 -498.263159)
			(xy 93.454713 -498.170121) (xy 93.391933 -498.072532) (xy 93.336018 -497.970854) (xy 93.287232 -497.865569)
			(xy 93.245807 -497.757177) (xy 93.228414 -497.701824) (xy 93.221621 -497.681096) (xy 93.201961 -497.642163)
			(xy 93.175941 -497.60716) (xy 93.144325 -497.577115) (xy 93.108043 -497.55291) (xy 93.068159 -497.535258)
			(xy 93.025847 -497.524677) (xy 92.982349 -497.521477) (xy 92.938944 -497.525753) (xy 92.896907 -497.537379)
			(xy 92.857473 -497.556013) (xy 92.821801 -497.581109) (xy 92.806012 -497.59616) (xy 92.628974 -497.773198)
			(xy 91.221306 -499.180612) (xy 86.606126 -499.180612) (xy 85.91804 -498.49278) (xy 85.906338 -498.481709)
			(xy 85.878611 -498.465326) (xy 85.847661 -498.456422) (xy 85.815468 -498.455564) (xy 85.799676 -498.458744)
			(xy 85.762925 -498.46672) (xy 85.68827 -498.475802) (xy 85.613072 -498.476962) (xy 85.538172 -498.470187)
			(xy 85.464404 -498.455552) (xy 85.39259 -498.43322) (xy 85.323531 -498.403441) (xy 85.257996 -498.366546)
			(xy 85.196718 -498.322947) (xy 85.140378 -498.273129) (xy 85.089605 -498.217649) (xy 85.044965 -498.157124)
			(xy 85.006955 -498.09223) (xy 84.976 -498.02369) (xy 84.952444 -497.952268) (xy 84.936551 -497.878761)
			(xy 84.928497 -497.803987) (xy 84.928371 -497.728781) (xy 84.936177 -497.653981) (xy 84.951825 -497.580421)
			(xy 84.975143 -497.508921) (xy 85.00587 -497.440278) (xy 85.043663 -497.375258) (xy 85.088102 -497.314585)
			(xy 85.13869 -497.258936) (xy 85.194863 -497.208931) (xy 85.255996 -497.165128) (xy 85.321407 -497.128015)
			(xy 85.355684 -497.112544) (xy 85.376099 -497.103121) (xy 85.413511 -497.078186) (xy 85.445951 -497.047056)
			(xy 85.472407 -497.010704) (xy 85.492054 -496.970264) (xy 85.504279 -496.926998) (xy 85.508699 -496.882256)
			(xy 85.505178 -496.837434) (xy 85.493825 -496.793931) (xy 85.474994 -496.753105) (xy 85.449273 -496.716229)
			(xy 85.433662 -496.700048) (xy 85.285834 -496.55222) (xy 84.111592 -495.377724) (xy 84.111592 -489.617258)
			(xy 84.09559 -489.588556) (xy 84.082676 -489.564216) (xy 84.063214 -489.512667) (xy 84.051372 -489.458855)
			(xy 84.047398 -489.403898) (xy 84.051373 -489.348942) (xy 84.063215 -489.295129) (xy 84.082677 -489.243581)
			(xy 84.09559 -489.21924) (xy 84.111592 -489.190538) (xy 84.111592 -487.173524) (xy 83.115404 -486.177336)
			(xy 83.115404 -467.86673) (xy 72.376538 -457.127864) (xy 40.36441 -457.127864) (xy 37.26688 -454.030334)
			(xy 37.26688 -447.399918) (xy 37.266361 -447.383274) (xy 37.257697 -447.351133) (xy 37.241006 -447.322331)
			(xy 37.229542 -447.310256) (xy 36.811966 -446.89268) (xy 36.795775 -446.877174) (xy 36.758998 -446.851544)
			(xy 36.718297 -446.832762) (xy 36.674931 -446.821411) (xy 36.630247 -446.817842) (xy 36.58563 -446.822166)
			(xy 36.542463 -446.834249) (xy 36.502084 -446.853717) (xy 36.465747 -446.879965) (xy 36.434577 -446.91218)
			(xy 36.40954 -446.949364) (xy 36.399978 -446.969642) (xy 36.382261 -447.008579) (xy 36.340747 -447.083382)
			(xy 36.29261 -447.154104) (xy 36.238248 -447.220162) (xy 36.178111 -447.281009) (xy 36.112695 -447.336142)
			(xy 36.042541 -447.385105) (xy 35.96823 -447.427493) (xy 35.890376 -447.462956) (xy 35.809622 -447.4912)
			(xy 35.726637 -447.511993) (xy 35.642106 -447.525161) (xy 35.556729 -447.530597) (xy 35.47121 -447.528255)
			(xy 35.386258 -447.518154) (xy 35.302575 -447.500379) (xy 35.220852 -447.475076) (xy 35.141765 -447.442454)
			(xy 35.065969 -447.402783) (xy 34.994089 -447.356391) (xy 34.92672 -447.303662) (xy 34.86442 -447.245032)
			(xy 34.807703 -447.180984) (xy 34.757038 -447.11205) (xy 34.712844 -447.038798) (xy 34.675487 -446.961835)
			(xy 34.645275 -446.881797) (xy 34.622458 -446.799346) (xy 34.607225 -446.715162) (xy 34.599702 -446.629943)
			(xy 34.59995 -446.544393) (xy 34.607969 -446.459219) (xy 34.623691 -446.375126) (xy 34.646987 -446.292808)
			(xy 34.677664 -446.212947) (xy 34.696146 -446.174368) (xy 34.705893 -446.153438) (xy 34.718478 -446.109021)
			(xy 34.722836 -446.063062) (xy 34.718825 -446.017071) (xy 34.706576 -445.97256) (xy 34.686491 -445.930992)
			(xy 34.659232 -445.893734) (xy 34.625694 -445.862009) (xy 34.586978 -445.836862) (xy 34.544359 -445.819118)
			(xy 34.499237 -445.809361) (xy 34.476182 -445.8081) (xy 31.523178 -445.8081) (xy 31.500114 -445.809316)
			(xy 31.454971 -445.819054) (xy 31.412331 -445.836787) (xy 31.373596 -445.861933) (xy 31.340041 -445.893662)
			(xy 31.312771 -445.930931) (xy 31.292682 -445.972514) (xy 31.280437 -446.017042) (xy 31.276438 -446.06305)
			(xy 31.280816 -446.109023) (xy 31.293428 -446.153448) (xy 31.303214 -446.174368) (xy 31.322101 -446.213841)
			(xy 31.353312 -446.295597) (xy 31.376791 -446.3799) (xy 31.392336 -446.466019) (xy 31.399812 -446.55321)
			(xy 31.399154 -446.640719) (xy 31.390368 -446.727788) (xy 31.37353 -446.813664) (xy 31.348786 -446.897604)
			(xy 31.31635 -446.978882) (xy 31.276502 -447.056795) (xy 31.229587 -447.130668) (xy 31.176012 -447.199862)
			(xy 31.116239 -447.263779) (xy 31.050785 -447.321866) (xy 30.980218 -447.37362) (xy 30.905148 -447.418593)
			(xy 30.826223 -447.456397) (xy 30.744127 -447.486704) (xy 30.659571 -447.509252) (xy 30.573285 -447.523846)
			(xy 30.486017 -447.530359) (xy 30.39852 -447.528736) (xy 30.311554 -447.51899) (xy 30.225869 -447.501206)
			(xy 30.142207 -447.475538) (xy 30.061291 -447.442207) (xy 29.983823 -447.401502) (xy 29.910472 -447.353775)
			(xy 29.841873 -447.299439) (xy 29.778619 -447.238965) (xy 29.721258 -447.172875) (xy 29.670286 -447.101741)
			(xy 29.626143 -447.026179) (xy 29.589212 -446.946842) (xy 29.559813 -446.864417) (xy 29.538199 -446.779617)
			(xy 29.524558 -446.693175) (xy 29.519008 -446.60584) (xy 29.521596 -446.518367) (xy 29.5323 -446.431513)
			(xy 29.551029 -446.34603) (xy 29.577619 -446.262656) (xy 29.61184 -446.182113) (xy 29.653397 -446.105099)
			(xy 29.70193 -446.032279) (xy 29.757019 -445.964283) (xy 29.818188 -445.901701) (xy 29.884907 -445.845072)
			(xy 29.920438 -445.81953) (xy 29.938333 -445.806418) (xy 29.969709 -445.775063) (xy 29.995164 -445.738737)
			(xy 30.013926 -445.698542) (xy 30.025424 -445.655701) (xy 30.02931 -445.611513) (xy 30.025464 -445.567323)
			(xy 30.014004 -445.524471) (xy 29.995278 -445.48426) (xy 29.969855 -445.447911) (xy 29.954474 -445.431926)
			(xy 23.188168 -438.66562) (xy 23.188168 -380.801118) (xy 22.662896 -380.275846) (xy 22.646194 -380.260935)
			(xy 22.608596 -380.236632) (xy 22.567323 -380.219289) (xy 22.52365 -380.209442) (xy 22.478928 -380.207397)
			(xy 22.434539 -380.213216) (xy 22.391855 -380.226719) (xy 22.352195 -380.247488) (xy 22.316786 -380.274883)
			(xy 22.286723 -380.308056) (xy 22.262934 -380.345981) (xy 22.246154 -380.387487) (xy 22.236903 -380.43129)
			(xy 22.235668 -380.453646) (xy 22.235668 -426.151802) (xy 12.453874 -435.93385) (xy 12.439396 -436.01132)
			(xy 12.455398 -436.047134) (xy 12.474005 -436.090467) (xy 12.504634 -436.179668) (xy 12.527552 -436.271154)
			(xy 12.542592 -436.36426) (xy 12.549645 -436.458309) (xy 12.54866 -436.552617) (xy 12.539643 -436.646498)
			(xy 12.522661 -436.73927) (xy 12.497837 -436.830257) (xy 12.465352 -436.918799) (xy 12.425441 -437.004251)
			(xy 12.378395 -437.085993) (xy 12.324556 -437.163428) (xy 12.264315 -437.235996) (xy 12.198111 -437.303167)
			(xy 12.126425 -437.364454) (xy 12.049778 -437.41941) (xy 11.968728 -437.467637) (xy 11.883863 -437.508783)
			(xy 11.795802 -437.542549) (xy 11.705184 -437.56869) (xy 11.612668 -437.587015) (xy 11.518928 -437.597392)
			(xy 11.424644 -437.599745) (xy 11.330503 -437.594057) (xy 11.237188 -437.580368) (xy 11.14538 -437.55878)
			(xy 11.055744 -437.529448) (xy 10.968933 -437.492586) (xy 10.885578 -437.448462) (xy 10.806285 -437.397397)
			(xy 10.731631 -437.339762) (xy 10.662159 -437.275977) (xy 10.598374 -437.206505) (xy 10.54074 -437.131851)
			(xy 10.489675 -437.052558) (xy 10.445552 -436.969203) (xy 10.40869 -436.882391) (xy 10.379359 -436.792755)
			(xy 10.357771 -436.700946) (xy 10.344083 -436.607632) (xy 10.338395 -436.51349) (xy 10.340748 -436.419207)
			(xy 10.351126 -436.325466) (xy 10.369452 -436.232951) (xy 10.395593 -436.142333) (xy 10.42936 -436.054272)
			(xy 10.470506 -435.969408) (xy 10.518733 -435.888358) (xy 10.57369 -435.811711) (xy 10.634977 -435.740025)
			(xy 10.702148 -435.673822) (xy 10.774716 -435.613581) (xy 10.852152 -435.559743) (xy 10.933893 -435.512697)
			(xy 11.019346 -435.472786) (xy 11.107888 -435.440301) (xy 11.198875 -435.415478) (xy 11.291647 -435.398496)
			(xy 11.385528 -435.38948) (xy 11.479836 -435.388495) (xy 11.573885 -435.395549) (xy 11.666991 -435.410589)
			(xy 11.758477 -435.433508) (xy 11.847678 -435.464137) (xy 11.89101 -435.482746) (xy 11.926824 -435.498748)
			(xy 12.004294 -435.48427) (xy 21.567394 -425.92117) (xy 21.576921 -425.910048) (xy 21.591118 -425.884442)
			(xy 21.599103 -425.856274) (xy 21.60016 -425.841668) (xy 21.60016 -387.588506) (xy 21.599031 -387.566712)
			(xy 21.590246 -387.523968) (xy 21.574291 -387.483353) (xy 21.551633 -387.446059) (xy 21.522939 -387.413183)
			(xy 21.489051 -387.385691) (xy 21.450967 -387.364389) (xy 21.409803 -387.349905) (xy 21.366771 -387.342664)
			(xy 21.323135 -387.342879) (xy 21.280176 -387.350543) (xy 21.239157 -387.365431) (xy 21.201284 -387.387105)
			(xy 21.167668 -387.41493) (xy 21.139299 -387.448087) (xy 21.12772 -387.466586) (xy 21.091967 -387.526945)
			(xy 21.017661 -387.64596) (xy 20.97913 -387.704584) (xy 20.922475 -387.789104) (xy 20.803503 -387.954206)
			(xy 20.678228 -388.114577) (xy 20.546837 -388.269979) (xy 20.409529 -388.420176) (xy 20.266509 -388.564945)
			(xy 20.117991 -388.704069) (xy 19.964198 -388.837338) (xy 19.80536 -388.964552) (xy 19.641717 -389.085522)
			(xy 19.473512 -389.200066) (xy 19.300999 -389.308011) (xy 19.124436 -389.409196) (xy 18.944088 -389.50347)
			(xy 18.760226 -389.590691) (xy 18.573124 -389.670727) (xy 18.383064 -389.74346) (xy 18.19033 -389.80878)
			(xy 17.995212 -389.866589) (xy 17.798003 -389.916801) (xy 17.598997 -389.959339) (xy 17.398493 -389.994141)
			(xy 17.196792 -390.021155) (xy 16.994197 -390.040338) (xy 16.79101 -390.051664) (xy 16.587538 -390.055115)
			(xy 16.384085 -390.050685) (xy 16.180955 -390.038382) (xy 15.978455 -390.018224) (xy 15.776886 -389.99024)
			(xy 15.576552 -389.954474) (xy 15.377753 -389.910979) (xy 15.180787 -389.859819) (xy 14.985949 -389.801072)
			(xy 14.793532 -389.734825) (xy 14.603824 -389.661179) (xy 14.41711 -389.580243) (xy 14.233669 -389.492139)
			(xy 14.053777 -389.396998) (xy 13.877703 -389.294965) (xy 13.705711 -389.186191) (xy 13.53806 -389.070839)
			(xy 13.375 -388.949084) (xy 13.216777 -388.821106) (xy 13.063626 -388.687099) (xy 12.915779 -388.547263)
			(xy 12.773457 -388.401807) (xy 12.636873 -388.250951) (xy 12.506232 -388.094919) (xy 12.38173 -387.933947)
			(xy 12.263553 -387.768275) (xy 12.151879 -387.598152) (xy 12.046876 -387.423832) (xy 11.9487 -387.245579)
			(xy 11.857499 -387.063658) (xy 11.77341 -386.878342) (xy 11.696558 -386.68991) (xy 11.627059 -386.498643)
			(xy 11.565018 -386.304829) (xy 11.510527 -386.108759) (xy 11.463668 -385.910726) (xy 11.424511 -385.711027)
			(xy 11.393115 -385.509962) (xy 11.369527 -385.307832) (xy 11.353782 -385.10494) (xy 11.345904 -384.901591)
			(xy 11.345418 -384.79984) (xy 11.345925 -384.69666) (xy 11.354026 -384.490459) (xy 11.370217 -384.284735)
			(xy 11.394472 -384.079805) (xy 11.426754 -383.875985) (xy 11.467013 -383.67359) (xy 11.515187 -383.472931)
			(xy 11.571201 -383.274319) (xy 11.63497 -383.078059) (xy 11.706395 -382.884453) (xy 11.785365 -382.693801)
			(xy 11.87176 -382.506397) (xy 11.965446 -382.322528) (xy 12.066278 -382.14248) (xy 12.174101 -381.966529)
			(xy 12.288748 -381.794946) (xy 12.410044 -381.627998) (xy 12.5378 -381.465939) (xy 12.671821 -381.309022)
			(xy 12.811898 -381.157487) (xy 12.957817 -381.011568) (xy 13.109352 -380.871491) (xy 13.266269 -380.73747)
			(xy 13.428328 -380.609714) (xy 13.595276 -380.488418) (xy 13.766859 -380.373771) (xy 13.94281 -380.265948)
			(xy 14.122858 -380.165116) (xy 14.306727 -380.07143) (xy 14.494131 -379.985035) (xy 14.684783 -379.906065)
			(xy 14.878389 -379.83464) (xy 15.074649 -379.770871) (xy 15.273261 -379.714857) (xy 15.47392 -379.666683)
			(xy 15.676315 -379.626424) (xy 15.880135 -379.594142) (xy 16.085065 -379.569887) (xy 16.290789 -379.553696)
			(xy 16.49699 -379.545595) (xy 16.60017 -379.545088) (xy 16.700652 -379.545574) (xy 16.90147 -379.553273)
			(xy 17.101846 -379.568643) (xy 17.301489 -379.591663) (xy 17.500105 -379.622298) (xy 17.697405 -379.660505)
			(xy 17.8931 -379.706226) (xy 18.086903 -379.759396) (xy 18.278533 -379.819936) (xy 18.467708 -379.887758)
			(xy 18.654151 -379.962763) (xy 18.837591 -380.044841) (xy 19.017758 -380.133872) (xy 19.194391 -380.229727)
			(xy 19.367229 -380.332264) (xy 19.536021 -380.441333) (xy 19.700519 -380.556777) (xy 19.860484 -380.678424)
			(xy 20.015681 -380.806099) (xy 20.165884 -380.939614) (xy 20.310872 -381.078773) (xy 20.450434 -381.223374)
			(xy 20.584366 -381.373204) (xy 20.712472 -381.528046) (xy 20.773898 -381.607568) (xy 20.837861 -381.692049)
			(xy 20.959737 -381.865424) (xy 21.074523 -382.043572) (xy 21.128736 -382.134618) (xy 21.14124 -382.154295)
			(xy 21.17222 -382.189128) (xy 21.209031 -382.21773) (xy 21.25044 -382.239141) (xy 21.295058 -382.252645)
			(xy 21.341389 -382.257788) (xy 21.387883 -382.254399) (xy 21.432979 -382.24259) (xy 21.475166 -382.222759)
			(xy 21.513032 -382.195568) (xy 21.545305 -382.16193) (xy 21.570906 -382.122973) (xy 21.588976 -382.08)
			(xy 21.598908 -382.034454) (xy 21.60016 -382.011174) (xy 21.60016 -379.710188) (xy 12.1666 -370.276628)
			(xy 12.1666 -342.66505) (xy 12.16541 -342.64269) (xy 12.156158 -342.598883) (xy 12.139377 -342.557373)
			(xy 12.115585 -342.519444) (xy 12.085517 -342.486269) (xy 12.050104 -342.458872) (xy 12.01044 -342.438102)
			(xy 11.967751 -342.4246) (xy 11.923357 -342.418783) (xy 11.87863 -342.420832) (xy 11.834954 -342.430683)
			(xy 11.793678 -342.448031) (xy 11.756078 -342.47234) (xy 11.739372 -342.48725) (xy 11.57859 -342.648032)
			(xy 8.846312 -342.648032) (xy 8.751824 -342.74252) (xy 8.73631 -342.758713) (xy 8.710665 -342.795496)
			(xy 8.691871 -342.836209) (xy 8.680513 -342.879587) (xy 8.676942 -342.924285) (xy 8.681269 -342.968917)
			(xy 8.69336 -343.012096) (xy 8.71284 -343.052485) (xy 8.739105 -343.088829) (xy 8.771339 -343.12)
			(xy 8.78967 -343.132918) (xy 8.81948 -343.152373) (xy 8.875 -343.196929) (xy 8.925193 -343.24741)
			(xy 8.969429 -343.303185) (xy 9.007155 -343.363554) (xy 9.037897 -343.427761) (xy 9.061272 -343.495002)
			(xy 9.076984 -343.564434) (xy 9.084839 -343.635187) (xy 9.084737 -343.706374) (xy 9.076679 -343.777104)
			(xy 9.060768 -343.846491) (xy 9.037201 -343.913664) (xy 9.006274 -343.977783) (xy 8.968376 -344.038044)
			(xy 8.92398 -344.093691) (xy 8.873643 -344.144028) (xy 8.817995 -344.188425) (xy 8.757734 -344.226324)
			(xy 8.693616 -344.25725) (xy 8.626442 -344.280817) (xy 8.557056 -344.296729) (xy 8.486326 -344.304787)
			(xy 8.415138 -344.304889) (xy 8.344386 -344.297035) (xy 8.274954 -344.281322) (xy 8.207713 -344.257948)
			(xy 8.143506 -344.227206) (xy 8.083136 -344.18948) (xy 8.027361 -344.145244) (xy 7.97688 -344.095052)
			(xy 7.932324 -344.039532) (xy 7.912862 -344.009726) (xy 7.899957 -343.991382) (xy 7.868792 -343.959133)
			(xy 7.83245 -343.932855) (xy 7.792059 -343.913366) (xy 7.748873 -343.90127) (xy 7.704235 -343.896943)
			(xy 7.659531 -343.90052) (xy 7.616149 -343.911889) (xy 7.575436 -343.930698) (xy 7.538658 -343.956362)
			(xy 7.522464 -343.97188) (xy 7.342124 -344.15222) (xy 7.299198 -344.15222) (xy 7.275721 -344.152761)
			(xy 7.229567 -344.161386) (xy 7.185782 -344.178343) (xy 7.145857 -344.203053) (xy 7.111151 -344.234677)
			(xy 7.082844 -344.272138) (xy 7.0619 -344.314162) (xy 7.049031 -344.359317) (xy 7.044676 -344.406068)
			(xy 7.048983 -344.452823) (xy 7.05485 -344.475562) (xy 7.065156 -344.509198) (xy 7.079138 -344.578147)
			(xy 7.085418 -344.648218) (xy 7.083921 -344.718555) (xy 7.074664 -344.788295) (xy 7.05776 -344.856587)
			(xy 7.033417 -344.922593) (xy 7.001933 -344.985507) (xy 6.963691 -345.044558) (xy 6.919162 -345.099025)
			(xy 6.868888 -345.148239) (xy 6.813487 -345.191599) (xy 6.753635 -345.228575) (xy 6.690065 -345.258714)
			(xy 6.623556 -345.281647) (xy 6.55492 -345.297093) (xy 6.484998 -345.304864) (xy 6.414646 -345.304864)
			(xy 6.344724 -345.297093) (xy 6.276088 -345.281647) (xy 6.209579 -345.258714) (xy 6.146009 -345.228575)
			(xy 6.086157 -345.191599) (xy 6.030756 -345.148239) (xy 5.980482 -345.099025) (xy 5.935953 -345.044558)
			(xy 5.897711 -344.985507) (xy 5.866227 -344.922593) (xy 5.841884 -344.856587) (xy 5.82498 -344.788295)
			(xy 5.815723 -344.718555) (xy 5.814226 -344.648218) (xy 5.820506 -344.578147) (xy 5.834488 -344.509198)
			(xy 5.844794 -344.475562) (xy 5.850683 -344.452829) (xy 5.854986 -344.406071) (xy 5.850628 -344.359319)
			(xy 5.837757 -344.314162) (xy 5.81681 -344.272139) (xy 5.788501 -344.234677) (xy 5.753792 -344.203053)
			(xy 5.713866 -344.178342) (xy 5.670079 -344.161385) (xy 5.623923 -344.152759) (xy 5.600446 -344.15222)
			(xy 4.79933 -344.15222) (xy 4.775851 -344.152758) (xy 4.729692 -344.161379) (xy 4.685902 -344.178333)
			(xy 4.645972 -344.203043) (xy 4.61126 -344.234667) (xy 4.582949 -344.27213) (xy 4.562002 -344.314156)
			(xy 4.549131 -344.359316) (xy 4.544776 -344.406071) (xy 4.549084 -344.45283) (xy 4.554982 -344.475562)
			(xy 4.565336 -344.509401) (xy 4.579348 -344.57877) (xy 4.585569 -344.649265) (xy 4.583921 -344.720015)
			(xy 4.574425 -344.790144) (xy 4.557199 -344.858785) (xy 4.532455 -344.925088) (xy 4.5005 -344.988232)
			(xy 4.46173 -345.047436) (xy 4.416623 -345.101968) (xy 4.365739 -345.151152) (xy 4.309706 -345.19438)
			(xy 4.249219 -345.231117) (xy 4.185026 -345.260909) (xy 4.15163 -345.272614) (xy 4.115828 -345.283996)
			(xy 4.042262 -345.29924) (xy 3.967412 -345.305704) (xy 3.892322 -345.303298) (xy 3.81804 -345.292057)
			(xy 3.7456 -345.272136) (xy 3.676015 -345.243814) (xy 3.642868 -345.226132) (xy 3.611725 -345.208375)
			(xy 3.553262 -345.166878) (xy 3.499841 -345.119065) (xy 3.452141 -345.065544) (xy 3.410767 -345.006994)
			(xy 3.376245 -344.94416) (xy 3.349014 -344.87784) (xy 3.32942 -344.808876) (xy 3.317712 -344.738146)
			(xy 3.314038 -344.666547) (xy 3.318446 -344.59499) (xy 3.330879 -344.524383) (xy 3.35118 -344.455625)
			(xy 3.37909 -344.389588) (xy 3.414254 -344.327111) (xy 3.434842 -344.297762) (xy 3.446018 -344.282268)
			(xy 3.459734 -344.241628) (xy 3.464844 -344.224718) (xy 3.466546 -344.189449) (xy 3.458506 -344.155065)
			(xy 3.441342 -344.124207) (xy 3.429254 -344.111326) (xy 3.305556 -343.987628) (xy 2.56921 -343.987628)
			(xy 2.46761 -344.039952) (xy 2.450338 -344.061796) (xy 2.42779 -344.089784) (xy 2.377371 -344.14101)
			(xy 2.32149 -344.186214) (xy 2.260862 -344.224819) (xy 2.196263 -344.256331) (xy 2.162556 -344.268806)
			(xy 2.130548 -344.279692) (xy 2.064791 -344.295418) (xy 1.997736 -344.304073) (xy 1.93014 -344.305561)
			(xy 1.862769 -344.299865) (xy 1.796384 -344.287049) (xy 1.731734 -344.267258) (xy 1.66955 -344.240715)
			(xy 1.639824 -344.22461) (xy 1.620355 -344.215128) (xy 1.579026 -344.202203) (xy 1.536104 -344.196472)
			(xy 1.492832 -344.198099) (xy 1.450463 -344.207039) (xy 1.410221 -344.223031) (xy 1.373274 -344.245614)
			(xy 1.340689 -344.274134) (xy 1.313411 -344.307764) (xy 1.292228 -344.345532) (xy 1.277755 -344.386344)
			(xy 1.270409 -344.429019) (xy 1.27 -344.45067) (xy 1.27 -344.889074) (xy 1.270438 -344.910724) (xy 1.277779 -344.953398)
			(xy 1.292249 -344.994209) (xy 1.313428 -345.031976) (xy 1.340704 -345.065606) (xy 1.373285 -345.094125)
			(xy 1.410231 -345.116708) (xy 1.450469 -345.132701) (xy 1.492837 -345.14164) (xy 1.536107 -345.143267)
			(xy 1.579026 -345.137535) (xy 1.620352 -345.124609) (xy 1.639824 -345.115134) (xy 1.671264 -345.098114)
			(xy 1.737191 -345.070449) (xy 1.805806 -345.050357) (xy 1.876243 -345.038093) (xy 1.947611 -345.033811)
			(xy 2.019008 -345.037566) (xy 2.089533 -345.049309) (xy 2.158295 -345.068893) (xy 2.224425 -345.096071)
			(xy 2.287086 -345.130498) (xy 2.345488 -345.17174) (xy 2.398893 -345.219276) (xy 2.446626 -345.272504)
			(xy 2.488083 -345.330754) (xy 2.522742 -345.393288) (xy 2.550163 -345.459317) (xy 2.570001 -345.528005)
			(xy 2.582005 -345.598487) (xy 2.586023 -345.66987) (xy 2.584016 -345.705531) (xy 7.81481 -345.705531)
			(xy 7.81481 -345.634209) (xy 7.822796 -345.563335) (xy 7.838666 -345.4938) (xy 7.862223 -345.42648)
			(xy 7.893168 -345.362221) (xy 7.931114 -345.30183) (xy 7.975583 -345.246068) (xy 8.026016 -345.195635)
			(xy 8.081778 -345.151166) (xy 8.142169 -345.11322) (xy 8.206428 -345.082275) (xy 8.273748 -345.058718)
			(xy 8.343283 -345.042848) (xy 8.414157 -345.034862) (xy 8.485479 -345.034862) (xy 8.556353 -345.042848)
			(xy 8.625888 -345.058718) (xy 8.693208 -345.082275) (xy 8.757467 -345.11322) (xy 8.817858 -345.151166)
			(xy 8.87362 -345.195635) (xy 8.924053 -345.246068) (xy 8.968522 -345.30183) (xy 9.006468 -345.362221)
			(xy 9.037413 -345.42648) (xy 9.06097 -345.4938) (xy 9.07684 -345.563335) (xy 9.084826 -345.634209)
			(xy 9.085326 -345.66987) (xy 9.084826 -345.705531) (xy 9.07684 -345.776405) (xy 9.06097 -345.84594)
			(xy 9.037413 -345.91326) (xy 9.006468 -345.977519) (xy 8.968522 -346.03791) (xy 8.924053 -346.093672)
			(xy 8.87362 -346.144105) (xy 8.817858 -346.188574) (xy 8.757467 -346.22652) (xy 8.693208 -346.257465)
			(xy 8.625888 -346.281022) (xy 8.556353 -346.296892) (xy 8.485479 -346.304878) (xy 8.414157 -346.304878)
			(xy 8.343283 -346.296892) (xy 8.273748 -346.281022) (xy 8.206428 -346.257465) (xy 8.142169 -346.22652)
			(xy 8.081778 -346.188574) (xy 8.026016 -346.144105) (xy 7.975583 -346.093672) (xy 7.931114 -346.03791)
			(xy 7.893168 -345.977519) (xy 7.862223 -345.91326) (xy 7.838666 -345.84594) (xy 7.822796 -345.776405)
			(xy 7.81481 -345.705531) (xy 2.584016 -345.705531) (xy 2.582005 -345.741253) (xy 2.570001 -345.811735)
			(xy 2.550163 -345.880423) (xy 2.522742 -345.946452) (xy 2.488083 -346.008986) (xy 2.446626 -346.067236)
			(xy 2.398893 -346.120464) (xy 2.345488 -346.168) (xy 2.287086 -346.209242) (xy 2.224425 -346.243669)
			(xy 2.158295 -346.270847) (xy 2.089533 -346.290431) (xy 2.019008 -346.302174) (xy 1.947611 -346.305929)
			(xy 1.876243 -346.301647) (xy 1.805806 -346.289383) (xy 1.737191 -346.269291) (xy 1.671264 -346.241626)
			(xy 1.639824 -346.224606) (xy 1.620355 -346.215124) (xy 1.579026 -346.202199) (xy 1.536104 -346.196468)
			(xy 1.492832 -346.198096) (xy 1.450462 -346.207035) (xy 1.410221 -346.223028) (xy 1.373273 -346.245611)
			(xy 1.340688 -346.27413) (xy 1.313409 -346.30776) (xy 1.292226 -346.345528) (xy 1.277752 -346.38634)
			(xy 1.270406 -346.429015) (xy 1.27 -346.450666) (xy 1.27 -346.705529) (xy 3.314946 -346.705529) (xy 3.314946 -346.634207)
			(xy 3.322932 -346.563333) (xy 3.338802 -346.493798) (xy 3.362359 -346.426478) (xy 3.393304 -346.362219)
			(xy 3.43125 -346.301828) (xy 3.475719 -346.246066) (xy 3.526152 -346.195633) (xy 3.581914 -346.151164)
			(xy 3.642305 -346.113218) (xy 3.706564 -346.082273) (xy 3.773884 -346.058716) (xy 3.843419 -346.042846)
			(xy 3.914293 -346.03486) (xy 3.985615 -346.03486) (xy 4.056489 -346.042846) (xy 4.126024 -346.058716)
			(xy 4.193344 -346.082273) (xy 4.257603 -346.113218) (xy 4.317994 -346.151164) (xy 4.373756 -346.195633)
			(xy 4.424189 -346.246066) (xy 4.468658 -346.301828) (xy 4.506604 -346.362219) (xy 4.537549 -346.426478)
			(xy 4.561106 -346.493798) (xy 4.576976 -346.563333) (xy 4.584962 -346.634207) (xy 4.585462 -346.669868)
			(xy 4.584962 -346.705529) (xy 5.814814 -346.705529) (xy 5.814814 -346.634207) (xy 5.8228 -346.563333)
			(xy 5.83867 -346.493798) (xy 5.862227 -346.426478) (xy 5.893172 -346.362219) (xy 5.931118 -346.301828)
			(xy 5.975587 -346.246066) (xy 6.02602 -346.195633) (xy 6.081782 -346.151164) (xy 6.142173 -346.113218)
			(xy 6.206432 -346.082273) (xy 6.273752 -346.058716) (xy 6.343287 -346.042846) (xy 6.414161 -346.03486)
			(xy 6.485483 -346.03486) (xy 6.556357 -346.042846) (xy 6.625892 -346.058716) (xy 6.693212 -346.082273)
			(xy 6.757471 -346.113218) (xy 6.817862 -346.151164) (xy 6.873624 -346.195633) (xy 6.924057 -346.246066)
			(xy 6.968526 -346.301828) (xy 7.006472 -346.362219) (xy 7.037417 -346.426478) (xy 7.060974 -346.493798)
			(xy 7.076844 -346.563333) (xy 7.08483 -346.634207) (xy 7.08533 -346.669868) (xy 7.08483 -346.705529)
			(xy 7.076844 -346.776403) (xy 7.060974 -346.845938) (xy 7.037417 -346.913258) (xy 7.006472 -346.977517)
			(xy 6.968526 -347.037908) (xy 6.924057 -347.09367) (xy 6.873624 -347.144103) (xy 6.817862 -347.188572)
			(xy 6.757471 -347.226518) (xy 6.693212 -347.257463) (xy 6.625892 -347.28102) (xy 6.556357 -347.29689)
			(xy 6.485483 -347.304876) (xy 6.414161 -347.304876) (xy 6.343287 -347.29689) (xy 6.273752 -347.28102)
			(xy 6.206432 -347.257463) (xy 6.142173 -347.226518) (xy 6.081782 -347.188572) (xy 6.02602 -347.144103)
			(xy 5.975587 -347.09367) (xy 5.931118 -347.037908) (xy 5.893172 -346.977517) (xy 5.862227 -346.913258)
			(xy 5.83867 -346.845938) (xy 5.8228 -346.776403) (xy 5.814814 -346.705529) (xy 4.584962 -346.705529)
			(xy 4.576976 -346.776403) (xy 4.561106 -346.845938) (xy 4.537549 -346.913258) (xy 4.506604 -346.977517)
			(xy 4.468658 -347.037908) (xy 4.424189 -347.09367) (xy 4.373756 -347.144103) (xy 4.317994 -347.188572)
			(xy 4.257603 -347.226518) (xy 4.193344 -347.257463) (xy 4.126024 -347.28102) (xy 4.056489 -347.29689)
			(xy 3.985615 -347.304876) (xy 3.914293 -347.304876) (xy 3.843419 -347.29689) (xy 3.773884 -347.28102)
			(xy 3.706564 -347.257463) (xy 3.642305 -347.226518) (xy 3.581914 -347.188572) (xy 3.526152 -347.144103)
			(xy 3.475719 -347.09367) (xy 3.43125 -347.037908) (xy 3.393304 -346.977517) (xy 3.362359 -346.913258)
			(xy 3.338802 -346.845938) (xy 3.322932 -346.776403) (xy 3.314946 -346.705529) (xy 1.27 -346.705529)
			(xy 1.27 -346.88907) (xy 1.270438 -346.91072) (xy 1.277779 -346.953394) (xy 1.292248 -346.994206)
			(xy 1.313427 -347.031974) (xy 1.340702 -347.065605) (xy 1.373284 -347.094125) (xy 1.41023 -347.116708)
			(xy 1.450469 -347.1327) (xy 1.492837 -347.14164) (xy 1.536107 -347.143267) (xy 1.579027 -347.137535)
			(xy 1.620354 -347.124609) (xy 1.639824 -347.11513) (xy 1.671264 -347.09811) (xy 1.737191 -347.070445)
			(xy 1.805806 -347.050354) (xy 1.876242 -347.03809) (xy 1.94761 -347.033808) (xy 2.019007 -347.037563)
			(xy 2.089532 -347.049306) (xy 2.158294 -347.068891) (xy 2.224423 -347.096068) (xy 2.287084 -347.130495)
			(xy 2.345486 -347.171737) (xy 2.398891 -347.219273) (xy 2.446623 -347.272501) (xy 2.488081 -347.330751)
			(xy 2.522739 -347.393285) (xy 2.55016 -347.459313) (xy 2.569998 -347.528002) (xy 2.582002 -347.598483)
			(xy 2.58602 -347.669866) (xy 2.584013 -347.705527) (xy 7.81481 -347.705527) (xy 7.81481 -347.634205)
			(xy 7.822796 -347.563331) (xy 7.838666 -347.493796) (xy 7.862223 -347.426476) (xy 7.893168 -347.362217)
			(xy 7.931114 -347.301826) (xy 7.975583 -347.246064) (xy 8.026016 -347.195631) (xy 8.081778 -347.151162)
			(xy 8.142169 -347.113216) (xy 8.206428 -347.082271) (xy 8.273748 -347.058714) (xy 8.343283 -347.042844)
			(xy 8.414157 -347.034858) (xy 8.485479 -347.034858) (xy 8.556353 -347.042844) (xy 8.625888 -347.058714)
			(xy 8.693208 -347.082271) (xy 8.757467 -347.113216) (xy 8.817858 -347.151162) (xy 8.87362 -347.195631)
			(xy 8.924053 -347.246064) (xy 8.968522 -347.301826) (xy 9.006468 -347.362217) (xy 9.037413 -347.426476)
			(xy 9.06097 -347.493796) (xy 9.07684 -347.563331) (xy 9.084826 -347.634205) (xy 9.085326 -347.669866)
			(xy 9.084826 -347.705527) (xy 9.07684 -347.776401) (xy 9.06097 -347.845936) (xy 9.037413 -347.913256)
			(xy 9.006468 -347.977515) (xy 8.968522 -348.037906) (xy 8.924053 -348.093668) (xy 8.87362 -348.144101)
			(xy 8.817858 -348.18857) (xy 8.757467 -348.226516) (xy 8.693208 -348.257461) (xy 8.625888 -348.281018)
			(xy 8.556353 -348.296888) (xy 8.485479 -348.304874) (xy 8.414157 -348.304874) (xy 8.343283 -348.296888)
			(xy 8.273748 -348.281018) (xy 8.206428 -348.257461) (xy 8.142169 -348.226516) (xy 8.081778 -348.18857)
			(xy 8.026016 -348.144101) (xy 7.975583 -348.093668) (xy 7.931114 -348.037906) (xy 7.893168 -347.977515)
			(xy 7.862223 -347.913256) (xy 7.838666 -347.845936) (xy 7.822796 -347.776401) (xy 7.81481 -347.705527)
			(xy 2.584013 -347.705527) (xy 2.582002 -347.741249) (xy 2.569998 -347.81173) (xy 2.55016 -347.880419)
			(xy 2.522739 -347.946447) (xy 2.488081 -348.008981) (xy 2.446623 -348.067231) (xy 2.398891 -348.120459)
			(xy 2.345486 -348.167995) (xy 2.287084 -348.209237) (xy 2.224423 -348.243664) (xy 2.158294 -348.270841)
			(xy 2.089532 -348.290426) (xy 2.019007 -348.302169) (xy 1.94761 -348.305924) (xy 1.876242 -348.301642)
			(xy 1.805806 -348.289378) (xy 1.737191 -348.269287) (xy 1.671264 -348.241622) (xy 1.639824 -348.224602)
			(xy 1.620354 -348.21512) (xy 1.579025 -348.202196) (xy 1.536103 -348.196465) (xy 1.492831 -348.198092)
			(xy 1.450461 -348.207032) (xy 1.41022 -348.223024) (xy 1.373272 -348.245607) (xy 1.340687 -348.274126)
			(xy 1.313408 -348.307756) (xy 1.292224 -348.345524) (xy 1.277749 -348.386336) (xy 1.270402 -348.429011)
			(xy 1.27 -348.450662) (xy 1.27 -348.705525) (xy 3.314946 -348.705525) (xy 3.314946 -348.634203) (xy 3.322932 -348.563329)
			(xy 3.338802 -348.493794) (xy 3.362359 -348.426474) (xy 3.393304 -348.362215) (xy 3.43125 -348.301824)
			(xy 3.475719 -348.246062) (xy 3.526152 -348.195629) (xy 3.581914 -348.15116) (xy 3.642305 -348.113214)
			(xy 3.706564 -348.082269) (xy 3.773884 -348.058712) (xy 3.843419 -348.042842) (xy 3.914293 -348.034856)
			(xy 3.985615 -348.034856) (xy 4.056489 -348.042842) (xy 4.126024 -348.058712) (xy 4.193344 -348.082269)
			(xy 4.257603 -348.113214) (xy 4.317994 -348.15116) (xy 4.373756 -348.195629) (xy 4.424189 -348.246062)
			(xy 4.468658 -348.301824) (xy 4.506604 -348.362215) (xy 4.537549 -348.426474) (xy 4.561106 -348.493794)
			(xy 4.576976 -348.563329) (xy 4.584962 -348.634203) (xy 4.585462 -348.669864) (xy 4.584962 -348.705525)
			(xy 5.814814 -348.705525) (xy 5.814814 -348.634203) (xy 5.8228 -348.563329) (xy 5.83867 -348.493794)
			(xy 5.862227 -348.426474) (xy 5.893172 -348.362215) (xy 5.931118 -348.301824) (xy 5.975587 -348.246062)
			(xy 6.02602 -348.195629) (xy 6.081782 -348.15116) (xy 6.142173 -348.113214) (xy 6.206432 -348.082269)
			(xy 6.273752 -348.058712) (xy 6.343287 -348.042842) (xy 6.414161 -348.034856) (xy 6.485483 -348.034856)
			(xy 6.556357 -348.042842) (xy 6.625892 -348.058712) (xy 6.693212 -348.082269) (xy 6.757471 -348.113214)
			(xy 6.817862 -348.15116) (xy 6.873624 -348.195629) (xy 6.924057 -348.246062) (xy 6.968526 -348.301824)
			(xy 7.006472 -348.362215) (xy 7.037417 -348.426474) (xy 7.060974 -348.493794) (xy 7.076844 -348.563329)
			(xy 7.08483 -348.634203) (xy 7.08533 -348.669864) (xy 7.08483 -348.705525) (xy 7.076844 -348.776399)
			(xy 7.060974 -348.845934) (xy 7.037417 -348.913254) (xy 7.006472 -348.977513) (xy 6.968526 -349.037904)
			(xy 6.924057 -349.093666) (xy 6.873624 -349.144099) (xy 6.817862 -349.188568) (xy 6.757471 -349.226514)
			(xy 6.693212 -349.257459) (xy 6.625892 -349.281016) (xy 6.556357 -349.296886) (xy 6.485483 -349.304872)
			(xy 6.414161 -349.304872) (xy 6.343287 -349.296886) (xy 6.273752 -349.281016) (xy 6.206432 -349.257459)
			(xy 6.142173 -349.226514) (xy 6.081782 -349.188568) (xy 6.02602 -349.144099) (xy 5.975587 -349.093666)
			(xy 5.931118 -349.037904) (xy 5.893172 -348.977513) (xy 5.862227 -348.913254) (xy 5.83867 -348.845934)
			(xy 5.8228 -348.776399) (xy 5.814814 -348.705525) (xy 4.584962 -348.705525) (xy 4.576976 -348.776399)
			(xy 4.561106 -348.845934) (xy 4.537549 -348.913254) (xy 4.506604 -348.977513) (xy 4.468658 -349.037904)
			(xy 4.424189 -349.093666) (xy 4.373756 -349.144099) (xy 4.317994 -349.188568) (xy 4.257603 -349.226514)
			(xy 4.193344 -349.257459) (xy 4.126024 -349.281016) (xy 4.056489 -349.296886) (xy 3.985615 -349.304872)
			(xy 3.914293 -349.304872) (xy 3.843419 -349.296886) (xy 3.773884 -349.281016) (xy 3.706564 -349.257459)
			(xy 3.642305 -349.226514) (xy 3.581914 -349.188568) (xy 3.526152 -349.144099) (xy 3.475719 -349.093666)
			(xy 3.43125 -349.037904) (xy 3.393304 -348.977513) (xy 3.362359 -348.913254) (xy 3.338802 -348.845934)
			(xy 3.322932 -348.776399) (xy 3.314946 -348.705525) (xy 1.27 -348.705525) (xy 1.27 -348.889066) (xy 1.270438 -348.910716)
			(xy 1.27778 -348.953389) (xy 1.29225 -348.9942) (xy 1.313429 -349.031967) (xy 1.340704 -349.065597)
			(xy 1.373286 -349.094116) (xy 1.410231 -349.116698) (xy 1.45047 -349.132691) (xy 1.492837 -349.14163)
			(xy 1.536106 -349.143257) (xy 1.579026 -349.137525) (xy 1.620352 -349.1246) (xy 1.639824 -349.115126)
			(xy 1.671264 -349.098106) (xy 1.737191 -349.070441) (xy 1.805806 -349.050349) (xy 1.876242 -349.038085)
			(xy 1.94761 -349.033803) (xy 2.019007 -349.037557) (xy 2.089532 -349.049301) (xy 2.158294 -349.068885)
			(xy 2.224423 -349.096062) (xy 2.287084 -349.130489) (xy 2.345487 -349.171731) (xy 2.398891 -349.219266)
			(xy 2.446624 -349.272495) (xy 2.488081 -349.330744) (xy 2.52274 -349.393278) (xy 2.550161 -349.459306)
			(xy 2.569999 -349.527995) (xy 2.582003 -349.598476) (xy 2.586021 -349.669859) (xy 2.584014 -349.705523)
			(xy 7.81481 -349.705523) (xy 7.81481 -349.634201) (xy 7.822796 -349.563327) (xy 7.838666 -349.493792)
			(xy 7.862223 -349.426472) (xy 7.893168 -349.362213) (xy 7.931114 -349.301822) (xy 7.975583 -349.24606)
			(xy 8.026016 -349.195627) (xy 8.081778 -349.151158) (xy 8.142169 -349.113212) (xy 8.206428 -349.082267)
			(xy 8.273748 -349.05871) (xy 8.343283 -349.04284) (xy 8.414157 -349.034854) (xy 8.485479 -349.034854)
			(xy 8.556353 -349.04284) (xy 8.625888 -349.05871) (xy 8.693208 -349.082267) (xy 8.757467 -349.113212)
			(xy 8.817858 -349.151158) (xy 8.87362 -349.195627) (xy 8.924053 -349.24606) (xy 8.968522 -349.301822)
			(xy 9.006468 -349.362213) (xy 9.037413 -349.426472) (xy 9.06097 -349.493792) (xy 9.07684 -349.563327)
			(xy 9.084826 -349.634201) (xy 9.085326 -349.669862) (xy 9.084826 -349.705523) (xy 9.07684 -349.776397)
			(xy 9.06097 -349.845932) (xy 9.037413 -349.913252) (xy 9.006468 -349.977511) (xy 8.968522 -350.037902)
			(xy 8.924053 -350.093664) (xy 8.87362 -350.144097) (xy 8.817858 -350.188566) (xy 8.757467 -350.226512)
			(xy 8.693208 -350.257457) (xy 8.625888 -350.281014) (xy 8.556353 -350.296884) (xy 8.485479 -350.30487)
			(xy 8.414157 -350.30487) (xy 8.343283 -350.296884) (xy 8.273748 -350.281014) (xy 8.206428 -350.257457)
			(xy 8.142169 -350.226512) (xy 8.081778 -350.188566) (xy 8.026016 -350.144097) (xy 7.975583 -350.093664)
			(xy 7.931114 -350.037902) (xy 7.893168 -349.977511) (xy 7.862223 -349.913252) (xy 7.838666 -349.845932)
			(xy 7.822796 -349.776397) (xy 7.81481 -349.705523) (xy 2.584014 -349.705523) (xy 2.582003 -349.741242)
			(xy 2.569999 -349.811723) (xy 2.550162 -349.880412) (xy 2.52274 -349.94644) (xy 2.488082 -350.008974)
			(xy 2.446625 -350.067224) (xy 2.398893 -350.120453) (xy 2.345488 -350.167988) (xy 2.287086 -350.20923)
			(xy 2.224425 -350.243657) (xy 2.158295 -350.270835) (xy 2.089534 -350.290419) (xy 2.019009 -350.302162)
			(xy 1.947612 -350.305917) (xy 1.876244 -350.301635) (xy 1.805808 -350.289371) (xy 1.737193 -350.26928)
			(xy 1.671266 -350.241615) (xy 1.639824 -350.224598) (xy 1.620354 -350.215116) (xy 1.579025 -350.202192)
			(xy 1.536103 -350.196461) (xy 1.492831 -350.198089) (xy 1.450461 -350.207028) (xy 1.410219 -350.223021)
			(xy 1.373271 -350.245603) (xy 1.340685 -350.274122) (xy 1.313406 -350.307752) (xy 1.292222 -350.34552)
			(xy 1.277747 -350.386332) (xy 1.270399 -350.429007) (xy 1.27 -350.450658) (xy 1.27 -350.705521) (xy 3.314946 -350.705521)
			(xy 3.314946 -350.634199) (xy 3.322932 -350.563325) (xy 3.338802 -350.49379) (xy 3.362359 -350.42647)
			(xy 3.393304 -350.362211) (xy 3.43125 -350.30182) (xy 3.475719 -350.246058) (xy 3.526152 -350.195625)
			(xy 3.581914 -350.151156) (xy 3.642305 -350.11321) (xy 3.706564 -350.082265) (xy 3.773884 -350.058708)
			(xy 3.843419 -350.042838) (xy 3.914293 -350.034852) (xy 3.985615 -350.034852) (xy 4.056489 -350.042838)
			(xy 4.126024 -350.058708) (xy 4.193344 -350.082265) (xy 4.257603 -350.11321) (xy 4.317994 -350.151156)
			(xy 4.373756 -350.195625) (xy 4.424189 -350.246058) (xy 4.468658 -350.30182) (xy 4.506604 -350.362211)
			(xy 4.537549 -350.42647) (xy 4.561106 -350.49379) (xy 4.576976 -350.563325) (xy 4.584962 -350.634199)
			(xy 4.585462 -350.66986) (xy 4.584962 -350.705521) (xy 5.814814 -350.705521) (xy 5.814814 -350.634199)
			(xy 5.8228 -350.563325) (xy 5.83867 -350.49379) (xy 5.862227 -350.42647) (xy 5.893172 -350.362211)
			(xy 5.931118 -350.30182) (xy 5.975587 -350.246058) (xy 6.02602 -350.195625) (xy 6.081782 -350.151156)
			(xy 6.142173 -350.11321) (xy 6.206432 -350.082265) (xy 6.273752 -350.058708) (xy 6.343287 -350.042838)
			(xy 6.414161 -350.034852) (xy 6.485483 -350.034852) (xy 6.556357 -350.042838) (xy 6.625892 -350.058708)
			(xy 6.693212 -350.082265) (xy 6.757471 -350.11321) (xy 6.817862 -350.151156) (xy 6.873624 -350.195625)
			(xy 6.924057 -350.246058) (xy 6.968526 -350.30182) (xy 7.006472 -350.362211) (xy 7.037417 -350.42647)
			(xy 7.060974 -350.49379) (xy 7.076844 -350.563325) (xy 7.08483 -350.634199) (xy 7.08533 -350.66986)
			(xy 7.08483 -350.705521) (xy 7.076844 -350.776395) (xy 7.060974 -350.84593) (xy 7.037417 -350.91325)
			(xy 7.006472 -350.977509) (xy 6.968526 -351.0379) (xy 6.924057 -351.093662) (xy 6.873624 -351.144095)
			(xy 6.817862 -351.188564) (xy 6.757471 -351.22651) (xy 6.693212 -351.257455) (xy 6.625892 -351.281012)
			(xy 6.556357 -351.296882) (xy 6.485483 -351.304868) (xy 6.414161 -351.304868) (xy 6.343287 -351.296882)
			(xy 6.273752 -351.281012) (xy 6.206432 -351.257455) (xy 6.142173 -351.22651) (xy 6.081782 -351.188564)
			(xy 6.02602 -351.144095) (xy 5.975587 -351.093662) (xy 5.931118 -351.0379) (xy 5.893172 -350.977509)
			(xy 5.862227 -350.91325) (xy 5.83867 -350.84593) (xy 5.8228 -350.776395) (xy 5.814814 -350.705521)
			(xy 4.584962 -350.705521) (xy 4.576976 -350.776395) (xy 4.561106 -350.84593) (xy 4.537549 -350.91325)
			(xy 4.506604 -350.977509) (xy 4.468658 -351.0379) (xy 4.424189 -351.093662) (xy 4.373756 -351.144095)
			(xy 4.317994 -351.188564) (xy 4.257603 -351.22651) (xy 4.193344 -351.257455) (xy 4.126024 -351.281012)
			(xy 4.056489 -351.296882) (xy 3.985615 -351.304868) (xy 3.914293 -351.304868) (xy 3.843419 -351.296882)
			(xy 3.773884 -351.281012) (xy 3.706564 -351.257455) (xy 3.642305 -351.22651) (xy 3.581914 -351.188564)
			(xy 3.526152 -351.144095) (xy 3.475719 -351.093662) (xy 3.43125 -351.0379) (xy 3.393304 -350.977509)
			(xy 3.362359 -350.91325) (xy 3.338802 -350.84593) (xy 3.322932 -350.776395) (xy 3.314946 -350.705521)
			(xy 1.27 -350.705521) (xy 1.27 -350.889062) (xy 1.270438 -350.910712) (xy 1.277779 -350.953386) (xy 1.292249 -350.994198)
			(xy 1.313428 -351.031965) (xy 1.340703 -351.065596) (xy 1.373285 -351.094115) (xy 1.41023 -351.116698)
			(xy 1.450469 -351.132691) (xy 1.492837 -351.14163) (xy 1.536107 -351.143257) (xy 1.579027 -351.137525)
			(xy 1.620353 -351.124599) (xy 1.639824 -351.115122) (xy 1.671264 -351.098102) (xy 1.737191 -351.070437)
			(xy 1.805807 -351.050345) (xy 1.876243 -351.038081) (xy 1.947612 -351.033799) (xy 2.019009 -351.037554)
			(xy 2.089535 -351.049298) (xy 2.158297 -351.068882) (xy 2.224426 -351.09606) (xy 2.287088 -351.130487)
			(xy 2.34549 -351.171729) (xy 2.398895 -351.219265) (xy 2.446628 -351.272494) (xy 2.488085 -351.330744)
			(xy 2.522744 -351.393278) (xy 2.550165 -351.459307) (xy 2.570003 -351.527996) (xy 2.582007 -351.598478)
			(xy 2.586025 -351.669861) (xy 2.584018 -351.705519) (xy 7.81481 -351.705519) (xy 7.81481 -351.634197)
			(xy 7.822796 -351.563323) (xy 7.838666 -351.493788) (xy 7.862223 -351.426468) (xy 7.893168 -351.362209)
			(xy 7.931114 -351.301818) (xy 7.975583 -351.246056) (xy 8.026016 -351.195623) (xy 8.081778 -351.151154)
			(xy 8.142169 -351.113208) (xy 8.206428 -351.082263) (xy 8.273748 -351.058706) (xy 8.343283 -351.042836)
			(xy 8.414157 -351.03485) (xy 8.485479 -351.03485) (xy 8.556353 -351.042836) (xy 8.625888 -351.058706)
			(xy 8.693208 -351.082263) (xy 8.757467 -351.113208) (xy 8.817858 -351.151154) (xy 8.87362 -351.195623)
			(xy 8.924053 -351.246056) (xy 8.968522 -351.301818) (xy 9.006468 -351.362209) (xy 9.037413 -351.426468)
			(xy 9.06097 -351.493788) (xy 9.07684 -351.563323) (xy 9.084826 -351.634197) (xy 9.085326 -351.669858)
			(xy 9.084826 -351.705519) (xy 9.07684 -351.776393) (xy 9.06097 -351.845928) (xy 9.037413 -351.913248)
			(xy 9.006468 -351.977507) (xy 8.968522 -352.037898) (xy 8.924053 -352.09366) (xy 8.87362 -352.144093)
			(xy 8.817858 -352.188562) (xy 8.757467 -352.226508) (xy 8.693208 -352.257453) (xy 8.625888 -352.28101)
			(xy 8.556353 -352.29688) (xy 8.485479 -352.304866) (xy 8.414157 -352.304866) (xy 8.343283 -352.29688)
			(xy 8.273748 -352.28101) (xy 8.206428 -352.257453) (xy 8.142169 -352.226508) (xy 8.081778 -352.188562)
			(xy 8.026016 -352.144093) (xy 7.975583 -352.09366) (xy 7.931114 -352.037898) (xy 7.893168 -351.977507)
			(xy 7.862223 -351.913248) (xy 7.838666 -351.845928) (xy 7.822796 -351.776393) (xy 7.81481 -351.705519)
			(xy 2.584018 -351.705519) (xy 2.582007 -351.741244) (xy 2.570002 -351.811726) (xy 2.550164 -351.880415)
			(xy 2.522743 -351.946444) (xy 2.488084 -352.008978) (xy 2.446627 -352.067227) (xy 2.398894 -352.120456)
			(xy 2.345489 -352.167992) (xy 2.287086 -352.209234) (xy 2.224424 -352.243661) (xy 2.158295 -352.270839)
			(xy 2.089533 -352.290423) (xy 2.019007 -352.302166) (xy 1.94761 -352.305921) (xy 1.876242 -352.301639)
			(xy 1.805805 -352.289374) (xy 1.73719 -352.269282) (xy 1.671263 -352.241617) (xy 1.639824 -352.224594)
			(xy 1.620357 -352.215109) (xy 1.579032 -352.202181) (xy 1.536114 -352.196447) (xy 1.492844 -352.198073)
			(xy 1.450477 -352.207013) (xy 1.410239 -352.223006) (xy 1.373296 -352.245591) (xy 1.340717 -352.274113)
			(xy 1.313445 -352.307746) (xy 1.292272 -352.345516) (xy 1.277809 -352.386329) (xy 1.270477 -352.429004)
			(xy 1.27 -352.450654) (xy 1.27 -352.705517) (xy 3.314946 -352.705517) (xy 3.314946 -352.634195) (xy 3.322932 -352.563321)
			(xy 3.338802 -352.493786) (xy 3.362359 -352.426466) (xy 3.393304 -352.362207) (xy 3.43125 -352.301816)
			(xy 3.475719 -352.246054) (xy 3.526152 -352.195621) (xy 3.581914 -352.151152) (xy 3.642305 -352.113206)
			(xy 3.706564 -352.082261) (xy 3.773884 -352.058704) (xy 3.843419 -352.042834) (xy 3.914293 -352.034848)
			(xy 3.985615 -352.034848) (xy 4.056489 -352.042834) (xy 4.126024 -352.058704) (xy 4.193344 -352.082261)
			(xy 4.257603 -352.113206) (xy 4.317994 -352.151152) (xy 4.373756 -352.195621) (xy 4.424189 -352.246054)
			(xy 4.468658 -352.301816) (xy 4.506604 -352.362207) (xy 4.537549 -352.426466) (xy 4.561106 -352.493786)
			(xy 4.576976 -352.563321) (xy 4.584962 -352.634195) (xy 4.585462 -352.669856) (xy 4.584962 -352.705517)
			(xy 5.814814 -352.705517) (xy 5.814814 -352.634195) (xy 5.8228 -352.563321) (xy 5.83867 -352.493786)
			(xy 5.862227 -352.426466) (xy 5.893172 -352.362207) (xy 5.931118 -352.301816) (xy 5.975587 -352.246054)
			(xy 6.02602 -352.195621) (xy 6.081782 -352.151152) (xy 6.142173 -352.113206) (xy 6.206432 -352.082261)
			(xy 6.273752 -352.058704) (xy 6.343287 -352.042834) (xy 6.414161 -352.034848) (xy 6.485483 -352.034848)
			(xy 6.556357 -352.042834) (xy 6.625892 -352.058704) (xy 6.693212 -352.082261) (xy 6.757471 -352.113206)
			(xy 6.817862 -352.151152) (xy 6.873624 -352.195621) (xy 6.924057 -352.246054) (xy 6.968526 -352.301816)
			(xy 7.006472 -352.362207) (xy 7.037417 -352.426466) (xy 7.060974 -352.493786) (xy 7.076844 -352.563321)
			(xy 7.08483 -352.634195) (xy 7.08533 -352.669856) (xy 7.08483 -352.705517) (xy 7.076844 -352.776391)
			(xy 7.060974 -352.845926) (xy 7.037417 -352.913246) (xy 7.006472 -352.977505) (xy 6.968526 -353.037896)
			(xy 6.924057 -353.093658) (xy 6.873624 -353.144091) (xy 6.817862 -353.18856) (xy 6.757471 -353.226506)
			(xy 6.693212 -353.257451) (xy 6.625892 -353.281008) (xy 6.556357 -353.296878) (xy 6.485483 -353.304864)
			(xy 6.414161 -353.304864) (xy 6.343287 -353.296878) (xy 6.273752 -353.281008) (xy 6.206432 -353.257451)
			(xy 6.142173 -353.226506) (xy 6.081782 -353.18856) (xy 6.02602 -353.144091) (xy 5.975587 -353.093658)
			(xy 5.931118 -353.037896) (xy 5.893172 -352.977505) (xy 5.862227 -352.913246) (xy 5.83867 -352.845926)
			(xy 5.8228 -352.776391) (xy 5.814814 -352.705517) (xy 4.584962 -352.705517) (xy 4.576976 -352.776391)
			(xy 4.561106 -352.845926) (xy 4.537549 -352.913246) (xy 4.506604 -352.977505) (xy 4.468658 -353.037896)
			(xy 4.424189 -353.093658) (xy 4.373756 -353.144091) (xy 4.317994 -353.18856) (xy 4.257603 -353.226506)
			(xy 4.193344 -353.257451) (xy 4.126024 -353.281008) (xy 4.056489 -353.296878) (xy 3.985615 -353.304864)
			(xy 3.914293 -353.304864) (xy 3.843419 -353.296878) (xy 3.773884 -353.281008) (xy 3.706564 -353.257451)
			(xy 3.642305 -353.226506) (xy 3.581914 -353.18856) (xy 3.526152 -353.144091) (xy 3.475719 -353.093658)
			(xy 3.43125 -353.037896) (xy 3.393304 -352.977505) (xy 3.362359 -352.913246) (xy 3.338802 -352.845926)
			(xy 3.322932 -352.776391) (xy 3.314946 -352.705517) (xy 1.27 -352.705517) (xy 1.27 -373.875046) (xy 1.295616 -373.875046)
			(xy 1.299617 -373.779445) (xy 1.31159 -373.684513) (xy 1.331453 -373.590912) (xy 1.359066 -373.499299)
			(xy 1.394236 -373.410312) (xy 1.436718 -373.324575) (xy 1.486214 -373.242687) (xy 1.542379 -373.16522)
			(xy 1.604819 -373.092716) (xy 1.673098 -373.025683) (xy 1.746738 -372.964588) (xy 1.825226 -372.909859)
			(xy 1.908011 -372.861878) (xy 1.994515 -372.820982) (xy 2.084134 -372.787455) (xy 2.176241 -372.761533)
			(xy 2.270191 -372.743396) (xy 2.365327 -372.733172) (xy 2.460986 -372.730932) (xy 2.556497 -372.736691)
			(xy 2.651193 -372.75041) (xy 2.744412 -372.771992) (xy 2.835502 -372.801287) (xy 2.923826 -372.838089)
			(xy 3.008766 -372.882142) (xy 3.08973 -372.933137) (xy 3.16615 -372.990717) (xy 3.237492 -373.054481)
			(xy 3.303257 -373.123983) (xy 3.362987 -373.198735) (xy 3.416262 -373.278217) (xy 3.439922 -373.319802)
			(xy 3.463586 -373.278219) (xy 3.516861 -373.198738) (xy 3.57659 -373.123985) (xy 3.642356 -373.054484)
			(xy 3.713698 -372.990721) (xy 3.790118 -372.93314) (xy 3.871082 -372.882146) (xy 3.956022 -372.838093)
			(xy 4.044346 -372.801291) (xy 4.135436 -372.771997) (xy 4.228655 -372.750415) (xy 4.323351 -372.736697)
			(xy 4.418862 -372.730938) (xy 4.51452 -372.733178) (xy 4.609657 -372.743403) (xy 4.703606 -372.76154)
			(xy 4.795713 -372.787462) (xy 4.885331 -372.820989) (xy 4.971835 -372.861885) (xy 5.05462 -372.909866)
			(xy 5.133107 -372.964595) (xy 5.206748 -373.025691) (xy 5.275026 -373.092724) (xy 5.337466 -373.165228)
			(xy 5.39363 -373.242695) (xy 5.443126 -373.324583) (xy 5.485607 -373.41032) (xy 5.520777 -373.499307)
			(xy 5.54839 -373.59092) (xy 5.568253 -373.68452) (xy 5.580226 -373.779453) (xy 5.584226 -373.875053)
			(xy 5.580225 -373.970654) (xy 5.568251 -374.065587) (xy 5.548389 -374.159187) (xy 5.520775 -374.2508)
			(xy 5.485605 -374.339786) (xy 5.443123 -374.425523) (xy 5.393626 -374.507411) (xy 5.337462 -374.584877)
			(xy 5.275022 -374.657381) (xy 5.206742 -374.724414) (xy 5.133102 -374.785509) (xy 5.054614 -374.840238)
			(xy 4.971829 -374.888218) (xy 4.885325 -374.929114) (xy 4.795706 -374.96264) (xy 4.7036 -374.988562)
			(xy 4.60965 -375.006698) (xy 4.514513 -375.016922) (xy 4.418855 -375.019162) (xy 4.323344 -375.013402)
			(xy 4.228648 -374.999683) (xy 4.135429 -374.978101) (xy 4.04434 -374.948806) (xy 3.956016 -374.912004)
			(xy 3.871076 -374.867951) (xy 3.790113 -374.816956) (xy 3.713693 -374.759375) (xy 3.642351 -374.695611)
			(xy 3.576586 -374.626109) (xy 3.516857 -374.551357) (xy 3.463582 -374.471875) (xy 3.439922 -374.43029)
			(xy 3.416262 -374.471875) (xy 3.362987 -374.551357) (xy 3.303257 -374.626109) (xy 3.237492 -374.695611)
			(xy 3.16615 -374.759375) (xy 3.08973 -374.816955) (xy 3.008766 -374.86795) (xy 2.923826 -374.912003)
			(xy 2.835502 -374.948805) (xy 2.744412 -374.9781) (xy 2.651193 -374.999682) (xy 2.556497 -375.013401)
			(xy 2.460986 -375.01916) (xy 2.365327 -375.01692) (xy 2.270191 -375.006696) (xy 2.176241 -374.988559)
			(xy 2.084134 -374.962637) (xy 1.994515 -374.92911) (xy 1.908011 -374.888214) (xy 1.825226 -374.840233)
			(xy 1.746738 -374.785504) (xy 1.673098 -374.724409) (xy 1.604819 -374.657376) (xy 1.542379 -374.584872)
			(xy 1.486214 -374.507405) (xy 1.436718 -374.425517) (xy 1.394236 -374.33978) (xy 1.359066 -374.250793)
			(xy 1.331453 -374.15918) (xy 1.31159 -374.065579) (xy 1.299617 -373.970647) (xy 1.295616 -373.875046)
			(xy 1.27 -373.875046) (xy 1.27 -380.824994) (xy 1.295616 -380.824994) (xy 1.299617 -380.729393) (xy 1.31159 -380.634461)
			(xy 1.331453 -380.54086) (xy 1.359066 -380.449247) (xy 1.394236 -380.36026) (xy 1.436718 -380.274523)
			(xy 1.486214 -380.192635) (xy 1.542379 -380.115168) (xy 1.604819 -380.042664) (xy 1.673098 -379.975631)
			(xy 1.746738 -379.914536) (xy 1.825226 -379.859807) (xy 1.908011 -379.811826) (xy 1.994515 -379.77093)
			(xy 2.084134 -379.737403) (xy 2.176241 -379.711481) (xy 2.270191 -379.693344) (xy 2.365327 -379.68312)
			(xy 2.460986 -379.68088) (xy 2.556497 -379.686639) (xy 2.651193 -379.700358) (xy 2.744412 -379.72194)
			(xy 2.835502 -379.751235) (xy 2.923826 -379.788037) (xy 3.008766 -379.83209) (xy 3.08973 -379.883085)
			(xy 3.16615 -379.940665) (xy 3.237492 -380.004429) (xy 3.303257 -380.073931) (xy 3.362987 -380.148683)
			(xy 3.416262 -380.228165) (xy 3.439922 -380.26975) (xy 3.463579 -380.228163) (xy 3.516854 -380.148681)
			(xy 3.576583 -380.073928) (xy 3.642348 -380.004426) (xy 3.71369 -379.940662) (xy 3.79011 -379.883081)
			(xy 3.871074 -379.832086) (xy 3.956014 -379.788033) (xy 4.044338 -379.75123) (xy 4.135428 -379.721935)
			(xy 4.228647 -379.700353) (xy 4.323343 -379.686634) (xy 4.418855 -379.680874) (xy 4.514513 -379.683114)
			(xy 4.60965 -379.693338) (xy 4.7036 -379.711474) (xy 4.795707 -379.737396) (xy 4.885326 -379.770922)
			(xy 4.971831 -379.811819) (xy 5.054616 -379.859799) (xy 5.133104 -379.914528) (xy 5.206745 -379.975623)
			(xy 5.275024 -380.042657) (xy 5.337465 -380.11516) (xy 5.39363 -380.192627) (xy 5.443126 -380.274515)
			(xy 5.485608 -380.360252) (xy 5.520779 -380.449239) (xy 5.548392 -380.540852) (xy 5.568255 -380.634453)
			(xy 5.580229 -380.729385) (xy 5.58423 -380.824987) (xy 5.58023 -380.920588) (xy 5.568256 -381.01552)
			(xy 5.548394 -381.109121) (xy 5.520781 -381.200735) (xy 5.485611 -381.289721) (xy 5.443129 -381.375459)
			(xy 5.393633 -381.457347) (xy 5.337469 -381.534814) (xy 5.275029 -381.607318) (xy 5.20675 -381.674352)
			(xy 5.13311 -381.735448) (xy 5.054622 -381.790177) (xy 4.971837 -381.838158) (xy 4.885332 -381.879055)
			(xy 4.795714 -381.912582) (xy 4.703607 -381.938504) (xy 4.609657 -381.956641) (xy 4.51452 -381.966866)
			(xy 4.418862 -381.969106) (xy 4.32335 -381.963347) (xy 4.228654 -381.949628) (xy 4.135435 -381.928047)
			(xy 4.044345 -381.898752) (xy 3.956021 -381.86195) (xy 3.87108 -381.817898) (xy 3.790116 -381.766903)
			(xy 3.713696 -381.709322) (xy 3.642353 -381.645558) (xy 3.576587 -381.576057) (xy 3.516858 -381.501305)
			(xy 3.463582 -381.421823) (xy 3.439922 -381.380238) (xy 3.416262 -381.421823) (xy 3.362987 -381.501305)
			(xy 3.303257 -381.576057) (xy 3.237492 -381.645559) (xy 3.16615 -381.709323) (xy 3.08973 -381.766903)
			(xy 3.008766 -381.817898) (xy 2.923826 -381.861951) (xy 2.835502 -381.898753) (xy 2.744412 -381.928048)
			(xy 2.651193 -381.94963) (xy 2.556497 -381.963349) (xy 2.460986 -381.969108) (xy 2.365327 -381.966868)
			(xy 2.270191 -381.956644) (xy 2.176241 -381.938507) (xy 2.084134 -381.912585) (xy 1.994515 -381.879058)
			(xy 1.908011 -381.838162) (xy 1.825226 -381.790181) (xy 1.746738 -381.735452) (xy 1.673098 -381.674357)
			(xy 1.604819 -381.607324) (xy 1.542379 -381.53482) (xy 1.486214 -381.457353) (xy 1.436718 -381.375465)
			(xy 1.394236 -381.289728) (xy 1.359066 -381.200741) (xy 1.331453 -381.109128) (xy 1.31159 -381.015527)
			(xy 1.299617 -380.920595) (xy 1.295616 -380.824994) (xy 1.27 -380.824994) (xy 1.27 -394.357606) (xy 2.433572 -394.357606)
			(xy 2.437643 -394.301984) (xy 2.449769 -394.247547) (xy 2.469692 -394.195456) (xy 2.496988 -394.146821)
			(xy 2.531074 -394.102678) (xy 2.571223 -394.063969) (xy 2.616581 -394.031518) (xy 2.666181 -394.006017)
			(xy 2.718965 -393.98801) (xy 2.773808 -393.97788) (xy 2.829542 -393.975843) (xy 2.884979 -393.981943)
			(xy 2.938936 -393.996049) (xy 2.990265 -394.017861) (xy 3.037871 -394.046915) (xy 3.080739 -394.08259)
			(xy 3.117956 -394.124127) (xy 3.148729 -394.17064) (xy 3.172401 -394.221137) (xy 3.180599 -394.248386)
			(xy 3.804918 -394.248386) (xy 3.808989 -394.192764) (xy 3.821115 -394.138327) (xy 3.841038 -394.086236)
			(xy 3.868334 -394.037601) (xy 3.90242 -393.993458) (xy 3.942569 -393.954749) (xy 3.987927 -393.922298)
			(xy 4.037527 -393.896797) (xy 4.090311 -393.87879) (xy 4.145154 -393.86866) (xy 4.200888 -393.866623)
			(xy 4.256325 -393.872723) (xy 4.310282 -393.886829) (xy 4.361611 -393.908641) (xy 4.409217 -393.937695)
			(xy 4.452085 -393.97337) (xy 4.489302 -394.014907) (xy 4.520075 -394.06142) (xy 4.543747 -394.111917)
			(xy 4.559815 -394.165324) (xy 4.567935 -394.2205) (xy 4.568444 -394.248386) (xy 4.567935 -394.276272)
			(xy 4.559815 -394.331448) (xy 4.543747 -394.384855) (xy 4.520075 -394.435352) (xy 4.489302 -394.481865)
			(xy 4.452085 -394.523402) (xy 4.409217 -394.559077) (xy 4.361611 -394.588131) (xy 4.310282 -394.609943)
			(xy 4.256325 -394.624049) (xy 4.200888 -394.630149) (xy 4.145154 -394.628112) (xy 4.090311 -394.617982)
			(xy 4.037527 -394.599975) (xy 3.987927 -394.574474) (xy 3.942569 -394.542023) (xy 3.90242 -394.503314)
			(xy 3.868334 -394.459171) (xy 3.841038 -394.410536) (xy 3.821115 -394.358445) (xy 3.808989 -394.304008)
			(xy 3.804918 -394.248386) (xy 3.180599 -394.248386) (xy 3.188469 -394.274544) (xy 3.196589 -394.32972)
			(xy 3.197098 -394.357606) (xy 3.196589 -394.385492) (xy 3.188469 -394.440668) (xy 3.172401 -394.494075)
			(xy 3.148729 -394.544572) (xy 3.117956 -394.591085) (xy 3.080739 -394.632622) (xy 3.037871 -394.668297)
			(xy 2.990265 -394.697351) (xy 2.938936 -394.719163) (xy 2.884979 -394.733269) (xy 2.829542 -394.739369)
			(xy 2.773808 -394.737332) (xy 2.718965 -394.727202) (xy 2.666181 -394.709195) (xy 2.616581 -394.683694)
			(xy 2.571223 -394.651243) (xy 2.531074 -394.612534) (xy 2.496988 -394.568391) (xy 2.469692 -394.519756)
			(xy 2.449769 -394.467665) (xy 2.437643 -394.413228) (xy 2.433572 -394.357606) (xy 1.27 -394.357606)
			(xy 1.27 -396.021052) (xy 13.361414 -396.021052) (xy 13.365485 -395.96543) (xy 13.377611 -395.910993)
			(xy 13.397534 -395.858902) (xy 13.42483 -395.810267) (xy 13.458916 -395.766124) (xy 13.499065 -395.727415)
			(xy 13.544423 -395.694964) (xy 13.594023 -395.669463) (xy 13.646807 -395.651456) (xy 13.70165 -395.641326)
			(xy 13.757384 -395.639289) (xy 13.812821 -395.645389) (xy 13.866778 -395.659495) (xy 13.918107 -395.681307)
			(xy 13.965713 -395.710361) (xy 14.008581 -395.746036) (xy 14.045798 -395.787573) (xy 14.076571 -395.834086)
			(xy 14.100243 -395.884583) (xy 14.116311 -395.93799) (xy 14.124431 -395.993166) (xy 14.12494 -396.021052)
			(xy 14.124431 -396.048938) (xy 14.116311 -396.104114) (xy 14.100243 -396.157521) (xy 14.076571 -396.208018)
			(xy 14.045798 -396.254531) (xy 14.008581 -396.296068) (xy 13.965713 -396.331743) (xy 13.918107 -396.360797)
			(xy 13.866778 -396.382609) (xy 13.812821 -396.396715) (xy 13.757384 -396.402815) (xy 13.70165 -396.400778)
			(xy 13.646807 -396.390648) (xy 13.594023 -396.372641) (xy 13.544423 -396.34714) (xy 13.499065 -396.314689)
			(xy 13.458916 -396.27598) (xy 13.42483 -396.231837) (xy 13.397534 -396.183202) (xy 13.377611 -396.131111)
			(xy 13.365485 -396.076674) (xy 13.361414 -396.021052) (xy 1.27 -396.021052) (xy 1.27 -399.279927)
			(xy 2.182365 -399.279927) (xy 2.182365 -399.200061) (xy 2.190445 -399.120606) (xy 2.206522 -399.042376)
			(xy 2.230431 -398.966174) (xy 2.261926 -398.892781) (xy 2.300685 -398.822951) (xy 2.346309 -398.757401)
			(xy 2.398331 -398.696802) (xy 2.456216 -398.641778) (xy 2.519372 -398.592892) (xy 2.587149 -398.550646)
			(xy 2.658852 -398.515474) (xy 2.733746 -398.487737) (xy 2.811061 -398.467718) (xy 2.890005 -398.455625)
			(xy 2.969768 -398.45158) (xy 3.049531 -398.455625) (xy 3.128475 -398.467718) (xy 3.20579 -398.487737)
			(xy 3.280684 -398.515474) (xy 3.352387 -398.550646) (xy 3.420164 -398.592892) (xy 3.48332 -398.641778)
			(xy 3.541205 -398.696802) (xy 3.593227 -398.757401) (xy 3.638851 -398.822951) (xy 3.67761 -398.892781)
			(xy 3.709105 -398.966174) (xy 3.733014 -399.042376) (xy 3.749091 -399.120606) (xy 3.757171 -399.200061)
			(xy 3.757676 -399.239994) (xy 3.757171 -399.279927) (xy 4.672327 -399.279927) (xy 4.672327 -399.200061)
			(xy 4.680407 -399.120606) (xy 4.696484 -399.042376) (xy 4.720393 -398.966174) (xy 4.751888 -398.892781)
			(xy 4.790647 -398.822951) (xy 4.836271 -398.757401) (xy 4.888293 -398.696802) (xy 4.946178 -398.641778)
			(xy 5.009334 -398.592892) (xy 5.077111 -398.550646) (xy 5.148814 -398.515474) (xy 5.223708 -398.487737)
			(xy 5.301023 -398.467718) (xy 5.379967 -398.455625) (xy 5.45973 -398.45158) (xy 5.539493 -398.455625)
			(xy 5.618437 -398.467718) (xy 5.695752 -398.487737) (xy 5.770646 -398.515474) (xy 5.842349 -398.550646)
			(xy 5.910126 -398.592892) (xy 5.973282 -398.641778) (xy 6.031167 -398.696802) (xy 6.083189 -398.757401)
			(xy 6.128813 -398.822951) (xy 6.167572 -398.892781) (xy 6.199067 -398.966174) (xy 6.222976 -399.042376)
			(xy 6.239053 -399.120606) (xy 6.247133 -399.200061) (xy 6.247638 -399.239994) (xy 6.247133 -399.279927)
			(xy 12.292327 -399.279927) (xy 12.292327 -399.200061) (xy 12.300407 -399.120606) (xy 12.316484 -399.042376)
			(xy 12.340393 -398.966174) (xy 12.371888 -398.892781) (xy 12.410647 -398.822951) (xy 12.456271 -398.757401)
			(xy 12.508293 -398.696802) (xy 12.566178 -398.641778) (xy 12.629334 -398.592892) (xy 12.697111 -398.550646)
			(xy 12.768814 -398.515474) (xy 12.843708 -398.487737) (xy 12.921023 -398.467718) (xy 12.999967 -398.455625)
			(xy 13.07973 -398.45158) (xy 13.159493 -398.455625) (xy 13.238437 -398.467718) (xy 13.315752 -398.487737)
			(xy 13.390646 -398.515474) (xy 13.462349 -398.550646) (xy 13.530126 -398.592892) (xy 13.593282 -398.641778)
			(xy 13.651167 -398.696802) (xy 13.703189 -398.757401) (xy 13.748813 -398.822951) (xy 13.787572 -398.892781)
			(xy 13.819067 -398.966174) (xy 13.842976 -399.042376) (xy 13.859053 -399.120606) (xy 13.867133 -399.200061)
			(xy 13.867638 -399.239994) (xy 13.867133 -399.279927) (xy 14.782289 -399.279927) (xy 14.782289 -399.200061)
			(xy 14.790369 -399.120606) (xy 14.806446 -399.042376) (xy 14.830355 -398.966174) (xy 14.86185 -398.892781)
			(xy 14.900609 -398.822951) (xy 14.946233 -398.757401) (xy 14.998255 -398.696802) (xy 15.05614 -398.641778)
			(xy 15.119296 -398.592892) (xy 15.187073 -398.550646) (xy 15.258776 -398.515474) (xy 15.33367 -398.487737)
			(xy 15.410985 -398.467718) (xy 15.489929 -398.455625) (xy 15.569692 -398.45158) (xy 15.649455 -398.455625)
			(xy 15.728399 -398.467718) (xy 15.805714 -398.487737) (xy 15.880608 -398.515474) (xy 15.952311 -398.550646)
			(xy 16.020088 -398.592892) (xy 16.083244 -398.641778) (xy 16.141129 -398.696802) (xy 16.193151 -398.757401)
			(xy 16.238775 -398.822951) (xy 16.277534 -398.892781) (xy 16.309029 -398.966174) (xy 16.332938 -399.042376)
			(xy 16.349015 -399.120606) (xy 16.357095 -399.200061) (xy 16.3576 -399.239994) (xy 16.357095 -399.279927)
			(xy 16.349015 -399.359382) (xy 16.332938 -399.437612) (xy 16.309029 -399.513814) (xy 16.277534 -399.587207)
			(xy 16.238775 -399.657037) (xy 16.193151 -399.722587) (xy 16.141129 -399.783186) (xy 16.083244 -399.83821)
			(xy 16.020088 -399.887096) (xy 15.952311 -399.929342) (xy 15.880608 -399.964514) (xy 15.805714 -399.992251)
			(xy 15.728399 -400.01227) (xy 15.649455 -400.024363) (xy 15.569692 -400.028409) (xy 15.489929 -400.024363)
			(xy 15.410985 -400.01227) (xy 15.33367 -399.992251) (xy 15.258776 -399.964514) (xy 15.187073 -399.929342)
			(xy 15.119296 -399.887096) (xy 15.05614 -399.83821) (xy 14.998255 -399.783186) (xy 14.946233 -399.722587)
			(xy 14.900609 -399.657037) (xy 14.86185 -399.587207) (xy 14.830355 -399.513814) (xy 14.806446 -399.437612)
			(xy 14.790369 -399.359382) (xy 14.782289 -399.279927) (xy 13.867133 -399.279927) (xy 13.859053 -399.359382)
			(xy 13.842976 -399.437612) (xy 13.819067 -399.513814) (xy 13.787572 -399.587207) (xy 13.748813 -399.657037)
			(xy 13.703189 -399.722587) (xy 13.651167 -399.783186) (xy 13.593282 -399.83821) (xy 13.530126 -399.887096)
			(xy 13.462349 -399.929342) (xy 13.390646 -399.964514) (xy 13.315752 -399.992251) (xy 13.238437 -400.01227)
			(xy 13.159493 -400.024363) (xy 13.07973 -400.028409) (xy 12.999967 -400.024363) (xy 12.921023 -400.01227)
			(xy 12.843708 -399.992251) (xy 12.768814 -399.964514) (xy 12.697111 -399.929342) (xy 12.629334 -399.887096)
			(xy 12.566178 -399.83821) (xy 12.508293 -399.783186) (xy 12.456271 -399.722587) (xy 12.410647 -399.657037)
			(xy 12.371888 -399.587207) (xy 12.340393 -399.513814) (xy 12.316484 -399.437612) (xy 12.300407 -399.359382)
			(xy 12.292327 -399.279927) (xy 6.247133 -399.279927) (xy 6.239053 -399.359382) (xy 6.222976 -399.437612)
			(xy 6.199067 -399.513814) (xy 6.167572 -399.587207) (xy 6.128813 -399.657037) (xy 6.083189 -399.722587)
			(xy 6.031167 -399.783186) (xy 5.973282 -399.83821) (xy 5.910126 -399.887096) (xy 5.842349 -399.929342)
			(xy 5.770646 -399.964514) (xy 5.695752 -399.992251) (xy 5.618437 -400.01227) (xy 5.539493 -400.024363)
			(xy 5.45973 -400.028409) (xy 5.379967 -400.024363) (xy 5.301023 -400.01227) (xy 5.223708 -399.992251)
			(xy 5.148814 -399.964514) (xy 5.077111 -399.929342) (xy 5.009334 -399.887096) (xy 4.946178 -399.83821)
			(xy 4.888293 -399.783186) (xy 4.836271 -399.722587) (xy 4.790647 -399.657037) (xy 4.751888 -399.587207)
			(xy 4.720393 -399.513814) (xy 4.696484 -399.437612) (xy 4.680407 -399.359382) (xy 4.672327 -399.279927)
			(xy 3.757171 -399.279927) (xy 3.749091 -399.359382) (xy 3.733014 -399.437612) (xy 3.709105 -399.513814)
			(xy 3.67761 -399.587207) (xy 3.638851 -399.657037) (xy 3.593227 -399.722587) (xy 3.541205 -399.783186)
			(xy 3.48332 -399.83821) (xy 3.420164 -399.887096) (xy 3.352387 -399.929342) (xy 3.280684 -399.964514)
			(xy 3.20579 -399.992251) (xy 3.128475 -400.01227) (xy 3.049531 -400.024363) (xy 2.969768 -400.028409)
			(xy 2.890005 -400.024363) (xy 2.811061 -400.01227) (xy 2.733746 -399.992251) (xy 2.658852 -399.964514)
			(xy 2.587149 -399.929342) (xy 2.519372 -399.887096) (xy 2.456216 -399.83821) (xy 2.398331 -399.783186)
			(xy 2.346309 -399.722587) (xy 2.300685 -399.657037) (xy 2.261926 -399.587207) (xy 2.230431 -399.513814)
			(xy 2.206522 -399.437612) (xy 2.190445 -399.359382) (xy 2.182365 -399.279927) (xy 1.27 -399.279927)
			(xy 1.27 -403.413036) (xy 1.547863 -403.413036) (xy 1.547863 -403.2869) (xy 1.555783 -403.161012)
			(xy 1.571593 -403.03587) (xy 1.595228 -402.911967) (xy 1.626597 -402.789794) (xy 1.665575 -402.669831)
			(xy 1.712009 -402.552552) (xy 1.765716 -402.43842) (xy 1.826483 -402.327885) (xy 1.89407 -402.221385)
			(xy 1.968211 -402.119338) (xy 2.048614 -402.022148) (xy 2.13496 -401.930198) (xy 2.22691 -401.843852)
			(xy 2.3241 -401.763449) (xy 2.426147 -401.689308) (xy 2.532647 -401.621721) (xy 2.643182 -401.560954)
			(xy 2.757314 -401.507247) (xy 2.874593 -401.460813) (xy 2.994556 -401.421835) (xy 3.116729 -401.390466)
			(xy 3.240632 -401.366831) (xy 3.365774 -401.351021) (xy 3.491662 -401.343101) (xy 3.617798 -401.343101)
			(xy 3.743686 -401.351021) (xy 3.868828 -401.366831) (xy 3.992731 -401.390466) (xy 4.114904 -401.421835)
			(xy 4.234867 -401.460813) (xy 4.352146 -401.507247) (xy 4.466278 -401.560954) (xy 4.576813 -401.621721)
			(xy 4.683313 -401.689308) (xy 4.78536 -401.763449) (xy 4.88255 -401.843852) (xy 4.9745 -401.930198)
			(xy 5.060846 -402.022148) (xy 5.141249 -402.119338) (xy 5.21539 -402.221385) (xy 5.282977 -402.327885)
			(xy 5.343744 -402.43842) (xy 5.397451 -402.552552) (xy 5.443885 -402.669831) (xy 5.482863 -402.789794)
			(xy 5.514232 -402.911967) (xy 5.537867 -403.03587) (xy 5.553677 -403.161012) (xy 5.561597 -403.2869)
			(xy 5.562092 -403.349968) (xy 5.561597 -403.413036) (xy 12.977863 -403.413036) (xy 12.977863 -403.2869)
			(xy 12.985783 -403.161012) (xy 13.001593 -403.03587) (xy 13.025228 -402.911967) (xy 13.056597 -402.789794)
			(xy 13.095575 -402.669831) (xy 13.142009 -402.552552) (xy 13.195716 -402.43842) (xy 13.256483 -402.327885)
			(xy 13.32407 -402.221385) (xy 13.398211 -402.119338) (xy 13.478614 -402.022148) (xy 13.56496 -401.930198)
			(xy 13.65691 -401.843852) (xy 13.7541 -401.763449) (xy 13.856147 -401.689308) (xy 13.962647 -401.621721)
			(xy 14.073182 -401.560954) (xy 14.187314 -401.507247) (xy 14.304593 -401.460813) (xy 14.424556 -401.421835)
			(xy 14.546729 -401.390466) (xy 14.670632 -401.366831) (xy 14.795774 -401.351021) (xy 14.921662 -401.343101)
			(xy 15.047798 -401.343101) (xy 15.173686 -401.351021) (xy 15.298828 -401.366831) (xy 15.422731 -401.390466)
			(xy 15.544904 -401.421835) (xy 15.664867 -401.460813) (xy 15.782146 -401.507247) (xy 15.896278 -401.560954)
			(xy 16.006813 -401.621721) (xy 16.113313 -401.689308) (xy 16.21536 -401.763449) (xy 16.31255 -401.843852)
			(xy 16.4045 -401.930198) (xy 16.490846 -402.022148) (xy 16.571249 -402.119338) (xy 16.64539 -402.221385)
			(xy 16.712977 -402.327885) (xy 16.773744 -402.43842) (xy 16.827451 -402.552552) (xy 16.873885 -402.669831)
			(xy 16.912863 -402.789794) (xy 16.944232 -402.911967) (xy 16.967867 -403.03587) (xy 16.983677 -403.161012)
			(xy 16.991597 -403.2869) (xy 16.992092 -403.349968) (xy 16.991597 -403.413036) (xy 16.983677 -403.538924)
			(xy 16.967867 -403.664066) (xy 16.944232 -403.787969) (xy 16.912863 -403.910142) (xy 16.873885 -404.030105)
			(xy 16.827451 -404.147384) (xy 16.773744 -404.261516) (xy 16.712977 -404.372051) (xy 16.64539 -404.478551)
			(xy 16.571249 -404.580598) (xy 16.490846 -404.677788) (xy 16.4045 -404.769738) (xy 16.31255 -404.856084)
			(xy 16.21536 -404.936487) (xy 16.113313 -405.010628) (xy 16.006813 -405.078215) (xy 15.896278 -405.138982)
			(xy 15.782146 -405.192689) (xy 15.664867 -405.239123) (xy 15.544904 -405.278101) (xy 15.422731 -405.30947)
			(xy 15.298828 -405.333105) (xy 15.173686 -405.348915) (xy 15.047798 -405.356835) (xy 14.921662 -405.356835)
			(xy 14.795774 -405.348915) (xy 14.670632 -405.333105) (xy 14.546729 -405.30947) (xy 14.424556 -405.278101)
			(xy 14.304593 -405.239123) (xy 14.187314 -405.192689) (xy 14.073182 -405.138982) (xy 13.962647 -405.078215)
			(xy 13.856147 -405.010628) (xy 13.7541 -404.936487) (xy 13.65691 -404.856084) (xy 13.56496 -404.769738)
			(xy 13.478614 -404.677788) (xy 13.398211 -404.580598) (xy 13.32407 -404.478551) (xy 13.256483 -404.372051)
			(xy 13.195716 -404.261516) (xy 13.142009 -404.147384) (xy 13.095575 -404.030105) (xy 13.056597 -403.910142)
			(xy 13.025228 -403.787969) (xy 13.001593 -403.664066) (xy 12.985783 -403.538924) (xy 12.977863 -403.413036)
			(xy 5.561597 -403.413036) (xy 5.553677 -403.538924) (xy 5.537867 -403.664066) (xy 5.514232 -403.787969)
			(xy 5.482863 -403.910142) (xy 5.443885 -404.030105) (xy 5.397451 -404.147384) (xy 5.343744 -404.261516)
			(xy 5.282977 -404.372051) (xy 5.21539 -404.478551) (xy 5.141249 -404.580598) (xy 5.060846 -404.677788)
			(xy 4.9745 -404.769738) (xy 4.88255 -404.856084) (xy 4.78536 -404.936487) (xy 4.683313 -405.010628)
			(xy 4.576813 -405.078215) (xy 4.466278 -405.138982) (xy 4.352146 -405.192689) (xy 4.234867 -405.239123)
			(xy 4.114904 -405.278101) (xy 3.992731 -405.30947) (xy 3.868828 -405.333105) (xy 3.743686 -405.348915)
			(xy 3.617798 -405.356835) (xy 3.491662 -405.356835) (xy 3.365774 -405.348915) (xy 3.240632 -405.333105)
			(xy 3.116729 -405.30947) (xy 2.994556 -405.278101) (xy 2.874593 -405.239123) (xy 2.757314 -405.192689)
			(xy 2.643182 -405.138982) (xy 2.532647 -405.078215) (xy 2.426147 -405.010628) (xy 2.3241 -404.936487)
			(xy 2.22691 -404.856084) (xy 2.13496 -404.769738) (xy 2.048614 -404.677788) (xy 1.968211 -404.580598)
			(xy 1.89407 -404.478551) (xy 1.826483 -404.372051) (xy 1.765716 -404.261516) (xy 1.712009 -404.147384)
			(xy 1.665575 -404.030105) (xy 1.626597 -403.910142) (xy 1.595228 -403.787969) (xy 1.571593 -403.664066)
			(xy 1.555783 -403.538924) (xy 1.547863 -403.413036) (xy 1.27 -403.413036) (xy 1.27 -405.764238) (xy 1.39573 -405.890222)
			(xy 1.445514 -405.892254) (xy 1.496866 -405.894742) (xy 1.598977 -405.906784) (xy 1.699829 -405.926804)
			(xy 1.798798 -405.954676) (xy 1.895275 -405.99023) (xy 1.988663 -406.033246) (xy 2.078388 -406.083458)
			(xy 2.163895 -406.140557) (xy 2.244657 -406.204191) (xy 2.320176 -406.273967) (xy 2.389986 -406.349454)
			(xy 2.453656 -406.430188) (xy 2.510794 -406.515669) (xy 2.561047 -406.605371) (xy 2.604104 -406.69874)
			(xy 2.639702 -406.795201) (xy 2.667619 -406.894158) (xy 2.687684 -406.995) (xy 2.699772 -407.097106)
			(xy 2.70381 -407.199846) (xy 2.70179 -407.251242) (xy 15.836642 -407.251242) (xy 15.836642 -407.14845)
			(xy 15.844707 -407.045976) (xy 15.860787 -406.944451) (xy 15.884783 -406.8445) (xy 15.916548 -406.74674)
			(xy 15.955884 -406.651773) (xy 16.00255 -406.560186) (xy 16.056258 -406.472542) (xy 16.116677 -406.389382)
			(xy 16.183435 -406.311219) (xy 16.256119 -406.238535) (xy 16.334282 -406.171777) (xy 16.417442 -406.111358)
			(xy 16.505086 -406.05765) (xy 16.596673 -406.010984) (xy 16.69164 -405.971648) (xy 16.7894 -405.939883)
			(xy 16.889351 -405.915887) (xy 16.990876 -405.899807) (xy 17.09335 -405.891742) (xy 17.196142 -405.891742)
			(xy 17.298616 -405.899807) (xy 17.400141 -405.915887) (xy 17.500092 -405.939883) (xy 17.597852 -405.971648)
			(xy 17.692819 -406.010984) (xy 17.784406 -406.05765) (xy 17.87205 -406.111358) (xy 17.95521 -406.171777)
			(xy 18.033373 -406.238535) (xy 18.106057 -406.311219) (xy 18.172815 -406.389382) (xy 18.233234 -406.472542)
			(xy 18.286942 -406.560186) (xy 18.333608 -406.651773) (xy 18.372944 -406.74674) (xy 18.404709 -406.8445)
			(xy 18.428705 -406.944451) (xy 18.444785 -407.045976) (xy 18.45285 -407.14845) (xy 18.453354 -407.199846)
			(xy 18.45285 -407.251242) (xy 18.444785 -407.353716) (xy 18.428705 -407.455241) (xy 18.404709 -407.555192)
			(xy 18.372944 -407.652952) (xy 18.333608 -407.747919) (xy 18.286942 -407.839506) (xy 18.233234 -407.92715)
			(xy 18.172815 -408.01031) (xy 18.106057 -408.088473) (xy 18.033373 -408.161157) (xy 17.95521 -408.227915)
			(xy 17.87205 -408.288334) (xy 17.784406 -408.342042) (xy 17.692819 -408.388708) (xy 17.597852 -408.428044)
			(xy 17.500092 -408.459809) (xy 17.400141 -408.483805) (xy 17.298616 -408.499885) (xy 17.196142 -408.50795)
			(xy 17.09335 -408.50795) (xy 16.990876 -408.499885) (xy 16.889351 -408.483805) (xy 16.7894 -408.459809)
			(xy 16.69164 -408.428044) (xy 16.596673 -408.388708) (xy 16.505086 -408.342042) (xy 16.417442 -408.288334)
			(xy 16.334282 -408.227915) (xy 16.256119 -408.161157) (xy 16.183435 -408.088473) (xy 16.116677 -408.01031)
			(xy 16.056258 -407.92715) (xy 16.00255 -407.839506) (xy 15.955884 -407.747919) (xy 15.916548 -407.652952)
			(xy 15.884783 -407.555192) (xy 15.860787 -407.455241) (xy 15.844707 -407.353716) (xy 15.836642 -407.251242)
			(xy 2.70179 -407.251242) (xy 2.699772 -407.302586) (xy 2.687684 -407.404692) (xy 2.667619 -407.505534)
			(xy 2.639702 -407.604491) (xy 2.604104 -407.700952) (xy 2.561047 -407.794321) (xy 2.510794 -407.884023)
			(xy 2.453656 -407.969504) (xy 2.389986 -408.050238) (xy 2.320176 -408.125725) (xy 2.244657 -408.195501)
			(xy 2.163895 -408.259135) (xy 2.078388 -408.316234) (xy 1.988663 -408.366446) (xy 1.895275 -408.409462)
			(xy 1.798798 -408.445016) (xy 1.699829 -408.472888) (xy 1.598977 -408.492908) (xy 1.496866 -408.50495)
			(xy 1.445514 -408.507438) (xy 1.39573 -408.50947) (xy 1.27 -408.635454) (xy 1.27 -409.739901) (xy 4.037327 -409.739901)
			(xy 4.037327 -409.660035) (xy 4.045407 -409.58058) (xy 4.061484 -409.50235) (xy 4.085393 -409.426148)
			(xy 4.116888 -409.352755) (xy 4.155647 -409.282925) (xy 4.201271 -409.217375) (xy 4.253293 -409.156776)
			(xy 4.311178 -409.101752) (xy 4.374334 -409.052866) (xy 4.442111 -409.01062) (xy 4.513814 -408.975448)
			(xy 4.588708 -408.947711) (xy 4.666023 -408.927692) (xy 4.744967 -408.915599) (xy 4.82473 -408.911554)
			(xy 4.904493 -408.915599) (xy 4.983437 -408.927692) (xy 5.060752 -408.947711) (xy 5.135646 -408.975448)
			(xy 5.207349 -409.01062) (xy 5.275126 -409.052866) (xy 5.338282 -409.101752) (xy 5.396167 -409.156776)
			(xy 5.448189 -409.217375) (xy 5.493813 -409.282925) (xy 5.532572 -409.352755) (xy 5.564067 -409.426148)
			(xy 5.587976 -409.50235) (xy 5.604053 -409.58058) (xy 5.612133 -409.660035) (xy 5.612638 -409.699968)
			(xy 5.612133 -409.739901) (xy 6.577327 -409.739901) (xy 6.577327 -409.660035) (xy 6.585407 -409.58058)
			(xy 6.601484 -409.50235) (xy 6.625393 -409.426148) (xy 6.656888 -409.352755) (xy 6.695647 -409.282925)
			(xy 6.741271 -409.217375) (xy 6.793293 -409.156776) (xy 6.851178 -409.101752) (xy 6.914334 -409.052866)
			(xy 6.982111 -409.01062) (xy 7.053814 -408.975448) (xy 7.128708 -408.947711) (xy 7.206023 -408.927692)
			(xy 7.284967 -408.915599) (xy 7.36473 -408.911554) (xy 7.444493 -408.915599) (xy 7.523437 -408.927692)
			(xy 7.600752 -408.947711) (xy 7.675646 -408.975448) (xy 7.747349 -409.01062) (xy 7.815126 -409.052866)
			(xy 7.878282 -409.101752) (xy 7.936167 -409.156776) (xy 7.988189 -409.217375) (xy 8.033813 -409.282925)
			(xy 8.072572 -409.352755) (xy 8.104067 -409.426148) (xy 8.127976 -409.50235) (xy 8.144053 -409.58058)
			(xy 8.152133 -409.660035) (xy 8.152638 -409.699968) (xy 8.152133 -409.739901) (xy 9.117327 -409.739901)
			(xy 9.117327 -409.660035) (xy 9.125407 -409.58058) (xy 9.141484 -409.50235) (xy 9.165393 -409.426148)
			(xy 9.196888 -409.352755) (xy 9.235647 -409.282925) (xy 9.281271 -409.217375) (xy 9.333293 -409.156776)
			(xy 9.391178 -409.101752) (xy 9.454334 -409.052866) (xy 9.522111 -409.01062) (xy 9.593814 -408.975448)
			(xy 9.668708 -408.947711) (xy 9.746023 -408.927692) (xy 9.824967 -408.915599) (xy 9.90473 -408.911554)
			(xy 9.984493 -408.915599) (xy 10.063437 -408.927692) (xy 10.140752 -408.947711) (xy 10.215646 -408.975448)
			(xy 10.287349 -409.01062) (xy 10.355126 -409.052866) (xy 10.418282 -409.101752) (xy 10.476167 -409.156776)
			(xy 10.528189 -409.217375) (xy 10.573813 -409.282925) (xy 10.612572 -409.352755) (xy 10.644067 -409.426148)
			(xy 10.667976 -409.50235) (xy 10.684053 -409.58058) (xy 10.692133 -409.660035) (xy 10.692638 -409.699968)
			(xy 10.692133 -409.739901) (xy 11.657327 -409.739901) (xy 11.657327 -409.660035) (xy 11.665407 -409.58058)
			(xy 11.681484 -409.50235) (xy 11.705393 -409.426148) (xy 11.736888 -409.352755) (xy 11.775647 -409.282925)
			(xy 11.821271 -409.217375) (xy 11.873293 -409.156776) (xy 11.931178 -409.101752) (xy 11.994334 -409.052866)
			(xy 12.062111 -409.01062) (xy 12.133814 -408.975448) (xy 12.208708 -408.947711) (xy 12.286023 -408.927692)
			(xy 12.364967 -408.915599) (xy 12.44473 -408.911554) (xy 12.524493 -408.915599) (xy 12.603437 -408.927692)
			(xy 12.680752 -408.947711) (xy 12.755646 -408.975448) (xy 12.827349 -409.01062) (xy 12.895126 -409.052866)
			(xy 12.958282 -409.101752) (xy 13.016167 -409.156776) (xy 13.068189 -409.217375) (xy 13.113813 -409.282925)
			(xy 13.152572 -409.352755) (xy 13.184067 -409.426148) (xy 13.207976 -409.50235) (xy 13.224053 -409.58058)
			(xy 13.232133 -409.660035) (xy 13.232638 -409.699968) (xy 13.232133 -409.739901) (xy 13.224053 -409.819356)
			(xy 13.207976 -409.897586) (xy 13.184067 -409.973788) (xy 13.152572 -410.047181) (xy 13.113813 -410.117011)
			(xy 13.068189 -410.182561) (xy 13.016167 -410.24316) (xy 12.958282 -410.298184) (xy 12.895126 -410.34707)
			(xy 12.827349 -410.389316) (xy 12.755646 -410.424488) (xy 12.680752 -410.452225) (xy 12.603437 -410.472244)
			(xy 12.524493 -410.484337) (xy 12.44473 -410.488383) (xy 12.364967 -410.484337) (xy 12.286023 -410.472244)
			(xy 12.208708 -410.452225) (xy 12.133814 -410.424488) (xy 12.062111 -410.389316) (xy 11.994334 -410.34707)
			(xy 11.931178 -410.298184) (xy 11.873293 -410.24316) (xy 11.821271 -410.182561) (xy 11.775647 -410.117011)
			(xy 11.736888 -410.047181) (xy 11.705393 -409.973788) (xy 11.681484 -409.897586) (xy 11.665407 -409.819356)
			(xy 11.657327 -409.739901) (xy 10.692133 -409.739901) (xy 10.684053 -409.819356) (xy 10.667976 -409.897586)
			(xy 10.644067 -409.973788) (xy 10.612572 -410.047181) (xy 10.573813 -410.117011) (xy 10.528189 -410.182561)
			(xy 10.476167 -410.24316) (xy 10.418282 -410.298184) (xy 10.355126 -410.34707) (xy 10.287349 -410.389316)
			(xy 10.215646 -410.424488) (xy 10.140752 -410.452225) (xy 10.063437 -410.472244) (xy 9.984493 -410.484337)
			(xy 9.90473 -410.488383) (xy 9.824967 -410.484337) (xy 9.746023 -410.472244) (xy 9.668708 -410.452225)
			(xy 9.593814 -410.424488) (xy 9.522111 -410.389316) (xy 9.454334 -410.34707) (xy 9.391178 -410.298184)
			(xy 9.333293 -410.24316) (xy 9.281271 -410.182561) (xy 9.235647 -410.117011) (xy 9.196888 -410.047181)
			(xy 9.165393 -409.973788) (xy 9.141484 -409.897586) (xy 9.125407 -409.819356) (xy 9.117327 -409.739901)
			(xy 8.152133 -409.739901) (xy 8.144053 -409.819356) (xy 8.127976 -409.897586) (xy 8.104067 -409.973788)
			(xy 8.072572 -410.047181) (xy 8.033813 -410.117011) (xy 7.988189 -410.182561) (xy 7.936167 -410.24316)
			(xy 7.878282 -410.298184) (xy 7.815126 -410.34707) (xy 7.747349 -410.389316) (xy 7.675646 -410.424488)
			(xy 7.600752 -410.452225) (xy 7.523437 -410.472244) (xy 7.444493 -410.484337) (xy 7.36473 -410.488383)
			(xy 7.284967 -410.484337) (xy 7.206023 -410.472244) (xy 7.128708 -410.452225) (xy 7.053814 -410.424488)
			(xy 6.982111 -410.389316) (xy 6.914334 -410.34707) (xy 6.851178 -410.298184) (xy 6.793293 -410.24316)
			(xy 6.741271 -410.182561) (xy 6.695647 -410.117011) (xy 6.656888 -410.047181) (xy 6.625393 -409.973788)
			(xy 6.601484 -409.897586) (xy 6.585407 -409.819356) (xy 6.577327 -409.739901) (xy 5.612133 -409.739901)
			(xy 5.604053 -409.819356) (xy 5.587976 -409.897586) (xy 5.564067 -409.973788) (xy 5.532572 -410.047181)
			(xy 5.493813 -410.117011) (xy 5.448189 -410.182561) (xy 5.396167 -410.24316) (xy 5.338282 -410.298184)
			(xy 5.275126 -410.34707) (xy 5.207349 -410.389316) (xy 5.135646 -410.424488) (xy 5.060752 -410.452225)
			(xy 4.983437 -410.472244) (xy 4.904493 -410.484337) (xy 4.82473 -410.488383) (xy 4.744967 -410.484337)
			(xy 4.666023 -410.472244) (xy 4.588708 -410.452225) (xy 4.513814 -410.424488) (xy 4.442111 -410.389316)
			(xy 4.374334 -410.34707) (xy 4.311178 -410.298184) (xy 4.253293 -410.24316) (xy 4.201271 -410.182561)
			(xy 4.155647 -410.117011) (xy 4.116888 -410.047181) (xy 4.085393 -409.973788) (xy 4.061484 -409.897586)
			(xy 4.045407 -409.819356) (xy 4.037327 -409.739901) (xy 1.27 -409.739901) (xy 1.27 -412.279901) (xy 5.307327 -412.279901)
			(xy 5.307327 -412.200035) (xy 5.315407 -412.12058) (xy 5.331484 -412.04235) (xy 5.355393 -411.966148)
			(xy 5.386888 -411.892755) (xy 5.425647 -411.822925) (xy 5.471271 -411.757375) (xy 5.523293 -411.696776)
			(xy 5.581178 -411.641752) (xy 5.644334 -411.592866) (xy 5.712111 -411.55062) (xy 5.783814 -411.515448)
			(xy 5.858708 -411.487711) (xy 5.936023 -411.467692) (xy 6.014967 -411.455599) (xy 6.09473 -411.451554)
			(xy 6.174493 -411.455599) (xy 6.253437 -411.467692) (xy 6.330752 -411.487711) (xy 6.405646 -411.515448)
			(xy 6.477349 -411.55062) (xy 6.545126 -411.592866) (xy 6.608282 -411.641752) (xy 6.666167 -411.696776)
			(xy 6.718189 -411.757375) (xy 6.763813 -411.822925) (xy 6.802572 -411.892755) (xy 6.834067 -411.966148)
			(xy 6.857976 -412.04235) (xy 6.874053 -412.12058) (xy 6.882133 -412.200035) (xy 6.882638 -412.239968)
			(xy 6.882133 -412.279901) (xy 7.847327 -412.279901) (xy 7.847327 -412.200035) (xy 7.855407 -412.12058)
			(xy 7.871484 -412.04235) (xy 7.895393 -411.966148) (xy 7.926888 -411.892755) (xy 7.965647 -411.822925)
			(xy 8.011271 -411.757375) (xy 8.063293 -411.696776) (xy 8.121178 -411.641752) (xy 8.184334 -411.592866)
			(xy 8.252111 -411.55062) (xy 8.323814 -411.515448) (xy 8.398708 -411.487711) (xy 8.476023 -411.467692)
			(xy 8.554967 -411.455599) (xy 8.63473 -411.451554) (xy 8.714493 -411.455599) (xy 8.793437 -411.467692)
			(xy 8.870752 -411.487711) (xy 8.945646 -411.515448) (xy 9.017349 -411.55062) (xy 9.085126 -411.592866)
			(xy 9.148282 -411.641752) (xy 9.206167 -411.696776) (xy 9.258189 -411.757375) (xy 9.303813 -411.822925)
			(xy 9.342572 -411.892755) (xy 9.374067 -411.966148) (xy 9.397976 -412.04235) (xy 9.414053 -412.12058)
			(xy 9.422133 -412.200035) (xy 9.422638 -412.239968) (xy 9.422133 -412.279901) (xy 10.387327 -412.279901)
			(xy 10.387327 -412.200035) (xy 10.395407 -412.12058) (xy 10.411484 -412.04235) (xy 10.435393 -411.966148)
			(xy 10.466888 -411.892755) (xy 10.505647 -411.822925) (xy 10.551271 -411.757375) (xy 10.603293 -411.696776)
			(xy 10.661178 -411.641752) (xy 10.724334 -411.592866) (xy 10.792111 -411.55062) (xy 10.863814 -411.515448)
			(xy 10.938708 -411.487711) (xy 11.016023 -411.467692) (xy 11.094967 -411.455599) (xy 11.17473 -411.451554)
			(xy 11.254493 -411.455599) (xy 11.333437 -411.467692) (xy 11.410752 -411.487711) (xy 11.485646 -411.515448)
			(xy 11.557349 -411.55062) (xy 11.625126 -411.592866) (xy 11.688282 -411.641752) (xy 11.746167 -411.696776)
			(xy 11.798189 -411.757375) (xy 11.843813 -411.822925) (xy 11.882572 -411.892755) (xy 11.914067 -411.966148)
			(xy 11.937976 -412.04235) (xy 11.954053 -412.12058) (xy 11.962133 -412.200035) (xy 11.962638 -412.239968)
			(xy 11.962133 -412.279901) (xy 12.927327 -412.279901) (xy 12.927327 -412.200035) (xy 12.935407 -412.12058)
			(xy 12.951484 -412.04235) (xy 12.975393 -411.966148) (xy 13.006888 -411.892755) (xy 13.045647 -411.822925)
			(xy 13.091271 -411.757375) (xy 13.143293 -411.696776) (xy 13.201178 -411.641752) (xy 13.264334 -411.592866)
			(xy 13.332111 -411.55062) (xy 13.403814 -411.515448) (xy 13.478708 -411.487711) (xy 13.556023 -411.467692)
			(xy 13.634967 -411.455599) (xy 13.71473 -411.451554) (xy 13.794493 -411.455599) (xy 13.873437 -411.467692)
			(xy 13.950752 -411.487711) (xy 14.025646 -411.515448) (xy 14.097349 -411.55062) (xy 14.165126 -411.592866)
			(xy 14.228282 -411.641752) (xy 14.286167 -411.696776) (xy 14.338189 -411.757375) (xy 14.383813 -411.822925)
			(xy 14.422572 -411.892755) (xy 14.454067 -411.966148) (xy 14.477976 -412.04235) (xy 14.494053 -412.12058)
			(xy 14.502133 -412.200035) (xy 14.502638 -412.239968) (xy 14.502133 -412.279901) (xy 14.494053 -412.359356)
			(xy 14.477976 -412.437586) (xy 14.454067 -412.513788) (xy 14.422572 -412.587181) (xy 14.383813 -412.657011)
			(xy 14.338189 -412.722561) (xy 14.286167 -412.78316) (xy 14.228282 -412.838184) (xy 14.165126 -412.88707)
			(xy 14.097349 -412.929316) (xy 14.025646 -412.964488) (xy 13.950752 -412.992225) (xy 13.873437 -413.012244)
			(xy 13.794493 -413.024337) (xy 13.71473 -413.028383) (xy 13.634967 -413.024337) (xy 13.556023 -413.012244)
			(xy 13.478708 -412.992225) (xy 13.403814 -412.964488) (xy 13.332111 -412.929316) (xy 13.264334 -412.88707)
			(xy 13.201178 -412.838184) (xy 13.143293 -412.78316) (xy 13.091271 -412.722561) (xy 13.045647 -412.657011)
			(xy 13.006888 -412.587181) (xy 12.975393 -412.513788) (xy 12.951484 -412.437586) (xy 12.935407 -412.359356)
			(xy 12.927327 -412.279901) (xy 11.962133 -412.279901) (xy 11.954053 -412.359356) (xy 11.937976 -412.437586)
			(xy 11.914067 -412.513788) (xy 11.882572 -412.587181) (xy 11.843813 -412.657011) (xy 11.798189 -412.722561)
			(xy 11.746167 -412.78316) (xy 11.688282 -412.838184) (xy 11.625126 -412.88707) (xy 11.557349 -412.929316)
			(xy 11.485646 -412.964488) (xy 11.410752 -412.992225) (xy 11.333437 -413.012244) (xy 11.254493 -413.024337)
			(xy 11.17473 -413.028383) (xy 11.094967 -413.024337) (xy 11.016023 -413.012244) (xy 10.938708 -412.992225)
			(xy 10.863814 -412.964488) (xy 10.792111 -412.929316) (xy 10.724334 -412.88707) (xy 10.661178 -412.838184)
			(xy 10.603293 -412.78316) (xy 10.551271 -412.722561) (xy 10.505647 -412.657011) (xy 10.466888 -412.587181)
			(xy 10.435393 -412.513788) (xy 10.411484 -412.437586) (xy 10.395407 -412.359356) (xy 10.387327 -412.279901)
			(xy 9.422133 -412.279901) (xy 9.414053 -412.359356) (xy 9.397976 -412.437586) (xy 9.374067 -412.513788)
			(xy 9.342572 -412.587181) (xy 9.303813 -412.657011) (xy 9.258189 -412.722561) (xy 9.206167 -412.78316)
			(xy 9.148282 -412.838184) (xy 9.085126 -412.88707) (xy 9.017349 -412.929316) (xy 8.945646 -412.964488)
			(xy 8.870752 -412.992225) (xy 8.793437 -413.012244) (xy 8.714493 -413.024337) (xy 8.63473 -413.028383)
			(xy 8.554967 -413.024337) (xy 8.476023 -413.012244) (xy 8.398708 -412.992225) (xy 8.323814 -412.964488)
			(xy 8.252111 -412.929316) (xy 8.184334 -412.88707) (xy 8.121178 -412.838184) (xy 8.063293 -412.78316)
			(xy 8.011271 -412.722561) (xy 7.965647 -412.657011) (xy 7.926888 -412.587181) (xy 7.895393 -412.513788)
			(xy 7.871484 -412.437586) (xy 7.855407 -412.359356) (xy 7.847327 -412.279901) (xy 6.882133 -412.279901)
			(xy 6.874053 -412.359356) (xy 6.857976 -412.437586) (xy 6.834067 -412.513788) (xy 6.802572 -412.587181)
			(xy 6.763813 -412.657011) (xy 6.718189 -412.722561) (xy 6.666167 -412.78316) (xy 6.608282 -412.838184)
			(xy 6.545126 -412.88707) (xy 6.477349 -412.929316) (xy 6.405646 -412.964488) (xy 6.330752 -412.992225)
			(xy 6.253437 -413.012244) (xy 6.174493 -413.024337) (xy 6.09473 -413.028383) (xy 6.014967 -413.024337)
			(xy 5.936023 -413.012244) (xy 5.858708 -412.992225) (xy 5.783814 -412.964488) (xy 5.712111 -412.929316)
			(xy 5.644334 -412.88707) (xy 5.581178 -412.838184) (xy 5.523293 -412.78316) (xy 5.471271 -412.722561)
			(xy 5.425647 -412.657011) (xy 5.386888 -412.587181) (xy 5.355393 -412.513788) (xy 5.331484 -412.437586)
			(xy 5.315407 -412.359356) (xy 5.307327 -412.279901) (xy 1.27 -412.279901) (xy 1.27 -423.940932) (xy 4.839198 -423.940932)
			(xy 4.839198 -423.84706) (xy 4.847159 -423.753526) (xy 4.863023 -423.661004) (xy 4.886677 -423.570161)
			(xy 4.917949 -423.481652) (xy 4.956615 -423.396113) (xy 5.002396 -423.314161) (xy 5.054962 -423.236387)
			(xy 5.113935 -423.163352) (xy 5.178888 -423.09558) (xy 5.249355 -423.033561) (xy 5.324828 -422.977742)
			(xy 5.404763 -422.928524) (xy 5.488584 -422.886262) (xy 5.575687 -422.851262) (xy 5.665444 -422.823774)
			(xy 5.757209 -422.803997) (xy 5.850321 -422.792074) (xy 5.944108 -422.78809) (xy 6.037895 -422.792074)
			(xy 6.131007 -422.803997) (xy 6.222772 -422.823774) (xy 6.312529 -422.851262) (xy 6.399632 -422.886262)
			(xy 6.483453 -422.928524) (xy 6.563388 -422.977742) (xy 6.638861 -423.033561) (xy 6.709328 -423.09558)
			(xy 6.774281 -423.163352) (xy 6.833254 -423.236387) (xy 6.88582 -423.314161) (xy 6.931601 -423.396113)
			(xy 6.970267 -423.481652) (xy 7.001539 -423.570161) (xy 7.025193 -423.661004) (xy 7.041057 -423.753526)
			(xy 7.049018 -423.84706) (xy 7.049516 -423.893996) (xy 7.049018 -423.940932) (xy 10.339314 -423.940932)
			(xy 10.339314 -423.84706) (xy 10.347275 -423.753526) (xy 10.363139 -423.661004) (xy 10.386793 -423.570161)
			(xy 10.418065 -423.481652) (xy 10.456731 -423.396113) (xy 10.502512 -423.314161) (xy 10.555078 -423.236387)
			(xy 10.614051 -423.163352) (xy 10.679004 -423.09558) (xy 10.749471 -423.033561) (xy 10.824944 -422.977742)
			(xy 10.904879 -422.928524) (xy 10.9887 -422.886262) (xy 11.075803 -422.851262) (xy 11.16556 -422.823774)
			(xy 11.257325 -422.803997) (xy 11.350437 -422.792074) (xy 11.444224 -422.78809) (xy 11.538011 -422.792074)
			(xy 11.631123 -422.803997) (xy 11.722888 -422.823774) (xy 11.812645 -422.851262) (xy 11.899748 -422.886262)
			(xy 11.983569 -422.928524) (xy 12.063504 -422.977742) (xy 12.138977 -423.033561) (xy 12.209444 -423.09558)
			(xy 12.274397 -423.163352) (xy 12.33337 -423.236387) (xy 12.385936 -423.314161) (xy 12.431717 -423.396113)
			(xy 12.470383 -423.481652) (xy 12.501655 -423.570161) (xy 12.525309 -423.661004) (xy 12.541173 -423.753526)
			(xy 12.549134 -423.84706) (xy 12.549632 -423.893996) (xy 12.549134 -423.940932) (xy 12.541173 -424.034466)
			(xy 12.525309 -424.126988) (xy 12.501655 -424.217831) (xy 12.470383 -424.30634) (xy 12.431717 -424.391879)
			(xy 12.385936 -424.473831) (xy 12.33337 -424.551605) (xy 12.274397 -424.62464) (xy 12.209444 -424.692412)
			(xy 12.138977 -424.754431) (xy 12.063504 -424.81025) (xy 11.983569 -424.859468) (xy 11.899748 -424.90173)
			(xy 11.812645 -424.93673) (xy 11.722888 -424.964218) (xy 11.631123 -424.983995) (xy 11.538011 -424.995918)
			(xy 11.444224 -424.999903) (xy 11.350437 -424.995918) (xy 11.257325 -424.983995) (xy 11.16556 -424.964218)
			(xy 11.075803 -424.93673) (xy 10.9887 -424.90173) (xy 10.904879 -424.859468) (xy 10.824944 -424.81025)
			(xy 10.749471 -424.754431) (xy 10.679004 -424.692412) (xy 10.614051 -424.62464) (xy 10.555078 -424.551605)
			(xy 10.502512 -424.473831) (xy 10.456731 -424.391879) (xy 10.418065 -424.30634) (xy 10.386793 -424.217831)
			(xy 10.363139 -424.126988) (xy 10.347275 -424.034466) (xy 10.339314 -423.940932) (xy 7.049018 -423.940932)
			(xy 7.041057 -424.034466) (xy 7.025193 -424.126988) (xy 7.001539 -424.217831) (xy 6.970267 -424.30634)
			(xy 6.931601 -424.391879) (xy 6.88582 -424.473831) (xy 6.833254 -424.551605) (xy 6.774281 -424.62464)
			(xy 6.709328 -424.692412) (xy 6.638861 -424.754431) (xy 6.563388 -424.81025) (xy 6.483453 -424.859468)
			(xy 6.399632 -424.90173) (xy 6.312529 -424.93673) (xy 6.222772 -424.964218) (xy 6.131007 -424.983995)
			(xy 6.037895 -424.995918) (xy 5.944108 -424.999903) (xy 5.850321 -424.995918) (xy 5.757209 -424.983995)
			(xy 5.665444 -424.964218) (xy 5.575687 -424.93673) (xy 5.488584 -424.90173) (xy 5.404763 -424.859468)
			(xy 5.324828 -424.81025) (xy 5.249355 -424.754431) (xy 5.178888 -424.692412) (xy 5.113935 -424.62464)
			(xy 5.054962 -424.551605) (xy 5.002396 -424.473831) (xy 4.956615 -424.391879) (xy 4.917949 -424.30634)
			(xy 4.886677 -424.217831) (xy 4.863023 -424.126988) (xy 4.847159 -424.034466) (xy 4.839198 -423.940932)
			(xy 1.27 -423.940932) (xy 1.27 -428.141076) (xy 4.839198 -428.141076) (xy 4.839198 -428.047204) (xy 4.847159 -427.95367)
			(xy 4.863023 -427.861148) (xy 4.886677 -427.770305) (xy 4.917949 -427.681796) (xy 4.956615 -427.596257)
			(xy 5.002396 -427.514305) (xy 5.054962 -427.436531) (xy 5.113935 -427.363496) (xy 5.178888 -427.295724)
			(xy 5.249355 -427.233705) (xy 5.324828 -427.177886) (xy 5.404763 -427.128668) (xy 5.488584 -427.086406)
			(xy 5.575687 -427.051406) (xy 5.665444 -427.023918) (xy 5.757209 -427.004141) (xy 5.850321 -426.992218)
			(xy 5.944108 -426.988234) (xy 6.037895 -426.992218) (xy 6.131007 -427.004141) (xy 6.222772 -427.023918)
			(xy 6.312529 -427.051406) (xy 6.399632 -427.086406) (xy 6.483453 -427.128668) (xy 6.563388 -427.177886)
			(xy 6.638861 -427.233705) (xy 6.709328 -427.295724) (xy 6.774281 -427.363496) (xy 6.833254 -427.436531)
			(xy 6.88582 -427.514305) (xy 6.931601 -427.596257) (xy 6.970267 -427.681796) (xy 7.001539 -427.770305)
			(xy 7.025193 -427.861148) (xy 7.041057 -427.95367) (xy 7.049018 -428.047204) (xy 7.049516 -428.09414)
			(xy 7.049018 -428.141076) (xy 7.041057 -428.23461) (xy 7.025193 -428.327132) (xy 7.001539 -428.417975)
			(xy 6.970267 -428.506484) (xy 6.931601 -428.592023) (xy 6.88582 -428.673975) (xy 6.833254 -428.751749)
			(xy 6.774281 -428.824784) (xy 6.709328 -428.892556) (xy 6.638861 -428.954575) (xy 6.563388 -429.010394)
			(xy 6.483453 -429.059612) (xy 6.399632 -429.101874) (xy 6.312529 -429.136874) (xy 6.222772 -429.164362)
			(xy 6.131007 -429.184139) (xy 6.037895 -429.196062) (xy 5.944108 -429.200047) (xy 5.850321 -429.196062)
			(xy 5.757209 -429.184139) (xy 5.665444 -429.164362) (xy 5.575687 -429.136874) (xy 5.488584 -429.101874)
			(xy 5.404763 -429.059612) (xy 5.324828 -429.010394) (xy 5.249355 -428.954575) (xy 5.178888 -428.892556)
			(xy 5.113935 -428.824784) (xy 5.054962 -428.751749) (xy 5.002396 -428.673975) (xy 4.956615 -428.592023)
			(xy 4.917949 -428.506484) (xy 4.886677 -428.417975) (xy 4.863023 -428.327132) (xy 4.847159 -428.23461)
			(xy 4.839198 -428.141076) (xy 1.27 -428.141076) (xy 1.27 -432.340966) (xy 4.839198 -432.340966) (xy 4.839198 -432.247094)
			(xy 4.847159 -432.15356) (xy 4.863023 -432.061038) (xy 4.886677 -431.970195) (xy 4.917949 -431.881686)
			(xy 4.956615 -431.796147) (xy 5.002396 -431.714195) (xy 5.054962 -431.636421) (xy 5.113935 -431.563386)
			(xy 5.178888 -431.495614) (xy 5.249355 -431.433595) (xy 5.324828 -431.377776) (xy 5.404763 -431.328558)
			(xy 5.488584 -431.286296) (xy 5.575687 -431.251296) (xy 5.665444 -431.223808) (xy 5.757209 -431.204031)
			(xy 5.850321 -431.192108) (xy 5.944108 -431.188124) (xy 6.037895 -431.192108) (xy 6.131007 -431.204031)
			(xy 6.222772 -431.223808) (xy 6.312529 -431.251296) (xy 6.399632 -431.286296) (xy 6.483453 -431.328558)
			(xy 6.563388 -431.377776) (xy 6.638861 -431.433595) (xy 6.709328 -431.495614) (xy 6.774281 -431.563386)
			(xy 6.833254 -431.636421) (xy 6.88582 -431.714195) (xy 6.931601 -431.796147) (xy 6.970267 -431.881686)
			(xy 7.001539 -431.970195) (xy 7.025193 -432.061038) (xy 7.041057 -432.15356) (xy 7.049018 -432.247094)
			(xy 7.049516 -432.29403) (xy 7.049018 -432.340966) (xy 7.041057 -432.4345) (xy 7.025193 -432.527022)
			(xy 7.001539 -432.617865) (xy 6.970267 -432.706374) (xy 6.931601 -432.791913) (xy 6.88582 -432.873865)
			(xy 6.833254 -432.951639) (xy 6.774281 -433.024674) (xy 6.709328 -433.092446) (xy 6.638861 -433.154465)
			(xy 6.563388 -433.210284) (xy 6.483453 -433.259502) (xy 6.399632 -433.301764) (xy 6.312529 -433.336764)
			(xy 6.222772 -433.364252) (xy 6.131007 -433.384029) (xy 6.037895 -433.395952) (xy 5.944108 -433.399937)
			(xy 5.850321 -433.395952) (xy 5.757209 -433.384029) (xy 5.665444 -433.364252) (xy 5.575687 -433.336764)
			(xy 5.488584 -433.301764) (xy 5.404763 -433.259502) (xy 5.324828 -433.210284) (xy 5.249355 -433.154465)
			(xy 5.178888 -433.092446) (xy 5.113935 -433.024674) (xy 5.054962 -432.951639) (xy 5.002396 -432.873865)
			(xy 4.956615 -432.791913) (xy 4.917949 -432.706374) (xy 4.886677 -432.617865) (xy 4.863023 -432.527022)
			(xy 4.847159 -432.4345) (xy 4.839198 -432.340966) (xy 1.27 -432.340966) (xy 1.27 -436.540856) (xy 4.839198 -436.540856)
			(xy 4.839198 -436.446984) (xy 4.847159 -436.35345) (xy 4.863023 -436.260928) (xy 4.886677 -436.170085)
			(xy 4.917949 -436.081576) (xy 4.956615 -435.996037) (xy 5.002396 -435.914085) (xy 5.054962 -435.836311)
			(xy 5.113935 -435.763276) (xy 5.178888 -435.695504) (xy 5.249355 -435.633485) (xy 5.324828 -435.577666)
			(xy 5.404763 -435.528448) (xy 5.488584 -435.486186) (xy 5.575687 -435.451186) (xy 5.665444 -435.423698)
			(xy 5.757209 -435.403921) (xy 5.850321 -435.391998) (xy 5.944108 -435.388014) (xy 6.037895 -435.391998)
			(xy 6.131007 -435.403921) (xy 6.222772 -435.423698) (xy 6.312529 -435.451186) (xy 6.399632 -435.486186)
			(xy 6.483453 -435.528448) (xy 6.563388 -435.577666) (xy 6.638861 -435.633485) (xy 6.709328 -435.695504)
			(xy 6.774281 -435.763276) (xy 6.833254 -435.836311) (xy 6.88582 -435.914085) (xy 6.931601 -435.996037)
			(xy 6.970267 -436.081576) (xy 7.001539 -436.170085) (xy 7.025193 -436.260928) (xy 7.041057 -436.35345)
			(xy 7.049018 -436.446984) (xy 7.049516 -436.49392) (xy 7.049018 -436.540856) (xy 7.041057 -436.63439)
			(xy 7.025193 -436.726912) (xy 7.001539 -436.817755) (xy 6.970267 -436.906264) (xy 6.931601 -436.991803)
			(xy 6.88582 -437.073755) (xy 6.833254 -437.151529) (xy 6.774281 -437.224564) (xy 6.709328 -437.292336)
			(xy 6.638861 -437.354355) (xy 6.563388 -437.410174) (xy 6.483453 -437.459392) (xy 6.399632 -437.501654)
			(xy 6.312529 -437.536654) (xy 6.222772 -437.564142) (xy 6.131007 -437.583919) (xy 6.037895 -437.595842)
			(xy 5.944108 -437.599827) (xy 5.850321 -437.595842) (xy 5.757209 -437.583919) (xy 5.665444 -437.564142)
			(xy 5.575687 -437.536654) (xy 5.488584 -437.501654) (xy 5.404763 -437.459392) (xy 5.324828 -437.410174)
			(xy 5.249355 -437.354355) (xy 5.178888 -437.292336) (xy 5.113935 -437.224564) (xy 5.054962 -437.151529)
			(xy 5.002396 -437.073755) (xy 4.956615 -436.991803) (xy 4.917949 -436.906264) (xy 4.886677 -436.817755)
			(xy 4.863023 -436.726912) (xy 4.847159 -436.63439) (xy 4.839198 -436.540856) (xy 1.27 -436.540856)
			(xy 1.27 -440.741) (xy 4.839198 -440.741) (xy 4.839198 -440.647128) (xy 4.847159 -440.553594) (xy 4.863023 -440.461072)
			(xy 4.886677 -440.370229) (xy 4.917949 -440.28172) (xy 4.956615 -440.196181) (xy 5.002396 -440.114229)
			(xy 5.054962 -440.036455) (xy 5.113935 -439.96342) (xy 5.178888 -439.895648) (xy 5.249355 -439.833629)
			(xy 5.324828 -439.77781) (xy 5.404763 -439.728592) (xy 5.488584 -439.68633) (xy 5.575687 -439.65133)
			(xy 5.665444 -439.623842) (xy 5.757209 -439.604065) (xy 5.850321 -439.592142) (xy 5.944108 -439.588158)
			(xy 6.037895 -439.592142) (xy 6.131007 -439.604065) (xy 6.222772 -439.623842) (xy 6.312529 -439.65133)
			(xy 6.399632 -439.68633) (xy 6.483453 -439.728592) (xy 6.563388 -439.77781) (xy 6.638861 -439.833629)
			(xy 6.709328 -439.895648) (xy 6.774281 -439.96342) (xy 6.833254 -440.036455) (xy 6.88582 -440.114229)
			(xy 6.931601 -440.196181) (xy 6.970267 -440.28172) (xy 7.001539 -440.370229) (xy 7.025193 -440.461072)
			(xy 7.041057 -440.553594) (xy 7.049018 -440.647128) (xy 7.049516 -440.694064) (xy 7.049018 -440.741)
			(xy 7.041057 -440.834534) (xy 7.025193 -440.927056) (xy 7.001539 -441.017899) (xy 6.970267 -441.106408)
			(xy 6.931601 -441.191947) (xy 6.88582 -441.273899) (xy 6.833254 -441.351673) (xy 6.774281 -441.424708)
			(xy 6.709328 -441.49248) (xy 6.638861 -441.554499) (xy 6.563388 -441.610318) (xy 6.483453 -441.659536)
			(xy 6.399632 -441.701798) (xy 6.312529 -441.736798) (xy 6.222772 -441.764286) (xy 6.131007 -441.784063)
			(xy 6.037895 -441.795986) (xy 5.944108 -441.799971) (xy 5.850321 -441.795986) (xy 5.757209 -441.784063)
			(xy 5.665444 -441.764286) (xy 5.575687 -441.736798) (xy 5.488584 -441.701798) (xy 5.404763 -441.659536)
			(xy 5.324828 -441.610318) (xy 5.249355 -441.554499) (xy 5.178888 -441.49248) (xy 5.113935 -441.424708)
			(xy 5.054962 -441.351673) (xy 5.002396 -441.273899) (xy 4.956615 -441.191947) (xy 4.917949 -441.106408)
			(xy 4.886677 -441.017899) (xy 4.863023 -440.927056) (xy 4.847159 -440.834534) (xy 4.839198 -440.741)
			(xy 1.27 -440.741) (xy 1.27 -444.94089) (xy 4.839198 -444.94089) (xy 4.839198 -444.847018) (xy 4.847159 -444.753484)
			(xy 4.863023 -444.660962) (xy 4.886677 -444.570119) (xy 4.917949 -444.48161) (xy 4.956615 -444.396071)
			(xy 5.002396 -444.314119) (xy 5.054962 -444.236345) (xy 5.113935 -444.16331) (xy 5.178888 -444.095538)
			(xy 5.249355 -444.033519) (xy 5.324828 -443.9777) (xy 5.404763 -443.928482) (xy 5.488584 -443.88622)
			(xy 5.575687 -443.85122) (xy 5.665444 -443.823732) (xy 5.757209 -443.803955) (xy 5.850321 -443.792032)
			(xy 5.944108 -443.788048) (xy 6.037895 -443.792032) (xy 6.131007 -443.803955) (xy 6.222772 -443.823732)
			(xy 6.312529 -443.85122) (xy 6.399632 -443.88622) (xy 6.483453 -443.928482) (xy 6.563388 -443.9777)
			(xy 6.638861 -444.033519) (xy 6.709328 -444.095538) (xy 6.774281 -444.16331) (xy 6.833254 -444.236345)
			(xy 6.88582 -444.314119) (xy 6.931601 -444.396071) (xy 6.970267 -444.48161) (xy 7.001539 -444.570119)
			(xy 7.025193 -444.660962) (xy 7.041057 -444.753484) (xy 7.049018 -444.847018) (xy 7.049516 -444.893954)
			(xy 7.049018 -444.94089) (xy 7.041057 -445.034424) (xy 7.025193 -445.126946) (xy 7.001539 -445.217789)
			(xy 6.970267 -445.306298) (xy 6.931601 -445.391837) (xy 6.88582 -445.473789) (xy 6.833254 -445.551563)
			(xy 6.774281 -445.624598) (xy 6.709328 -445.69237) (xy 6.638861 -445.754389) (xy 6.563388 -445.810208)
			(xy 6.483453 -445.859426) (xy 6.399632 -445.901688) (xy 6.312529 -445.936688) (xy 6.222772 -445.964176)
			(xy 6.131007 -445.983953) (xy 6.037895 -445.995876) (xy 5.944108 -445.999861) (xy 5.850321 -445.995876)
			(xy 5.757209 -445.983953) (xy 5.665444 -445.964176) (xy 5.575687 -445.936688) (xy 5.488584 -445.901688)
			(xy 5.404763 -445.859426) (xy 5.324828 -445.810208) (xy 5.249355 -445.754389) (xy 5.178888 -445.69237)
			(xy 5.113935 -445.624598) (xy 5.054962 -445.551563) (xy 5.002396 -445.473789) (xy 4.956615 -445.391837)
			(xy 4.917949 -445.306298) (xy 4.886677 -445.217789) (xy 4.863023 -445.126946) (xy 4.847159 -445.034424)
			(xy 4.839198 -444.94089) (xy 1.27 -444.94089) (xy 1.27 -447.250058) (xy 24.781254 -447.250058) (xy 24.785325 -447.194436)
			(xy 24.797451 -447.139999) (xy 24.817374 -447.087908) (xy 24.84467 -447.039273) (xy 24.878756 -446.99513)
			(xy 24.918905 -446.956421) (xy 24.964263 -446.92397) (xy 25.013863 -446.898469) (xy 25.066647 -446.880462)
			(xy 25.12149 -446.870332) (xy 25.177224 -446.868295) (xy 25.232661 -446.874395) (xy 25.286618 -446.888501)
			(xy 25.337947 -446.910313) (xy 25.385553 -446.939367) (xy 25.428421 -446.975042) (xy 25.465638 -447.016579)
			(xy 25.496411 -447.063092) (xy 25.520083 -447.113589) (xy 25.536151 -447.166996) (xy 25.544271 -447.222172)
			(xy 25.54478 -447.250058) (xy 25.544271 -447.277944) (xy 25.536151 -447.33312) (xy 25.520083 -447.386527)
			(xy 25.496411 -447.437024) (xy 25.465638 -447.483537) (xy 25.428421 -447.525074) (xy 25.385553 -447.560749)
			(xy 25.337947 -447.589803) (xy 25.286618 -447.611615) (xy 25.232661 -447.625721) (xy 25.177224 -447.631821)
			(xy 25.12149 -447.629784) (xy 25.066647 -447.619654) (xy 25.013863 -447.601647) (xy 24.964263 -447.576146)
			(xy 24.918905 -447.543695) (xy 24.878756 -447.504986) (xy 24.84467 -447.460843) (xy 24.817374 -447.412208)
			(xy 24.797451 -447.360117) (xy 24.785325 -447.30568) (xy 24.781254 -447.250058) (xy 1.27 -447.250058)
			(xy 1.27 -449.141034) (xy 4.839198 -449.141034) (xy 4.839198 -449.047162) (xy 4.847159 -448.953628)
			(xy 4.863023 -448.861106) (xy 4.886677 -448.770263) (xy 4.917949 -448.681754) (xy 4.956615 -448.596215)
			(xy 5.002396 -448.514263) (xy 5.054962 -448.436489) (xy 5.113935 -448.363454) (xy 5.178888 -448.295682)
			(xy 5.249355 -448.233663) (xy 5.324828 -448.177844) (xy 5.404763 -448.128626) (xy 5.488584 -448.086364)
			(xy 5.575687 -448.051364) (xy 5.665444 -448.023876) (xy 5.757209 -448.004099) (xy 5.850321 -447.992176)
			(xy 5.944108 -447.988192) (xy 6.037895 -447.992176) (xy 6.131007 -448.004099) (xy 6.222772 -448.023876)
			(xy 6.312529 -448.051364) (xy 6.399632 -448.086364) (xy 6.483453 -448.128626) (xy 6.563388 -448.177844)
			(xy 6.638861 -448.233663) (xy 6.709328 -448.295682) (xy 6.774281 -448.363454) (xy 6.833254 -448.436489)
			(xy 6.88582 -448.514263) (xy 6.931601 -448.596215) (xy 6.970267 -448.681754) (xy 7.001539 -448.770263)
			(xy 7.025193 -448.861106) (xy 7.041057 -448.953628) (xy 7.049018 -449.047162) (xy 7.049516 -449.094098)
			(xy 7.049018 -449.141034) (xy 10.339314 -449.141034) (xy 10.339314 -449.047162) (xy 10.347275 -448.953628)
			(xy 10.363139 -448.861106) (xy 10.386793 -448.770263) (xy 10.418065 -448.681754) (xy 10.456731 -448.596215)
			(xy 10.502512 -448.514263) (xy 10.555078 -448.436489) (xy 10.614051 -448.363454) (xy 10.679004 -448.295682)
			(xy 10.749471 -448.233663) (xy 10.824944 -448.177844) (xy 10.904879 -448.128626) (xy 10.9887 -448.086364)
			(xy 11.075803 -448.051364) (xy 11.16556 -448.023876) (xy 11.257325 -448.004099) (xy 11.350437 -447.992176)
			(xy 11.444224 -447.988192) (xy 11.538011 -447.992176) (xy 11.631123 -448.004099) (xy 11.722888 -448.023876)
			(xy 11.812645 -448.051364) (xy 11.899748 -448.086364) (xy 11.983569 -448.128626) (xy 12.063504 -448.177844)
			(xy 12.138977 -448.233663) (xy 12.209444 -448.295682) (xy 12.274397 -448.363454) (xy 12.33337 -448.436489)
			(xy 12.371827 -448.493388) (xy 24.790144 -448.493388) (xy 24.794215 -448.437766) (xy 24.806341 -448.383329)
			(xy 24.826264 -448.331238) (xy 24.85356 -448.282603) (xy 24.887646 -448.23846) (xy 24.927795 -448.199751)
			(xy 24.973153 -448.1673) (xy 25.022753 -448.141799) (xy 25.075537 -448.123792) (xy 25.13038 -448.113662)
			(xy 25.186114 -448.111625) (xy 25.241551 -448.117725) (xy 25.295508 -448.131831) (xy 25.346837 -448.153643)
			(xy 25.394443 -448.182697) (xy 25.437311 -448.218372) (xy 25.474528 -448.259909) (xy 25.505301 -448.306422)
			(xy 25.528973 -448.356919) (xy 25.545041 -448.410326) (xy 25.553161 -448.465502) (xy 25.55367 -448.493388)
			(xy 25.553161 -448.521274) (xy 25.545041 -448.57645) (xy 25.528973 -448.629857) (xy 25.505301 -448.680354)
			(xy 25.474528 -448.726867) (xy 25.437311 -448.768404) (xy 25.394443 -448.804079) (xy 25.346837 -448.833133)
			(xy 25.295508 -448.854945) (xy 25.241551 -448.869051) (xy 25.186114 -448.875151) (xy 25.13038 -448.873114)
			(xy 25.075537 -448.862984) (xy 25.022753 -448.844977) (xy 24.973153 -448.819476) (xy 24.927795 -448.787025)
			(xy 24.887646 -448.748316) (xy 24.85356 -448.704173) (xy 24.826264 -448.655538) (xy 24.806341 -448.603447)
			(xy 24.794215 -448.54901) (xy 24.790144 -448.493388) (xy 12.371827 -448.493388) (xy 12.385936 -448.514263)
			(xy 12.431717 -448.596215) (xy 12.470383 -448.681754) (xy 12.501655 -448.770263) (xy 12.525309 -448.861106)
			(xy 12.541173 -448.953628) (xy 12.549134 -449.047162) (xy 12.549632 -449.094098) (xy 12.549134 -449.141034)
			(xy 12.546382 -449.173362) (xy 29.519874 -449.173362) (xy 29.519874 -449.086462) (xy 29.527892 -448.999933)
			(xy 29.54386 -448.914513) (xy 29.567641 -448.830931) (xy 29.599033 -448.749899) (xy 29.637767 -448.67211)
			(xy 29.683514 -448.598226) (xy 29.735883 -448.528879) (xy 29.794427 -448.464659) (xy 29.858647 -448.406115)
			(xy 29.927994 -448.353746) (xy 30.001878 -448.307999) (xy 30.079667 -448.269265) (xy 30.160699 -448.237873)
			(xy 30.244281 -448.214092) (xy 30.329701 -448.198124) (xy 30.41623 -448.190106) (xy 30.50313 -448.190106)
			(xy 30.589659 -448.198124) (xy 30.675079 -448.214092) (xy 30.758661 -448.237873) (xy 30.839693 -448.269265)
			(xy 30.917482 -448.307999) (xy 30.991366 -448.353746) (xy 31.060713 -448.406115) (xy 31.124933 -448.464659)
			(xy 31.183477 -448.528879) (xy 31.235846 -448.598226) (xy 31.281593 -448.67211) (xy 31.320327 -448.749899)
			(xy 31.351719 -448.830931) (xy 31.3755 -448.914513) (xy 31.391468 -448.999933) (xy 31.399486 -449.086462)
			(xy 31.399988 -449.129912) (xy 31.399486 -449.173362) (xy 34.599874 -449.173362) (xy 34.599874 -449.086462)
			(xy 34.607892 -448.999933) (xy 34.62386 -448.914513) (xy 34.647641 -448.830931) (xy 34.679033 -448.749899)
			(xy 34.717767 -448.67211) (xy 34.763514 -448.598226) (xy 34.815883 -448.528879) (xy 34.874427 -448.464659)
			(xy 34.938647 -448.406115) (xy 35.007994 -448.353746) (xy 35.081878 -448.307999) (xy 35.159667 -448.269265)
			(xy 35.240699 -448.237873) (xy 35.324281 -448.214092) (xy 35.409701 -448.198124) (xy 35.49623 -448.190106)
			(xy 35.58313 -448.190106) (xy 35.669659 -448.198124) (xy 35.755079 -448.214092) (xy 35.838661 -448.237873)
			(xy 35.919693 -448.269265) (xy 35.997482 -448.307999) (xy 36.071366 -448.353746) (xy 36.140713 -448.406115)
			(xy 36.204933 -448.464659) (xy 36.263477 -448.528879) (xy 36.315846 -448.598226) (xy 36.361593 -448.67211)
			(xy 36.400327 -448.749899) (xy 36.431719 -448.830931) (xy 36.4555 -448.914513) (xy 36.471468 -448.999933)
			(xy 36.479486 -449.086462) (xy 36.479988 -449.129912) (xy 36.479486 -449.173362) (xy 36.471468 -449.259891)
			(xy 36.4555 -449.345311) (xy 36.431719 -449.428893) (xy 36.400327 -449.509925) (xy 36.361593 -449.587714)
			(xy 36.315846 -449.661598) (xy 36.263477 -449.730945) (xy 36.204933 -449.795165) (xy 36.140713 -449.853709)
			(xy 36.071366 -449.906078) (xy 35.997482 -449.951825) (xy 35.919693 -449.990559) (xy 35.838661 -450.021951)
			(xy 35.755079 -450.045732) (xy 35.669659 -450.0617) (xy 35.58313 -450.069718) (xy 35.49623 -450.069718)
			(xy 35.409701 -450.0617) (xy 35.324281 -450.045732) (xy 35.240699 -450.021951) (xy 35.159667 -449.990559)
			(xy 35.081878 -449.951825) (xy 35.007994 -449.906078) (xy 34.938647 -449.853709) (xy 34.874427 -449.795165)
			(xy 34.815883 -449.730945) (xy 34.763514 -449.661598) (xy 34.717767 -449.587714) (xy 34.679033 -449.509925)
			(xy 34.647641 -449.428893) (xy 34.62386 -449.345311) (xy 34.607892 -449.259891) (xy 34.599874 -449.173362)
			(xy 31.399486 -449.173362) (xy 31.391468 -449.259891) (xy 31.3755 -449.345311) (xy 31.351719 -449.428893)
			(xy 31.320327 -449.509925) (xy 31.281593 -449.587714) (xy 31.235846 -449.661598) (xy 31.183477 -449.730945)
			(xy 31.124933 -449.795165) (xy 31.060713 -449.853709) (xy 30.991366 -449.906078) (xy 30.917482 -449.951825)
			(xy 30.839693 -449.990559) (xy 30.758661 -450.021951) (xy 30.675079 -450.045732) (xy 30.589659 -450.0617)
			(xy 30.50313 -450.069718) (xy 30.41623 -450.069718) (xy 30.329701 -450.0617) (xy 30.244281 -450.045732)
			(xy 30.160699 -450.021951) (xy 30.079667 -449.990559) (xy 30.001878 -449.951825) (xy 29.927994 -449.906078)
			(xy 29.858647 -449.853709) (xy 29.794427 -449.795165) (xy 29.735883 -449.730945) (xy 29.683514 -449.661598)
			(xy 29.637767 -449.587714) (xy 29.599033 -449.509925) (xy 29.567641 -449.428893) (xy 29.54386 -449.345311)
			(xy 29.527892 -449.259891) (xy 29.519874 -449.173362) (xy 12.546382 -449.173362) (xy 12.541173 -449.234568)
			(xy 12.525309 -449.32709) (xy 12.501655 -449.417933) (xy 12.470383 -449.506442) (xy 12.431717 -449.591981)
			(xy 12.385936 -449.673933) (xy 12.374402 -449.690998) (xy 26.886152 -449.690998) (xy 26.890223 -449.635376)
			(xy 26.902349 -449.580939) (xy 26.922272 -449.528848) (xy 26.949568 -449.480213) (xy 26.983654 -449.43607)
			(xy 27.023803 -449.397361) (xy 27.069161 -449.36491) (xy 27.118761 -449.339409) (xy 27.171545 -449.321402)
			(xy 27.226388 -449.311272) (xy 27.282122 -449.309235) (xy 27.337559 -449.315335) (xy 27.391516 -449.329441)
			(xy 27.442845 -449.351253) (xy 27.490451 -449.380307) (xy 27.533319 -449.415982) (xy 27.570536 -449.457519)
			(xy 27.601309 -449.504032) (xy 27.624981 -449.554529) (xy 27.641049 -449.607936) (xy 27.649169 -449.663112)
			(xy 27.649678 -449.690998) (xy 27.649169 -449.718884) (xy 27.641049 -449.77406) (xy 27.624981 -449.827467)
			(xy 27.601309 -449.877964) (xy 27.570536 -449.924477) (xy 27.533319 -449.966014) (xy 27.490451 -450.001689)
			(xy 27.442845 -450.030743) (xy 27.391516 -450.052555) (xy 27.337559 -450.066661) (xy 27.282122 -450.072761)
			(xy 27.226388 -450.070724) (xy 27.171545 -450.060594) (xy 27.118761 -450.042587) (xy 27.069161 -450.017086)
			(xy 27.023803 -449.984635) (xy 26.983654 -449.945926) (xy 26.949568 -449.901783) (xy 26.922272 -449.853148)
			(xy 26.902349 -449.801057) (xy 26.890223 -449.74662) (xy 26.886152 -449.690998) (xy 12.374402 -449.690998)
			(xy 12.33337 -449.751707) (xy 12.274397 -449.824742) (xy 12.209444 -449.892514) (xy 12.138977 -449.954533)
			(xy 12.063504 -450.010352) (xy 11.983569 -450.05957) (xy 11.899748 -450.101832) (xy 11.812645 -450.136832)
			(xy 11.722888 -450.16432) (xy 11.631123 -450.184097) (xy 11.538011 -450.19602) (xy 11.444224 -450.200005)
			(xy 11.350437 -450.19602) (xy 11.257325 -450.184097) (xy 11.16556 -450.16432) (xy 11.075803 -450.136832)
			(xy 10.9887 -450.101832) (xy 10.904879 -450.05957) (xy 10.824944 -450.010352) (xy 10.749471 -449.954533)
			(xy 10.679004 -449.892514) (xy 10.614051 -449.824742) (xy 10.555078 -449.751707) (xy 10.502512 -449.673933)
			(xy 10.456731 -449.591981) (xy 10.418065 -449.506442) (xy 10.386793 -449.417933) (xy 10.363139 -449.32709)
			(xy 10.347275 -449.234568) (xy 10.339314 -449.141034) (xy 7.049018 -449.141034) (xy 7.041057 -449.234568)
			(xy 7.025193 -449.32709) (xy 7.001539 -449.417933) (xy 6.970267 -449.506442) (xy 6.931601 -449.591981)
			(xy 6.88582 -449.673933) (xy 6.833254 -449.751707) (xy 6.774281 -449.824742) (xy 6.709328 -449.892514)
			(xy 6.638861 -449.954533) (xy 6.563388 -450.010352) (xy 6.483453 -450.05957) (xy 6.399632 -450.101832)
			(xy 6.312529 -450.136832) (xy 6.222772 -450.16432) (xy 6.131007 -450.184097) (xy 6.037895 -450.19602)
			(xy 5.944108 -450.200005) (xy 5.850321 -450.19602) (xy 5.757209 -450.184097) (xy 5.665444 -450.16432)
			(xy 5.575687 -450.136832) (xy 5.488584 -450.101832) (xy 5.404763 -450.05957) (xy 5.324828 -450.010352)
			(xy 5.249355 -449.954533) (xy 5.178888 -449.892514) (xy 5.113935 -449.824742) (xy 5.054962 -449.751707)
			(xy 5.002396 -449.673933) (xy 4.956615 -449.591981) (xy 4.917949 -449.506442) (xy 4.886677 -449.417933)
			(xy 4.863023 -449.32709) (xy 4.847159 -449.234568) (xy 4.839198 -449.141034) (xy 1.27 -449.141034)
			(xy 1.27 -451.713362) (xy 29.519874 -451.713362) (xy 29.519874 -451.626462) (xy 29.527892 -451.539933)
			(xy 29.54386 -451.454513) (xy 29.567641 -451.370931) (xy 29.599033 -451.289899) (xy 29.637767 -451.21211)
			(xy 29.683514 -451.138226) (xy 29.735883 -451.068879) (xy 29.794427 -451.004659) (xy 29.858647 -450.946115)
			(xy 29.927994 -450.893746) (xy 30.001878 -450.847999) (xy 30.079667 -450.809265) (xy 30.160699 -450.777873)
			(xy 30.244281 -450.754092) (xy 30.329701 -450.738124) (xy 30.41623 -450.730106) (xy 30.50313 -450.730106)
			(xy 30.589659 -450.738124) (xy 30.675079 -450.754092) (xy 30.758661 -450.777873) (xy 30.839693 -450.809265)
			(xy 30.917482 -450.847999) (xy 30.991366 -450.893746) (xy 31.060713 -450.946115) (xy 31.124933 -451.004659)
			(xy 31.183477 -451.068879) (xy 31.235846 -451.138226) (xy 31.281593 -451.21211) (xy 31.320327 -451.289899)
			(xy 31.351719 -451.370931) (xy 31.3755 -451.454513) (xy 31.391468 -451.539933) (xy 31.399486 -451.626462)
			(xy 31.399988 -451.669912) (xy 31.399486 -451.713362) (xy 34.599874 -451.713362) (xy 34.599874 -451.626462)
			(xy 34.607892 -451.539933) (xy 34.62386 -451.454513) (xy 34.647641 -451.370931) (xy 34.679033 -451.289899)
			(xy 34.717767 -451.21211) (xy 34.763514 -451.138226) (xy 34.815883 -451.068879) (xy 34.874427 -451.004659)
			(xy 34.938647 -450.946115) (xy 35.007994 -450.893746) (xy 35.081878 -450.847999) (xy 35.159667 -450.809265)
			(xy 35.240699 -450.777873) (xy 35.324281 -450.754092) (xy 35.409701 -450.738124) (xy 35.49623 -450.730106)
			(xy 35.58313 -450.730106) (xy 35.669659 -450.738124) (xy 35.755079 -450.754092) (xy 35.838661 -450.777873)
			(xy 35.919693 -450.809265) (xy 35.997482 -450.847999) (xy 36.071366 -450.893746) (xy 36.140713 -450.946115)
			(xy 36.204933 -451.004659) (xy 36.263477 -451.068879) (xy 36.315846 -451.138226) (xy 36.361593 -451.21211)
			(xy 36.400327 -451.289899) (xy 36.431719 -451.370931) (xy 36.4555 -451.454513) (xy 36.471468 -451.539933)
			(xy 36.479486 -451.626462) (xy 36.479988 -451.669912) (xy 36.479486 -451.713362) (xy 36.471468 -451.799891)
			(xy 36.4555 -451.885311) (xy 36.431719 -451.968893) (xy 36.400327 -452.049925) (xy 36.361593 -452.127714)
			(xy 36.315846 -452.201598) (xy 36.263477 -452.270945) (xy 36.204933 -452.335165) (xy 36.140713 -452.393709)
			(xy 36.071366 -452.446078) (xy 35.997482 -452.491825) (xy 35.919693 -452.530559) (xy 35.838661 -452.561951)
			(xy 35.755079 -452.585732) (xy 35.669659 -452.6017) (xy 35.58313 -452.609718) (xy 35.49623 -452.609718)
			(xy 35.409701 -452.6017) (xy 35.324281 -452.585732) (xy 35.240699 -452.561951) (xy 35.159667 -452.530559)
			(xy 35.081878 -452.491825) (xy 35.007994 -452.446078) (xy 34.938647 -452.393709) (xy 34.874427 -452.335165)
			(xy 34.815883 -452.270945) (xy 34.763514 -452.201598) (xy 34.717767 -452.127714) (xy 34.679033 -452.049925)
			(xy 34.647641 -451.968893) (xy 34.62386 -451.885311) (xy 34.607892 -451.799891) (xy 34.599874 -451.713362)
			(xy 31.399486 -451.713362) (xy 31.391468 -451.799891) (xy 31.3755 -451.885311) (xy 31.351719 -451.968893)
			(xy 31.320327 -452.049925) (xy 31.281593 -452.127714) (xy 31.235846 -452.201598) (xy 31.183477 -452.270945)
			(xy 31.124933 -452.335165) (xy 31.060713 -452.393709) (xy 30.991366 -452.446078) (xy 30.917482 -452.491825)
			(xy 30.839693 -452.530559) (xy 30.758661 -452.561951) (xy 30.675079 -452.585732) (xy 30.589659 -452.6017)
			(xy 30.50313 -452.609718) (xy 30.41623 -452.609718) (xy 30.329701 -452.6017) (xy 30.244281 -452.585732)
			(xy 30.160699 -452.561951) (xy 30.079667 -452.530559) (xy 30.001878 -452.491825) (xy 29.927994 -452.446078)
			(xy 29.858647 -452.393709) (xy 29.794427 -452.335165) (xy 29.735883 -452.270945) (xy 29.683514 -452.201598)
			(xy 29.637767 -452.127714) (xy 29.599033 -452.049925) (xy 29.567641 -451.968893) (xy 29.54386 -451.885311)
			(xy 29.527892 -451.799891) (xy 29.519874 -451.713362) (xy 1.27 -451.713362) (xy 1.27 -453.340924)
			(xy 4.839198 -453.340924) (xy 4.839198 -453.247052) (xy 4.847159 -453.153518) (xy 4.863023 -453.060996)
			(xy 4.886677 -452.970153) (xy 4.917949 -452.881644) (xy 4.956615 -452.796105) (xy 5.002396 -452.714153)
			(xy 5.054962 -452.636379) (xy 5.113935 -452.563344) (xy 5.178888 -452.495572) (xy 5.249355 -452.433553)
			(xy 5.324828 -452.377734) (xy 5.404763 -452.328516) (xy 5.488584 -452.286254) (xy 5.575687 -452.251254)
			(xy 5.665444 -452.223766) (xy 5.757209 -452.203989) (xy 5.850321 -452.192066) (xy 5.944108 -452.188082)
			(xy 6.037895 -452.192066) (xy 6.131007 -452.203989) (xy 6.222772 -452.223766) (xy 6.312529 -452.251254)
			(xy 6.328491 -452.257668) (xy 24.731724 -452.257668) (xy 24.735795 -452.202046) (xy 24.747921 -452.147609)
			(xy 24.767844 -452.095518) (xy 24.79514 -452.046883) (xy 24.829226 -452.00274) (xy 24.869375 -451.964031)
			(xy 24.914733 -451.93158) (xy 24.964333 -451.906079) (xy 25.017117 -451.888072) (xy 25.07196 -451.877942)
			(xy 25.127694 -451.875905) (xy 25.183131 -451.882005) (xy 25.237088 -451.896111) (xy 25.288417 -451.917923)
			(xy 25.336023 -451.946977) (xy 25.378891 -451.982652) (xy 25.416108 -452.024189) (xy 25.446881 -452.070702)
			(xy 25.470553 -452.121199) (xy 25.486621 -452.174606) (xy 25.494741 -452.229782) (xy 25.49525 -452.257668)
			(xy 25.495241 -452.258176) (xy 26.890724 -452.258176) (xy 26.894795 -452.202554) (xy 26.906921 -452.148117)
			(xy 26.926844 -452.096026) (xy 26.95414 -452.047391) (xy 26.988226 -452.003248) (xy 27.028375 -451.964539)
			(xy 27.073733 -451.932088) (xy 27.123333 -451.906587) (xy 27.176117 -451.88858) (xy 27.23096 -451.87845)
			(xy 27.286694 -451.876413) (xy 27.342131 -451.882513) (xy 27.396088 -451.896619) (xy 27.447417 -451.918431)
			(xy 27.495023 -451.947485) (xy 27.537891 -451.98316) (xy 27.575108 -452.024697) (xy 27.605881 -452.07121)
			(xy 27.629553 -452.121707) (xy 27.645621 -452.175114) (xy 27.653741 -452.23029) (xy 27.65425 -452.258176)
			(xy 27.653741 -452.286062) (xy 27.645621 -452.341238) (xy 27.629553 -452.394645) (xy 27.605881 -452.445142)
			(xy 27.575108 -452.491655) (xy 27.537891 -452.533192) (xy 27.495023 -452.568867) (xy 27.447417 -452.597921)
			(xy 27.396088 -452.619733) (xy 27.342131 -452.633839) (xy 27.286694 -452.639939) (xy 27.23096 -452.637902)
			(xy 27.176117 -452.627772) (xy 27.123333 -452.609765) (xy 27.073733 -452.584264) (xy 27.028375 -452.551813)
			(xy 26.988226 -452.513104) (xy 26.95414 -452.468961) (xy 26.926844 -452.420326) (xy 26.906921 -452.368235)
			(xy 26.894795 -452.313798) (xy 26.890724 -452.258176) (xy 25.495241 -452.258176) (xy 25.494741 -452.285554)
			(xy 25.486621 -452.34073) (xy 25.470553 -452.394137) (xy 25.446881 -452.444634) (xy 25.416108 -452.491147)
			(xy 25.378891 -452.532684) (xy 25.336023 -452.568359) (xy 25.288417 -452.597413) (xy 25.237088 -452.619225)
			(xy 25.183131 -452.633331) (xy 25.127694 -452.639431) (xy 25.07196 -452.637394) (xy 25.017117 -452.627264)
			(xy 24.964333 -452.609257) (xy 24.914733 -452.583756) (xy 24.869375 -452.551305) (xy 24.829226 -452.512596)
			(xy 24.79514 -452.468453) (xy 24.767844 -452.419818) (xy 24.747921 -452.367727) (xy 24.735795 -452.31329)
			(xy 24.731724 -452.257668) (xy 6.328491 -452.257668) (xy 6.399632 -452.286254) (xy 6.483453 -452.328516)
			(xy 6.563388 -452.377734) (xy 6.638861 -452.433553) (xy 6.709328 -452.495572) (xy 6.774281 -452.563344)
			(xy 6.833254 -452.636379) (xy 6.88582 -452.714153) (xy 6.931601 -452.796105) (xy 6.970267 -452.881644)
			(xy 7.001539 -452.970153) (xy 7.025193 -453.060996) (xy 7.041057 -453.153518) (xy 7.049018 -453.247052)
			(xy 7.049516 -453.293988) (xy 7.049018 -453.340924) (xy 7.041057 -453.434458) (xy 7.025193 -453.52698)
			(xy 7.023096 -453.535034) (xy 24.77592 -453.535034) (xy 24.779991 -453.479412) (xy 24.792117 -453.424975)
			(xy 24.81204 -453.372884) (xy 24.839336 -453.324249) (xy 24.873422 -453.280106) (xy 24.913571 -453.241397)
			(xy 24.958929 -453.208946) (xy 25.008529 -453.183445) (xy 25.061313 -453.165438) (xy 25.116156 -453.155308)
			(xy 25.17189 -453.153271) (xy 25.227327 -453.159371) (xy 25.281284 -453.173477) (xy 25.332613 -453.195289)
			(xy 25.380219 -453.224343) (xy 25.423087 -453.260018) (xy 25.460304 -453.301555) (xy 25.491077 -453.348068)
			(xy 25.514749 -453.398565) (xy 25.530817 -453.451972) (xy 25.538937 -453.507148) (xy 25.539446 -453.535034)
			(xy 25.538937 -453.56292) (xy 25.530817 -453.618096) (xy 25.514749 -453.671503) (xy 25.491077 -453.722)
			(xy 25.460304 -453.768513) (xy 25.423087 -453.81005) (xy 25.380219 -453.845725) (xy 25.332613 -453.874779)
			(xy 25.281284 -453.896591) (xy 25.227327 -453.910697) (xy 25.17189 -453.916797) (xy 25.116156 -453.91476)
			(xy 25.061313 -453.90463) (xy 25.008529 -453.886623) (xy 24.958929 -453.861122) (xy 24.913571 -453.828671)
			(xy 24.873422 -453.789962) (xy 24.839336 -453.745819) (xy 24.81204 -453.697184) (xy 24.792117 -453.645093)
			(xy 24.779991 -453.590656) (xy 24.77592 -453.535034) (xy 7.023096 -453.535034) (xy 7.001539 -453.617823)
			(xy 6.970267 -453.706332) (xy 6.931601 -453.791871) (xy 6.88582 -453.873823) (xy 6.833254 -453.951597)
			(xy 6.774281 -454.024632) (xy 6.709328 -454.092404) (xy 6.638861 -454.154423) (xy 6.563388 -454.210242)
			(xy 6.493357 -454.253362) (xy 29.519874 -454.253362) (xy 29.519874 -454.166462) (xy 29.527892 -454.079933)
			(xy 29.54386 -453.994513) (xy 29.567641 -453.910931) (xy 29.599033 -453.829899) (xy 29.637767 -453.75211)
			(xy 29.683514 -453.678226) (xy 29.735883 -453.608879) (xy 29.794427 -453.544659) (xy 29.858647 -453.486115)
			(xy 29.927994 -453.433746) (xy 30.001878 -453.387999) (xy 30.079667 -453.349265) (xy 30.160699 -453.317873)
			(xy 30.244281 -453.294092) (xy 30.329701 -453.278124) (xy 30.41623 -453.270106) (xy 30.50313 -453.270106)
			(xy 30.589659 -453.278124) (xy 30.675079 -453.294092) (xy 30.758661 -453.317873) (xy 30.839693 -453.349265)
			(xy 30.917482 -453.387999) (xy 30.991366 -453.433746) (xy 31.060713 -453.486115) (xy 31.124933 -453.544659)
			(xy 31.183477 -453.608879) (xy 31.235846 -453.678226) (xy 31.281593 -453.75211) (xy 31.320327 -453.829899)
			(xy 31.351719 -453.910931) (xy 31.3755 -453.994513) (xy 31.391468 -454.079933) (xy 31.399486 -454.166462)
			(xy 31.399988 -454.209912) (xy 31.399486 -454.253362) (xy 34.599874 -454.253362) (xy 34.599874 -454.166462)
			(xy 34.607892 -454.079933) (xy 34.62386 -453.994513) (xy 34.647641 -453.910931) (xy 34.679033 -453.829899)
			(xy 34.717767 -453.75211) (xy 34.763514 -453.678226) (xy 34.815883 -453.608879) (xy 34.874427 -453.544659)
			(xy 34.938647 -453.486115) (xy 35.007994 -453.433746) (xy 35.081878 -453.387999) (xy 35.159667 -453.349265)
			(xy 35.240699 -453.317873) (xy 35.324281 -453.294092) (xy 35.409701 -453.278124) (xy 35.49623 -453.270106)
			(xy 35.58313 -453.270106) (xy 35.669659 -453.278124) (xy 35.755079 -453.294092) (xy 35.838661 -453.317873)
			(xy 35.919693 -453.349265) (xy 35.997482 -453.387999) (xy 36.071366 -453.433746) (xy 36.140713 -453.486115)
			(xy 36.204933 -453.544659) (xy 36.263477 -453.608879) (xy 36.315846 -453.678226) (xy 36.361593 -453.75211)
			(xy 36.400327 -453.829899) (xy 36.431719 -453.910931) (xy 36.4555 -453.994513) (xy 36.471468 -454.079933)
			(xy 36.479486 -454.166462) (xy 36.479988 -454.209912) (xy 36.479486 -454.253362) (xy 36.471468 -454.339891)
			(xy 36.4555 -454.425311) (xy 36.431719 -454.508893) (xy 36.400327 -454.589925) (xy 36.361593 -454.667714)
			(xy 36.315846 -454.741598) (xy 36.263477 -454.810945) (xy 36.204933 -454.875165) (xy 36.140713 -454.933709)
			(xy 36.071366 -454.986078) (xy 35.997482 -455.031825) (xy 35.919693 -455.070559) (xy 35.838661 -455.101951)
			(xy 35.755079 -455.125732) (xy 35.669659 -455.1417) (xy 35.58313 -455.149718) (xy 35.49623 -455.149718)
			(xy 35.409701 -455.1417) (xy 35.324281 -455.125732) (xy 35.240699 -455.101951) (xy 35.159667 -455.070559)
			(xy 35.081878 -455.031825) (xy 35.007994 -454.986078) (xy 34.938647 -454.933709) (xy 34.874427 -454.875165)
			(xy 34.815883 -454.810945) (xy 34.763514 -454.741598) (xy 34.717767 -454.667714) (xy 34.679033 -454.589925)
			(xy 34.647641 -454.508893) (xy 34.62386 -454.425311) (xy 34.607892 -454.339891) (xy 34.599874 -454.253362)
			(xy 31.399486 -454.253362) (xy 31.391468 -454.339891) (xy 31.3755 -454.425311) (xy 31.351719 -454.508893)
			(xy 31.320327 -454.589925) (xy 31.281593 -454.667714) (xy 31.235846 -454.741598) (xy 31.183477 -454.810945)
			(xy 31.124933 -454.875165) (xy 31.060713 -454.933709) (xy 30.991366 -454.986078) (xy 30.917482 -455.031825)
			(xy 30.839693 -455.070559) (xy 30.758661 -455.101951) (xy 30.675079 -455.125732) (xy 30.589659 -455.1417)
			(xy 30.50313 -455.149718) (xy 30.41623 -455.149718) (xy 30.329701 -455.1417) (xy 30.244281 -455.125732)
			(xy 30.160699 -455.101951) (xy 30.079667 -455.070559) (xy 30.001878 -455.031825) (xy 29.927994 -454.986078)
			(xy 29.858647 -454.933709) (xy 29.794427 -454.875165) (xy 29.735883 -454.810945) (xy 29.683514 -454.741598)
			(xy 29.637767 -454.667714) (xy 29.599033 -454.589925) (xy 29.567641 -454.508893) (xy 29.54386 -454.425311)
			(xy 29.527892 -454.339891) (xy 29.519874 -454.253362) (xy 6.493357 -454.253362) (xy 6.483453 -454.25946)
			(xy 6.399632 -454.301722) (xy 6.312529 -454.336722) (xy 6.222772 -454.36421) (xy 6.131007 -454.383987)
			(xy 6.037895 -454.39591) (xy 5.944108 -454.399895) (xy 5.850321 -454.39591) (xy 5.757209 -454.383987)
			(xy 5.665444 -454.36421) (xy 5.575687 -454.336722) (xy 5.488584 -454.301722) (xy 5.404763 -454.25946)
			(xy 5.324828 -454.210242) (xy 5.249355 -454.154423) (xy 5.178888 -454.092404) (xy 5.113935 -454.024632)
			(xy 5.054962 -453.951597) (xy 5.002396 -453.873823) (xy 4.956615 -453.791871) (xy 4.917949 -453.706332)
			(xy 4.886677 -453.617823) (xy 4.863023 -453.52698) (xy 4.847159 -453.434458) (xy 4.839198 -453.340924)
			(xy 1.27 -453.340924) (xy 1.27 -454.646538) (xy 24.838658 -454.646538) (xy 24.842729 -454.590916)
			(xy 24.854855 -454.536479) (xy 24.874778 -454.484388) (xy 24.902074 -454.435753) (xy 24.93616 -454.39161)
			(xy 24.976309 -454.352901) (xy 25.021667 -454.32045) (xy 25.071267 -454.294949) (xy 25.124051 -454.276942)
			(xy 25.178894 -454.266812) (xy 25.234628 -454.264775) (xy 25.290065 -454.270875) (xy 25.344022 -454.284981)
			(xy 25.395351 -454.306793) (xy 25.442957 -454.335847) (xy 25.485825 -454.371522) (xy 25.523042 -454.413059)
			(xy 25.553815 -454.459572) (xy 25.577487 -454.510069) (xy 25.593555 -454.563476) (xy 25.601675 -454.618652)
			(xy 25.602184 -454.646538) (xy 25.601675 -454.674424) (xy 25.593555 -454.7296) (xy 25.577487 -454.783007)
			(xy 25.553815 -454.833504) (xy 25.523042 -454.880017) (xy 25.485825 -454.921554) (xy 25.442957 -454.957229)
			(xy 25.395351 -454.986283) (xy 25.344022 -455.008095) (xy 25.290065 -455.022201) (xy 25.234628 -455.028301)
			(xy 25.178894 -455.026264) (xy 25.124051 -455.016134) (xy 25.071267 -454.998127) (xy 25.021667 -454.972626)
			(xy 24.976309 -454.940175) (xy 24.93616 -454.901466) (xy 24.902074 -454.857323) (xy 24.874778 -454.808688)
			(xy 24.854855 -454.756597) (xy 24.842729 -454.70216) (xy 24.838658 -454.646538) (xy 1.27 -454.646538)
			(xy 1.27 -455.070073) (xy 26.851826 -455.070073) (xy 26.854933 -455.014607) (xy 26.866051 -454.960178)
			(xy 26.884946 -454.907936) (xy 26.911217 -454.858987) (xy 26.944309 -454.814366) (xy 26.983523 -454.775016)
			(xy 27.02803 -454.741769) (xy 27.076887 -454.715328) (xy 27.129063 -454.696252) (xy 27.183453 -454.684945)
			(xy 27.238908 -454.681646) (xy 27.294256 -454.686424) (xy 27.348325 -454.699179) (xy 27.399973 -454.71964)
			(xy 27.448107 -454.747375) (xy 27.491711 -454.781798) (xy 27.52986 -454.822181) (xy 27.56175 -454.867669)
			(xy 27.586706 -454.917302) (xy 27.604199 -454.970029) (xy 27.613861 -455.024736) (xy 27.615487 -455.080265)
			(xy 27.609042 -455.135443) (xy 27.594662 -455.189104) (xy 27.572653 -455.240111) (xy 27.558492 -455.264012)
			(xy 27.547184 -455.283157) (xy 27.530785 -455.324484) (xy 27.521838 -455.368037) (xy 27.520619 -455.412482)
			(xy 27.527165 -455.456459) (xy 27.541275 -455.498623) (xy 27.562517 -455.537682) (xy 27.576018 -455.55535)
			(xy 27.592935 -455.577387) (xy 27.62084 -455.625427) (xy 27.641483 -455.677005) (xy 27.654428 -455.731032)
			(xy 27.6594 -455.786365) (xy 27.656294 -455.841834) (xy 27.645177 -455.896266) (xy 27.626283 -455.94851)
			(xy 27.600012 -455.997462) (xy 27.566919 -456.042086) (xy 27.527705 -456.081439) (xy 27.483197 -456.114689)
			(xy 27.434338 -456.141132) (xy 27.382161 -456.16021) (xy 27.327768 -456.171519) (xy 27.27231 -456.17482)
			(xy 27.21696 -456.170043) (xy 27.162888 -456.157289) (xy 27.111237 -456.136828) (xy 27.0631 -456.109092)
			(xy 27.019494 -456.074669) (xy 26.981342 -456.034285) (xy 26.94945 -455.988795) (xy 26.924492 -455.93916)
			(xy 26.906997 -455.886431) (xy 26.897334 -455.831722) (xy 26.895707 -455.77619) (xy 26.902152 -455.721009)
			(xy 26.916531 -455.667346) (xy 26.938541 -455.616336) (xy 26.952702 -455.592434) (xy 26.963957 -455.573261)
			(xy 26.980355 -455.531941) (xy 26.989303 -455.488396) (xy 26.990528 -455.443958) (xy 26.983992 -455.399986)
			(xy 26.969895 -455.357825) (xy 26.948669 -455.318766) (xy 26.935176 -455.301096) (xy 26.91828 -455.279043)
			(xy 26.890378 -455.231005) (xy 26.869738 -455.179429) (xy 26.856796 -455.125404) (xy 26.851826 -455.070073)
			(xy 1.27 -455.070073) (xy 1.27 -457.541068) (xy 4.839198 -457.541068) (xy 4.839198 -457.447196) (xy 4.847159 -457.353662)
			(xy 4.863023 -457.26114) (xy 4.886677 -457.170297) (xy 4.917949 -457.081788) (xy 4.956615 -456.996249)
			(xy 5.002396 -456.914297) (xy 5.054962 -456.836523) (xy 5.113935 -456.763488) (xy 5.178888 -456.695716)
			(xy 5.249355 -456.633697) (xy 5.324828 -456.577878) (xy 5.404763 -456.52866) (xy 5.488584 -456.486398)
			(xy 5.575687 -456.451398) (xy 5.665444 -456.42391) (xy 5.757209 -456.404133) (xy 5.850321 -456.39221)
			(xy 5.944108 -456.388226) (xy 6.037895 -456.39221) (xy 6.131007 -456.404133) (xy 6.222772 -456.42391)
			(xy 6.312529 -456.451398) (xy 6.399632 -456.486398) (xy 6.483453 -456.52866) (xy 6.563388 -456.577878)
			(xy 6.638861 -456.633697) (xy 6.709328 -456.695716) (xy 6.774281 -456.763488) (xy 6.798403 -456.793362)
			(xy 29.519874 -456.793362) (xy 29.519874 -456.706462) (xy 29.527892 -456.619933) (xy 29.54386 -456.534513)
			(xy 29.567641 -456.450931) (xy 29.599033 -456.369899) (xy 29.637767 -456.29211) (xy 29.683514 -456.218226)
			(xy 29.735883 -456.148879) (xy 29.794427 -456.084659) (xy 29.858647 -456.026115) (xy 29.927994 -455.973746)
			(xy 30.001878 -455.927999) (xy 30.079667 -455.889265) (xy 30.160699 -455.857873) (xy 30.244281 -455.834092)
			(xy 30.329701 -455.818124) (xy 30.41623 -455.810106) (xy 30.50313 -455.810106) (xy 30.589659 -455.818124)
			(xy 30.675079 -455.834092) (xy 30.758661 -455.857873) (xy 30.839693 -455.889265) (xy 30.917482 -455.927999)
			(xy 30.991366 -455.973746) (xy 31.060713 -456.026115) (xy 31.124933 -456.084659) (xy 31.183477 -456.148879)
			(xy 31.235846 -456.218226) (xy 31.281593 -456.29211) (xy 31.320327 -456.369899) (xy 31.351719 -456.450931)
			(xy 31.3755 -456.534513) (xy 31.391468 -456.619933) (xy 31.399486 -456.706462) (xy 31.399988 -456.749912)
			(xy 31.399486 -456.793362) (xy 34.599874 -456.793362) (xy 34.599874 -456.706462) (xy 34.607892 -456.619933)
			(xy 34.62386 -456.534513) (xy 34.647641 -456.450931) (xy 34.679033 -456.369899) (xy 34.717767 -456.29211)
			(xy 34.763514 -456.218226) (xy 34.815883 -456.148879) (xy 34.874427 -456.084659) (xy 34.938647 -456.026115)
			(xy 35.007994 -455.973746) (xy 35.081878 -455.927999) (xy 35.159667 -455.889265) (xy 35.240699 -455.857873)
			(xy 35.324281 -455.834092) (xy 35.409701 -455.818124) (xy 35.49623 -455.810106) (xy 35.58313 -455.810106)
			(xy 35.669659 -455.818124) (xy 35.755079 -455.834092) (xy 35.838661 -455.857873) (xy 35.919693 -455.889265)
			(xy 35.997482 -455.927999) (xy 36.071366 -455.973746) (xy 36.140713 -456.026115) (xy 36.204933 -456.084659)
			(xy 36.263477 -456.148879) (xy 36.315846 -456.218226) (xy 36.361593 -456.29211) (xy 36.400327 -456.369899)
			(xy 36.431719 -456.450931) (xy 36.4555 -456.534513) (xy 36.471468 -456.619933) (xy 36.479486 -456.706462)
			(xy 36.479988 -456.749912) (xy 36.479486 -456.793362) (xy 36.471468 -456.879891) (xy 36.4555 -456.965311)
			(xy 36.431719 -457.048893) (xy 36.400327 -457.129925) (xy 36.361593 -457.207714) (xy 36.315846 -457.281598)
			(xy 36.263477 -457.350945) (xy 36.210978 -457.408534) (xy 39.35679 -457.408534) (xy 39.360861 -457.352912)
			(xy 39.372987 -457.298475) (xy 39.39291 -457.246384) (xy 39.420206 -457.197749) (xy 39.454292 -457.153606)
			(xy 39.494441 -457.114897) (xy 39.539799 -457.082446) (xy 39.589399 -457.056945) (xy 39.642183 -457.038938)
			(xy 39.697026 -457.028808) (xy 39.75276 -457.026771) (xy 39.808197 -457.032871) (xy 39.862154 -457.046977)
			(xy 39.913483 -457.068789) (xy 39.961089 -457.097843) (xy 40.003957 -457.133518) (xy 40.041174 -457.175055)
			(xy 40.071947 -457.221568) (xy 40.095619 -457.272065) (xy 40.111687 -457.325472) (xy 40.119807 -457.380648)
			(xy 40.120316 -457.408534) (xy 40.119807 -457.43642) (xy 40.111687 -457.491596) (xy 40.095619 -457.545003)
			(xy 40.071947 -457.5955) (xy 40.041174 -457.642013) (xy 40.003957 -457.68355) (xy 39.961089 -457.719225)
			(xy 39.913483 -457.748279) (xy 39.862154 -457.770091) (xy 39.808197 -457.784197) (xy 39.75276 -457.790297)
			(xy 39.697026 -457.78826) (xy 39.642183 -457.77813) (xy 39.589399 -457.760123) (xy 39.539799 -457.734622)
			(xy 39.494441 -457.702171) (xy 39.454292 -457.663462) (xy 39.420206 -457.619319) (xy 39.39291 -457.570684)
			(xy 39.372987 -457.518593) (xy 39.360861 -457.464156) (xy 39.35679 -457.408534) (xy 36.210978 -457.408534)
			(xy 36.204933 -457.415165) (xy 36.140713 -457.473709) (xy 36.071366 -457.526078) (xy 35.997482 -457.571825)
			(xy 35.919693 -457.610559) (xy 35.838661 -457.641951) (xy 35.755079 -457.665732) (xy 35.669659 -457.6817)
			(xy 35.58313 -457.689718) (xy 35.49623 -457.689718) (xy 35.409701 -457.6817) (xy 35.324281 -457.665732)
			(xy 35.240699 -457.641951) (xy 35.159667 -457.610559) (xy 35.081878 -457.571825) (xy 35.007994 -457.526078)
			(xy 34.938647 -457.473709) (xy 34.874427 -457.415165) (xy 34.815883 -457.350945) (xy 34.763514 -457.281598)
			(xy 34.717767 -457.207714) (xy 34.679033 -457.129925) (xy 34.647641 -457.048893) (xy 34.62386 -456.965311)
			(xy 34.607892 -456.879891) (xy 34.599874 -456.793362) (xy 31.399486 -456.793362) (xy 31.391468 -456.879891)
			(xy 31.3755 -456.965311) (xy 31.351719 -457.048893) (xy 31.320327 -457.129925) (xy 31.281593 -457.207714)
			(xy 31.235846 -457.281598) (xy 31.183477 -457.350945) (xy 31.124933 -457.415165) (xy 31.060713 -457.473709)
			(xy 30.991366 -457.526078) (xy 30.917482 -457.571825) (xy 30.839693 -457.610559) (xy 30.758661 -457.641951)
			(xy 30.675079 -457.665732) (xy 30.589659 -457.6817) (xy 30.50313 -457.689718) (xy 30.41623 -457.689718)
			(xy 30.329701 -457.6817) (xy 30.244281 -457.665732) (xy 30.160699 -457.641951) (xy 30.079667 -457.610559)
			(xy 30.001878 -457.571825) (xy 29.927994 -457.526078) (xy 29.858647 -457.473709) (xy 29.794427 -457.415165)
			(xy 29.735883 -457.350945) (xy 29.683514 -457.281598) (xy 29.637767 -457.207714) (xy 29.599033 -457.129925)
			(xy 29.567641 -457.048893) (xy 29.54386 -456.965311) (xy 29.527892 -456.879891) (xy 29.519874 -456.793362)
			(xy 6.798403 -456.793362) (xy 6.833254 -456.836523) (xy 6.88582 -456.914297) (xy 6.931601 -456.996249)
			(xy 6.970267 -457.081788) (xy 7.001539 -457.170297) (xy 7.025193 -457.26114) (xy 7.041057 -457.353662)
			(xy 7.049018 -457.447196) (xy 7.049516 -457.494132) (xy 7.049018 -457.541068) (xy 7.041057 -457.634602)
			(xy 7.025193 -457.727124) (xy 7.014961 -457.76642) (xy 26.750008 -457.76642) (xy 26.754079 -457.710798)
			(xy 26.766205 -457.656361) (xy 26.786128 -457.60427) (xy 26.813424 -457.555635) (xy 26.84751 -457.511492)
			(xy 26.887659 -457.472783) (xy 26.933017 -457.440332) (xy 26.982617 -457.414831) (xy 27.035401 -457.396824)
			(xy 27.090244 -457.386694) (xy 27.145978 -457.384657) (xy 27.201415 -457.390757) (xy 27.255372 -457.404863)
			(xy 27.306701 -457.426675) (xy 27.354307 -457.455729) (xy 27.397175 -457.491404) (xy 27.434392 -457.532941)
			(xy 27.465165 -457.579454) (xy 27.488837 -457.629951) (xy 27.504905 -457.683358) (xy 27.513025 -457.738534)
			(xy 27.513534 -457.76642) (xy 27.513025 -457.794306) (xy 27.504905 -457.849482) (xy 27.488837 -457.902889)
			(xy 27.465165 -457.953386) (xy 27.434392 -457.999899) (xy 27.397175 -458.041436) (xy 27.354307 -458.077111)
			(xy 27.306701 -458.106165) (xy 27.255372 -458.127977) (xy 27.201415 -458.142083) (xy 27.145978 -458.148183)
			(xy 27.090244 -458.146146) (xy 27.035401 -458.136016) (xy 26.982617 -458.118009) (xy 26.933017 -458.092508)
			(xy 26.887659 -458.060057) (xy 26.84751 -458.021348) (xy 26.813424 -457.977205) (xy 26.786128 -457.92857)
			(xy 26.766205 -457.876479) (xy 26.754079 -457.822042) (xy 26.750008 -457.76642) (xy 7.014961 -457.76642)
			(xy 7.001539 -457.817967) (xy 6.970267 -457.906476) (xy 6.931601 -457.992015) (xy 6.88582 -458.073967)
			(xy 6.833254 -458.151741) (xy 6.774281 -458.224776) (xy 6.709328 -458.292548) (xy 6.638861 -458.354567)
			(xy 6.563388 -458.410386) (xy 6.483453 -458.459604) (xy 6.399632 -458.501866) (xy 6.312529 -458.536866)
			(xy 6.222772 -458.564354) (xy 6.131007 -458.584131) (xy 6.037895 -458.596054) (xy 5.944108 -458.600039)
			(xy 5.850321 -458.596054) (xy 5.757209 -458.584131) (xy 5.665444 -458.564354) (xy 5.575687 -458.536866)
			(xy 5.488584 -458.501866) (xy 5.404763 -458.459604) (xy 5.324828 -458.410386) (xy 5.249355 -458.354567)
			(xy 5.178888 -458.292548) (xy 5.113935 -458.224776) (xy 5.054962 -458.151741) (xy 5.002396 -458.073967)
			(xy 4.956615 -457.992015) (xy 4.917949 -457.906476) (xy 4.886677 -457.817967) (xy 4.863023 -457.727124)
			(xy 4.847159 -457.634602) (xy 4.839198 -457.541068) (xy 1.27 -457.541068) (xy 1.27 -459.333362) (xy 29.519874 -459.333362)
			(xy 29.519874 -459.246462) (xy 29.527892 -459.159933) (xy 29.54386 -459.074513) (xy 29.567641 -458.990931)
			(xy 29.599033 -458.909899) (xy 29.637767 -458.83211) (xy 29.683514 -458.758226) (xy 29.735883 -458.688879)
			(xy 29.794427 -458.624659) (xy 29.858647 -458.566115) (xy 29.927994 -458.513746) (xy 30.001878 -458.467999)
			(xy 30.079667 -458.429265) (xy 30.160699 -458.397873) (xy 30.244281 -458.374092) (xy 30.329701 -458.358124)
			(xy 30.41623 -458.350106) (xy 30.50313 -458.350106) (xy 30.589659 -458.358124) (xy 30.675079 -458.374092)
			(xy 30.758661 -458.397873) (xy 30.839693 -458.429265) (xy 30.917482 -458.467999) (xy 30.991366 -458.513746)
			(xy 31.060713 -458.566115) (xy 31.124933 -458.624659) (xy 31.183477 -458.688879) (xy 31.235846 -458.758226)
			(xy 31.281593 -458.83211) (xy 31.320327 -458.909899) (xy 31.351719 -458.990931) (xy 31.3755 -459.074513)
			(xy 31.391468 -459.159933) (xy 31.399486 -459.246462) (xy 31.399988 -459.289912) (xy 31.399486 -459.333362)
			(xy 34.599874 -459.333362) (xy 34.599874 -459.246462) (xy 34.607892 -459.159933) (xy 34.62386 -459.074513)
			(xy 34.647641 -458.990931) (xy 34.679033 -458.909899) (xy 34.717767 -458.83211) (xy 34.763514 -458.758226)
			(xy 34.815883 -458.688879) (xy 34.874427 -458.624659) (xy 34.938647 -458.566115) (xy 35.007994 -458.513746)
			(xy 35.081878 -458.467999) (xy 35.159667 -458.429265) (xy 35.240699 -458.397873) (xy 35.324281 -458.374092)
			(xy 35.409701 -458.358124) (xy 35.49623 -458.350106) (xy 35.58313 -458.350106) (xy 35.669659 -458.358124)
			(xy 35.755079 -458.374092) (xy 35.838661 -458.397873) (xy 35.919693 -458.429265) (xy 35.997482 -458.467999)
			(xy 36.071366 -458.513746) (xy 36.140713 -458.566115) (xy 36.204933 -458.624659) (xy 36.263477 -458.688879)
			(xy 36.315846 -458.758226) (xy 36.361593 -458.83211) (xy 36.400327 -458.909899) (xy 36.431719 -458.990931)
			(xy 36.4555 -459.074513) (xy 36.471468 -459.159933) (xy 36.472026 -459.16596) (xy 40.801542 -459.16596)
			(xy 40.805613 -459.110338) (xy 40.817739 -459.055901) (xy 40.837662 -459.00381) (xy 40.864958 -458.955175)
			(xy 40.899044 -458.911032) (xy 40.939193 -458.872323) (xy 40.984551 -458.839872) (xy 41.034151 -458.814371)
			(xy 41.086935 -458.796364) (xy 41.141778 -458.786234) (xy 41.197512 -458.784197) (xy 41.252949 -458.790297)
			(xy 41.306906 -458.804403) (xy 41.358235 -458.826215) (xy 41.405841 -458.855269) (xy 41.448709 -458.890944)
			(xy 41.485926 -458.932481) (xy 41.516699 -458.978994) (xy 41.540371 -459.029491) (xy 41.556439 -459.082898)
			(xy 41.564559 -459.138074) (xy 41.565068 -459.16596) (xy 41.564559 -459.193846) (xy 41.556439 -459.249022)
			(xy 41.540371 -459.302429) (xy 41.516699 -459.352926) (xy 41.485926 -459.399439) (xy 41.448709 -459.440976)
			(xy 41.405841 -459.476651) (xy 41.358235 -459.505705) (xy 41.306906 -459.527517) (xy 41.252949 -459.541623)
			(xy 41.197512 -459.547723) (xy 41.141778 -459.545686) (xy 41.086935 -459.535556) (xy 41.034151 -459.517549)
			(xy 40.984551 -459.492048) (xy 40.939193 -459.459597) (xy 40.899044 -459.420888) (xy 40.864958 -459.376745)
			(xy 40.837662 -459.32811) (xy 40.817739 -459.276019) (xy 40.805613 -459.221582) (xy 40.801542 -459.16596)
			(xy 36.472026 -459.16596) (xy 36.479486 -459.246462) (xy 36.479988 -459.289912) (xy 36.479486 -459.333362)
			(xy 36.471468 -459.419891) (xy 36.4555 -459.505311) (xy 36.431719 -459.588893) (xy 36.400327 -459.669925)
			(xy 36.361593 -459.747714) (xy 36.315846 -459.821598) (xy 36.263477 -459.890945) (xy 36.204933 -459.955165)
			(xy 36.140713 -460.013709) (xy 36.071366 -460.066078) (xy 35.997482 -460.111825) (xy 35.919693 -460.150559)
			(xy 35.838661 -460.181951) (xy 35.755079 -460.205732) (xy 35.669659 -460.2217) (xy 35.58313 -460.229718)
			(xy 35.49623 -460.229718) (xy 35.409701 -460.2217) (xy 35.324281 -460.205732) (xy 35.240699 -460.181951)
			(xy 35.159667 -460.150559) (xy 35.081878 -460.111825) (xy 35.007994 -460.066078) (xy 34.938647 -460.013709)
			(xy 34.874427 -459.955165) (xy 34.815883 -459.890945) (xy 34.763514 -459.821598) (xy 34.717767 -459.747714)
			(xy 34.679033 -459.669925) (xy 34.647641 -459.588893) (xy 34.62386 -459.505311) (xy 34.607892 -459.419891)
			(xy 34.599874 -459.333362) (xy 31.399486 -459.333362) (xy 31.391468 -459.419891) (xy 31.3755 -459.505311)
			(xy 31.351719 -459.588893) (xy 31.320327 -459.669925) (xy 31.281593 -459.747714) (xy 31.235846 -459.821598)
			(xy 31.183477 -459.890945) (xy 31.124933 -459.955165) (xy 31.060713 -460.013709) (xy 30.991366 -460.066078)
			(xy 30.917482 -460.111825) (xy 30.839693 -460.150559) (xy 30.758661 -460.181951) (xy 30.675079 -460.205732)
			(xy 30.589659 -460.2217) (xy 30.50313 -460.229718) (xy 30.41623 -460.229718) (xy 30.329701 -460.2217)
			(xy 30.244281 -460.205732) (xy 30.160699 -460.181951) (xy 30.079667 -460.150559) (xy 30.001878 -460.111825)
			(xy 29.927994 -460.066078) (xy 29.858647 -460.013709) (xy 29.794427 -459.955165) (xy 29.735883 -459.890945)
			(xy 29.683514 -459.821598) (xy 29.637767 -459.747714) (xy 29.599033 -459.669925) (xy 29.567641 -459.588893)
			(xy 29.54386 -459.505311) (xy 29.527892 -459.419891) (xy 29.519874 -459.333362) (xy 1.27 -459.333362)
			(xy 1.27 -460.277972) (xy 27.258008 -460.277972) (xy 27.262079 -460.22235) (xy 27.274205 -460.167913)
			(xy 27.294128 -460.115822) (xy 27.321424 -460.067187) (xy 27.35551 -460.023044) (xy 27.395659 -459.984335)
			(xy 27.441017 -459.951884) (xy 27.490617 -459.926383) (xy 27.543401 -459.908376) (xy 27.598244 -459.898246)
			(xy 27.653978 -459.896209) (xy 27.709415 -459.902309) (xy 27.763372 -459.916415) (xy 27.814701 -459.938227)
			(xy 27.862307 -459.967281) (xy 27.905175 -460.002956) (xy 27.942392 -460.044493) (xy 27.973165 -460.091006)
			(xy 27.996837 -460.141503) (xy 28.012905 -460.19491) (xy 28.021025 -460.250086) (xy 28.021534 -460.277972)
			(xy 28.021025 -460.305858) (xy 28.012905 -460.361034) (xy 27.996837 -460.414441) (xy 27.973165 -460.464938)
			(xy 27.942392 -460.511451) (xy 27.905175 -460.552988) (xy 27.862307 -460.588663) (xy 27.814701 -460.617717)
			(xy 27.763372 -460.639529) (xy 27.709415 -460.653635) (xy 27.653978 -460.659735) (xy 27.598244 -460.657698)
			(xy 27.543401 -460.647568) (xy 27.490617 -460.629561) (xy 27.441017 -460.60406) (xy 27.395659 -460.571609)
			(xy 27.35551 -460.5329) (xy 27.321424 -460.488757) (xy 27.294128 -460.440122) (xy 27.274205 -460.388031)
			(xy 27.262079 -460.333594) (xy 27.258008 -460.277972) (xy 1.27 -460.277972) (xy 1.27 -461.740958)
			(xy 4.839198 -461.740958) (xy 4.839198 -461.647086) (xy 4.847159 -461.553552) (xy 4.863023 -461.46103)
			(xy 4.886677 -461.370187) (xy 4.917949 -461.281678) (xy 4.956615 -461.196139) (xy 5.002396 -461.114187)
			(xy 5.054962 -461.036413) (xy 5.113935 -460.963378) (xy 5.178888 -460.895606) (xy 5.249355 -460.833587)
			(xy 5.324828 -460.777768) (xy 5.404763 -460.72855) (xy 5.488584 -460.686288) (xy 5.575687 -460.651288)
			(xy 5.665444 -460.6238) (xy 5.757209 -460.604023) (xy 5.850321 -460.5921) (xy 5.944108 -460.588116)
			(xy 6.037895 -460.5921) (xy 6.131007 -460.604023) (xy 6.222772 -460.6238) (xy 6.312529 -460.651288)
			(xy 6.399632 -460.686288) (xy 6.483453 -460.72855) (xy 6.563388 -460.777768) (xy 6.638861 -460.833587)
			(xy 6.709328 -460.895606) (xy 6.774281 -460.963378) (xy 6.833254 -461.036413) (xy 6.88582 -461.114187)
			(xy 6.931601 -461.196139) (xy 6.970267 -461.281678) (xy 7.001539 -461.370187) (xy 7.025193 -461.46103)
			(xy 7.041057 -461.553552) (xy 7.049018 -461.647086) (xy 7.049516 -461.694022) (xy 7.049018 -461.740958)
			(xy 10.339314 -461.740958) (xy 10.339314 -461.647086) (xy 10.347275 -461.553552) (xy 10.363139 -461.46103)
			(xy 10.386793 -461.370187) (xy 10.418065 -461.281678) (xy 10.456731 -461.196139) (xy 10.502512 -461.114187)
			(xy 10.555078 -461.036413) (xy 10.614051 -460.963378) (xy 10.679004 -460.895606) (xy 10.749471 -460.833587)
			(xy 10.824944 -460.777768) (xy 10.904879 -460.72855) (xy 10.9887 -460.686288) (xy 11.075803 -460.651288)
			(xy 11.16556 -460.6238) (xy 11.257325 -460.604023) (xy 11.350437 -460.5921) (xy 11.444224 -460.588116)
			(xy 11.538011 -460.5921) (xy 11.631123 -460.604023) (xy 11.722888 -460.6238) (xy 11.812645 -460.651288)
			(xy 11.899748 -460.686288) (xy 11.983569 -460.72855) (xy 12.063504 -460.777768) (xy 12.138977 -460.833587)
			(xy 12.209444 -460.895606) (xy 12.274397 -460.963378) (xy 12.33337 -461.036413) (xy 12.354488 -461.067658)
			(xy 26.457908 -461.067658) (xy 26.461979 -461.012036) (xy 26.474105 -460.957599) (xy 26.494028 -460.905508)
			(xy 26.521324 -460.856873) (xy 26.55541 -460.81273) (xy 26.595559 -460.774021) (xy 26.640917 -460.74157)
			(xy 26.690517 -460.716069) (xy 26.743301 -460.698062) (xy 26.798144 -460.687932) (xy 26.853878 -460.685895)
			(xy 26.909315 -460.691995) (xy 26.963272 -460.706101) (xy 27.014601 -460.727913) (xy 27.062207 -460.756967)
			(xy 27.105075 -460.792642) (xy 27.142292 -460.834179) (xy 27.173065 -460.880692) (xy 27.196737 -460.931189)
			(xy 27.212805 -460.984596) (xy 27.220925 -461.039772) (xy 27.221434 -461.067658) (xy 27.220925 -461.095544)
			(xy 27.212805 -461.15072) (xy 27.196737 -461.204127) (xy 27.173065 -461.254624) (xy 27.142292 -461.301137)
			(xy 27.105075 -461.342674) (xy 27.062207 -461.378349) (xy 27.014601 -461.407403) (xy 26.963272 -461.429215)
			(xy 26.909315 -461.443321) (xy 26.853878 -461.449421) (xy 26.798144 -461.447384) (xy 26.743301 -461.437254)
			(xy 26.690517 -461.419247) (xy 26.640917 -461.393746) (xy 26.595559 -461.361295) (xy 26.55541 -461.322586)
			(xy 26.521324 -461.278443) (xy 26.494028 -461.229808) (xy 26.474105 -461.177717) (xy 26.461979 -461.12328)
			(xy 26.457908 -461.067658) (xy 12.354488 -461.067658) (xy 12.385936 -461.114187) (xy 12.431717 -461.196139)
			(xy 12.470383 -461.281678) (xy 12.501655 -461.370187) (xy 12.525309 -461.46103) (xy 12.541173 -461.553552)
			(xy 12.549134 -461.647086) (xy 12.549632 -461.694022) (xy 12.549134 -461.740958) (xy 12.541173 -461.834492)
			(xy 12.534508 -461.873362) (xy 29.519874 -461.873362) (xy 29.519874 -461.786462) (xy 29.527892 -461.699933)
			(xy 29.54386 -461.614513) (xy 29.567641 -461.530931) (xy 29.599033 -461.449899) (xy 29.637767 -461.37211)
			(xy 29.683514 -461.298226) (xy 29.735883 -461.228879) (xy 29.794427 -461.164659) (xy 29.858647 -461.106115)
			(xy 29.927994 -461.053746) (xy 30.001878 -461.007999) (xy 30.079667 -460.969265) (xy 30.160699 -460.937873)
			(xy 30.244281 -460.914092) (xy 30.329701 -460.898124) (xy 30.41623 -460.890106) (xy 30.50313 -460.890106)
			(xy 30.589659 -460.898124) (xy 30.675079 -460.914092) (xy 30.758661 -460.937873) (xy 30.839693 -460.969265)
			(xy 30.917482 -461.007999) (xy 30.991366 -461.053746) (xy 31.060713 -461.106115) (xy 31.124933 -461.164659)
			(xy 31.183477 -461.228879) (xy 31.235846 -461.298226) (xy 31.281593 -461.37211) (xy 31.320327 -461.449899)
			(xy 31.351719 -461.530931) (xy 31.3755 -461.614513) (xy 31.391468 -461.699933) (xy 31.399486 -461.786462)
			(xy 31.399988 -461.829912) (xy 31.399486 -461.873362) (xy 34.599874 -461.873362) (xy 34.599874 -461.786462)
			(xy 34.607892 -461.699933) (xy 34.62386 -461.614513) (xy 34.647641 -461.530931) (xy 34.679033 -461.449899)
			(xy 34.717767 -461.37211) (xy 34.763514 -461.298226) (xy 34.815883 -461.228879) (xy 34.874427 -461.164659)
			(xy 34.938647 -461.106115) (xy 35.007994 -461.053746) (xy 35.081878 -461.007999) (xy 35.159667 -460.969265)
			(xy 35.240699 -460.937873) (xy 35.324281 -460.914092) (xy 35.409701 -460.898124) (xy 35.49623 -460.890106)
			(xy 35.58313 -460.890106) (xy 35.669659 -460.898124) (xy 35.755079 -460.914092) (xy 35.838661 -460.937873)
			(xy 35.919693 -460.969265) (xy 35.997482 -461.007999) (xy 36.071366 -461.053746) (xy 36.140713 -461.106115)
			(xy 36.204933 -461.164659) (xy 36.210052 -461.170274) (xy 41.083482 -461.170274) (xy 41.087553 -461.114652)
			(xy 41.099679 -461.060215) (xy 41.119602 -461.008124) (xy 41.146898 -460.959489) (xy 41.180984 -460.915346)
			(xy 41.221133 -460.876637) (xy 41.266491 -460.844186) (xy 41.316091 -460.818685) (xy 41.368875 -460.800678)
			(xy 41.423718 -460.790548) (xy 41.479452 -460.788511) (xy 41.534889 -460.794611) (xy 41.588846 -460.808717)
			(xy 41.640175 -460.830529) (xy 41.684532 -460.8576) (xy 72.420224 -460.8576) (xy 72.424295 -460.801978)
			(xy 72.436421 -460.747541) (xy 72.456344 -460.69545) (xy 72.48364 -460.646815) (xy 72.517726 -460.602672)
			(xy 72.557875 -460.563963) (xy 72.603233 -460.531512) (xy 72.652833 -460.506011) (xy 72.705617 -460.488004)
			(xy 72.76046 -460.477874) (xy 72.816194 -460.475837) (xy 72.871631 -460.481937) (xy 72.925588 -460.496043)
			(xy 72.976917 -460.517855) (xy 73.024523 -460.546909) (xy 73.067391 -460.582584) (xy 73.104608 -460.624121)
			(xy 73.135381 -460.670634) (xy 73.159053 -460.721131) (xy 73.175121 -460.774538) (xy 73.183241 -460.829714)
			(xy 73.18375 -460.8576) (xy 73.183241 -460.885486) (xy 73.175121 -460.940662) (xy 73.166028 -460.970884)
			(xy 73.671682 -460.970884) (xy 73.675753 -460.915262) (xy 73.687879 -460.860825) (xy 73.707802 -460.808734)
			(xy 73.735098 -460.760099) (xy 73.769184 -460.715956) (xy 73.809333 -460.677247) (xy 73.854691 -460.644796)
			(xy 73.904291 -460.619295) (xy 73.957075 -460.601288) (xy 74.011918 -460.591158) (xy 74.067652 -460.589121)
			(xy 74.123089 -460.595221) (xy 74.177046 -460.609327) (xy 74.228375 -460.631139) (xy 74.275981 -460.660193)
			(xy 74.318849 -460.695868) (xy 74.356066 -460.737405) (xy 74.386839 -460.783918) (xy 74.410511 -460.834415)
			(xy 74.426579 -460.887822) (xy 74.434699 -460.942998) (xy 74.435208 -460.970884) (xy 74.434699 -460.99877)
			(xy 74.426579 -461.053946) (xy 74.410511 -461.107353) (xy 74.386839 -461.15785) (xy 74.356066 -461.204363)
			(xy 74.318849 -461.2459) (xy 74.275981 -461.281575) (xy 74.228375 -461.310629) (xy 74.177046 -461.332441)
			(xy 74.123089 -461.346547) (xy 74.067652 -461.352647) (xy 74.011918 -461.35061) (xy 73.957075 -461.34048)
			(xy 73.904291 -461.322473) (xy 73.854691 -461.296972) (xy 73.809333 -461.264521) (xy 73.769184 -461.225812)
			(xy 73.735098 -461.181669) (xy 73.707802 -461.133034) (xy 73.687879 -461.080943) (xy 73.675753 -461.026506)
			(xy 73.671682 -460.970884) (xy 73.166028 -460.970884) (xy 73.159053 -460.994069) (xy 73.135381 -461.044566)
			(xy 73.104608 -461.091079) (xy 73.067391 -461.132616) (xy 73.024523 -461.168291) (xy 72.976917 -461.197345)
			(xy 72.925588 -461.219157) (xy 72.871631 -461.233263) (xy 72.816194 -461.239363) (xy 72.76046 -461.237326)
			(xy 72.705617 -461.227196) (xy 72.652833 -461.209189) (xy 72.603233 -461.183688) (xy 72.557875 -461.151237)
			(xy 72.517726 -461.112528) (xy 72.48364 -461.068385) (xy 72.456344 -461.01975) (xy 72.436421 -460.967659)
			(xy 72.424295 -460.913222) (xy 72.420224 -460.8576) (xy 41.684532 -460.8576) (xy 41.687781 -460.859583)
			(xy 41.730649 -460.895258) (xy 41.767866 -460.936795) (xy 41.798639 -460.983308) (xy 41.822311 -461.033805)
			(xy 41.838379 -461.087212) (xy 41.846499 -461.142388) (xy 41.847008 -461.170274) (xy 41.846499 -461.19816)
			(xy 41.838379 -461.253336) (xy 41.822311 -461.306743) (xy 41.798639 -461.35724) (xy 41.767866 -461.403753)
			(xy 41.730649 -461.44529) (xy 41.687781 -461.480965) (xy 41.640175 -461.510019) (xy 41.588846 -461.531831)
			(xy 41.534889 -461.545937) (xy 41.479452 -461.552037) (xy 41.423718 -461.55) (xy 41.368875 -461.53987)
			(xy 41.316091 -461.521863) (xy 41.266491 -461.496362) (xy 41.221133 -461.463911) (xy 41.180984 -461.425202)
			(xy 41.146898 -461.381059) (xy 41.119602 -461.332424) (xy 41.099679 -461.280333) (xy 41.087553 -461.225896)
			(xy 41.083482 -461.170274) (xy 36.210052 -461.170274) (xy 36.263477 -461.228879) (xy 36.315846 -461.298226)
			(xy 36.361593 -461.37211) (xy 36.400327 -461.449899) (xy 36.431719 -461.530931) (xy 36.4555 -461.614513)
			(xy 36.471468 -461.699933) (xy 36.479486 -461.786462) (xy 36.479988 -461.829912) (xy 36.479486 -461.873362)
			(xy 36.471468 -461.959891) (xy 36.4555 -462.045311) (xy 36.431719 -462.128893) (xy 36.41559 -462.170526)
			(xy 71.008746 -462.170526) (xy 71.012817 -462.114904) (xy 71.024943 -462.060467) (xy 71.044866 -462.008376)
			(xy 71.072162 -461.959741) (xy 71.106248 -461.915598) (xy 71.146397 -461.876889) (xy 71.191755 -461.844438)
			(xy 71.241355 -461.818937) (xy 71.294139 -461.80093) (xy 71.348982 -461.7908) (xy 71.404716 -461.788763)
			(xy 71.460153 -461.794863) (xy 71.51411 -461.808969) (xy 71.565439 -461.830781) (xy 71.613045 -461.859835)
			(xy 71.655913 -461.89551) (xy 71.69313 -461.937047) (xy 71.723903 -461.98356) (xy 71.747575 -462.034057)
			(xy 71.763643 -462.087464) (xy 71.771763 -462.14264) (xy 71.772272 -462.170526) (xy 71.771763 -462.198412)
			(xy 71.763643 -462.253588) (xy 71.747575 -462.306995) (xy 71.723903 -462.357492) (xy 71.69313 -462.404005)
			(xy 71.655913 -462.445542) (xy 71.613045 -462.481217) (xy 71.565439 -462.510271) (xy 71.51411 -462.532083)
			(xy 71.460153 -462.546189) (xy 71.404716 -462.552289) (xy 71.348982 -462.550252) (xy 71.294139 -462.540122)
			(xy 71.241355 -462.522115) (xy 71.191755 -462.496614) (xy 71.146397 -462.464163) (xy 71.106248 -462.425454)
			(xy 71.072162 -462.381311) (xy 71.044866 -462.332676) (xy 71.024943 -462.280585) (xy 71.012817 -462.226148)
			(xy 71.008746 -462.170526) (xy 36.41559 -462.170526) (xy 36.400327 -462.209925) (xy 36.361593 -462.287714)
			(xy 36.315846 -462.361598) (xy 36.263477 -462.430945) (xy 36.204933 -462.495165) (xy 36.140713 -462.553709)
			(xy 36.071366 -462.606078) (xy 35.997482 -462.651825) (xy 35.919693 -462.690559) (xy 35.838661 -462.721951)
			(xy 35.755079 -462.745732) (xy 35.669659 -462.7617) (xy 35.58313 -462.769718) (xy 35.49623 -462.769718)
			(xy 35.409701 -462.7617) (xy 35.324281 -462.745732) (xy 35.240699 -462.721951) (xy 35.159667 -462.690559)
			(xy 35.081878 -462.651825) (xy 35.007994 -462.606078) (xy 34.938647 -462.553709) (xy 34.874427 -462.495165)
			(xy 34.815883 -462.430945) (xy 34.763514 -462.361598) (xy 34.717767 -462.287714) (xy 34.679033 -462.209925)
			(xy 34.647641 -462.128893) (xy 34.62386 -462.045311) (xy 34.607892 -461.959891) (xy 34.599874 -461.873362)
			(xy 31.399486 -461.873362) (xy 31.391468 -461.959891) (xy 31.3755 -462.045311) (xy 31.351719 -462.128893)
			(xy 31.320327 -462.209925) (xy 31.281593 -462.287714) (xy 31.235846 -462.361598) (xy 31.183477 -462.430945)
			(xy 31.124933 -462.495165) (xy 31.060713 -462.553709) (xy 30.991366 -462.606078) (xy 30.917482 -462.651825)
			(xy 30.839693 -462.690559) (xy 30.758661 -462.721951) (xy 30.675079 -462.745732) (xy 30.589659 -462.7617)
			(xy 30.50313 -462.769718) (xy 30.41623 -462.769718) (xy 30.329701 -462.7617) (xy 30.244281 -462.745732)
			(xy 30.160699 -462.721951) (xy 30.079667 -462.690559) (xy 30.001878 -462.651825) (xy 29.927994 -462.606078)
			(xy 29.858647 -462.553709) (xy 29.794427 -462.495165) (xy 29.735883 -462.430945) (xy 29.683514 -462.361598)
			(xy 29.637767 -462.287714) (xy 29.599033 -462.209925) (xy 29.567641 -462.128893) (xy 29.54386 -462.045311)
			(xy 29.527892 -461.959891) (xy 29.519874 -461.873362) (xy 12.534508 -461.873362) (xy 12.525309 -461.927014)
			(xy 12.501655 -462.017857) (xy 12.470383 -462.106366) (xy 12.431717 -462.191905) (xy 12.385936 -462.273857)
			(xy 12.33337 -462.351631) (xy 12.274397 -462.424666) (xy 12.209444 -462.492438) (xy 12.138977 -462.554457)
			(xy 12.063504 -462.610276) (xy 11.983569 -462.659494) (xy 11.899748 -462.701756) (xy 11.812645 -462.736756)
			(xy 11.722888 -462.764244) (xy 11.631123 -462.784021) (xy 11.538011 -462.795944) (xy 11.444224 -462.799929)
			(xy 11.350437 -462.795944) (xy 11.257325 -462.784021) (xy 11.16556 -462.764244) (xy 11.075803 -462.736756)
			(xy 10.9887 -462.701756) (xy 10.904879 -462.659494) (xy 10.824944 -462.610276) (xy 10.749471 -462.554457)
			(xy 10.679004 -462.492438) (xy 10.614051 -462.424666) (xy 10.555078 -462.351631) (xy 10.502512 -462.273857)
			(xy 10.456731 -462.191905) (xy 10.418065 -462.106366) (xy 10.386793 -462.017857) (xy 10.363139 -461.927014)
			(xy 10.347275 -461.834492) (xy 10.339314 -461.740958) (xy 7.049018 -461.740958) (xy 7.041057 -461.834492)
			(xy 7.025193 -461.927014) (xy 7.001539 -462.017857) (xy 6.970267 -462.106366) (xy 6.931601 -462.191905)
			(xy 6.88582 -462.273857) (xy 6.833254 -462.351631) (xy 6.774281 -462.424666) (xy 6.709328 -462.492438)
			(xy 6.638861 -462.554457) (xy 6.563388 -462.610276) (xy 6.483453 -462.659494) (xy 6.399632 -462.701756)
			(xy 6.312529 -462.736756) (xy 6.222772 -462.764244) (xy 6.131007 -462.784021) (xy 6.037895 -462.795944)
			(xy 5.944108 -462.799929) (xy 5.850321 -462.795944) (xy 5.757209 -462.784021) (xy 5.665444 -462.764244)
			(xy 5.575687 -462.736756) (xy 5.488584 -462.701756) (xy 5.404763 -462.659494) (xy 5.324828 -462.610276)
			(xy 5.249355 -462.554457) (xy 5.178888 -462.492438) (xy 5.113935 -462.424666) (xy 5.054962 -462.351631)
			(xy 5.002396 -462.273857) (xy 4.956615 -462.191905) (xy 4.917949 -462.106366) (xy 4.886677 -462.017857)
			(xy 4.863023 -461.927014) (xy 4.847159 -461.834492) (xy 4.839198 -461.740958) (xy 1.27 -461.740958)
			(xy 1.27 -463.41538) (xy 27.258008 -463.41538) (xy 27.262079 -463.359758) (xy 27.274205 -463.305321)
			(xy 27.294128 -463.25323) (xy 27.321424 -463.204595) (xy 27.35551 -463.160452) (xy 27.395659 -463.121743)
			(xy 27.441017 -463.089292) (xy 27.490617 -463.063791) (xy 27.543401 -463.045784) (xy 27.598244 -463.035654)
			(xy 27.653978 -463.033617) (xy 27.709415 -463.039717) (xy 27.763372 -463.053823) (xy 27.814701 -463.075635)
			(xy 27.862307 -463.104689) (xy 27.904994 -463.140213) (xy 47.82311 -463.140213) (xy 47.82311 -463.059103)
			(xy 47.83106 -462.978384) (xy 47.846883 -462.898833) (xy 47.870428 -462.821217) (xy 47.901467 -462.746281)
			(xy 47.939702 -462.674749) (xy 47.984764 -462.607309) (xy 48.036219 -462.54461) (xy 48.093572 -462.487257)
			(xy 48.156271 -462.435802) (xy 48.223711 -462.39074) (xy 48.295243 -462.352505) (xy 48.370179 -462.321466)
			(xy 48.447795 -462.297921) (xy 48.527346 -462.282098) (xy 48.608065 -462.274148) (xy 48.689175 -462.274148)
			(xy 48.769894 -462.282098) (xy 48.849445 -462.297921) (xy 48.927061 -462.321466) (xy 49.001997 -462.352505)
			(xy 49.073529 -462.39074) (xy 49.140969 -462.435802) (xy 49.203668 -462.487257) (xy 49.261021 -462.54461)
			(xy 49.312476 -462.607309) (xy 49.357538 -462.674749) (xy 49.395773 -462.746281) (xy 49.426812 -462.821217)
			(xy 49.450357 -462.898833) (xy 49.46618 -462.978384) (xy 49.47413 -463.059103) (xy 49.474628 -463.099658)
			(xy 49.47413 -463.140213) (xy 49.46618 -463.220932) (xy 49.450357 -463.300483) (xy 49.426812 -463.378099)
			(xy 49.395773 -463.453035) (xy 49.357538 -463.524567) (xy 49.312476 -463.592007) (xy 49.261021 -463.654706)
			(xy 49.203668 -463.712059) (xy 49.140969 -463.763514) (xy 49.073529 -463.808576) (xy 49.001997 -463.846811)
			(xy 48.927061 -463.87785) (xy 48.849445 -463.901395) (xy 48.769894 -463.917218) (xy 48.689175 -463.925168)
			(xy 48.608065 -463.925168) (xy 48.527346 -463.917218) (xy 48.447795 -463.901395) (xy 48.370179 -463.87785)
			(xy 48.295243 -463.846811) (xy 48.223711 -463.808576) (xy 48.156271 -463.763514) (xy 48.093572 -463.712059)
			(xy 48.036219 -463.654706) (xy 47.984764 -463.592007) (xy 47.939702 -463.524567) (xy 47.901467 -463.453035)
			(xy 47.870428 -463.378099) (xy 47.846883 -463.300483) (xy 47.83106 -463.220932) (xy 47.82311 -463.140213)
			(xy 27.904994 -463.140213) (xy 27.905175 -463.140364) (xy 27.942392 -463.181901) (xy 27.973165 -463.228414)
			(xy 27.996837 -463.278911) (xy 28.012905 -463.332318) (xy 28.021025 -463.387494) (xy 28.021534 -463.41538)
			(xy 28.021025 -463.443266) (xy 28.012905 -463.498442) (xy 27.996837 -463.551849) (xy 27.973165 -463.602346)
			(xy 27.942392 -463.648859) (xy 27.905175 -463.690396) (xy 27.862307 -463.726071) (xy 27.814701 -463.755125)
			(xy 27.763372 -463.776937) (xy 27.709415 -463.791043) (xy 27.653978 -463.797143) (xy 27.598244 -463.795106)
			(xy 27.543401 -463.784976) (xy 27.490617 -463.766969) (xy 27.441017 -463.741468) (xy 27.395659 -463.709017)
			(xy 27.35551 -463.670308) (xy 27.321424 -463.626165) (xy 27.294128 -463.57753) (xy 27.274205 -463.525439)
			(xy 27.262079 -463.471002) (xy 27.258008 -463.41538) (xy 1.27 -463.41538) (xy 1.27 -464.413362) (xy 29.519874 -464.413362)
			(xy 29.519874 -464.326462) (xy 29.527892 -464.239933) (xy 29.54386 -464.154513) (xy 29.567641 -464.070931)
			(xy 29.599033 -463.989899) (xy 29.637767 -463.91211) (xy 29.683514 -463.838226) (xy 29.735883 -463.768879)
			(xy 29.794427 -463.704659) (xy 29.858647 -463.646115) (xy 29.927994 -463.593746) (xy 30.001878 -463.547999)
			(xy 30.079667 -463.509265) (xy 30.160699 -463.477873) (xy 30.244281 -463.454092) (xy 30.329701 -463.438124)
			(xy 30.41623 -463.430106) (xy 30.50313 -463.430106) (xy 30.589659 -463.438124) (xy 30.675079 -463.454092)
			(xy 30.758661 -463.477873) (xy 30.839693 -463.509265) (xy 30.917482 -463.547999) (xy 30.991366 -463.593746)
			(xy 31.060713 -463.646115) (xy 31.124933 -463.704659) (xy 31.183477 -463.768879) (xy 31.235846 -463.838226)
			(xy 31.281593 -463.91211) (xy 31.320327 -463.989899) (xy 31.351719 -464.070931) (xy 31.3755 -464.154513)
			(xy 31.391468 -464.239933) (xy 31.399486 -464.326462) (xy 31.399988 -464.369912) (xy 31.399486 -464.413362)
			(xy 34.599874 -464.413362) (xy 34.599874 -464.326462) (xy 34.607892 -464.239933) (xy 34.62386 -464.154513)
			(xy 34.647641 -464.070931) (xy 34.679033 -463.989899) (xy 34.717767 -463.91211) (xy 34.763514 -463.838226)
			(xy 34.815883 -463.768879) (xy 34.874427 -463.704659) (xy 34.938647 -463.646115) (xy 35.007994 -463.593746)
			(xy 35.081878 -463.547999) (xy 35.159667 -463.509265) (xy 35.240699 -463.477873) (xy 35.324281 -463.454092)
			(xy 35.409701 -463.438124) (xy 35.49623 -463.430106) (xy 35.58313 -463.430106) (xy 35.669659 -463.438124)
			(xy 35.755079 -463.454092) (xy 35.838661 -463.477873) (xy 35.919693 -463.509265) (xy 35.997482 -463.547999)
			(xy 36.036403 -463.572098) (xy 40.023032 -463.572098) (xy 40.027103 -463.516476) (xy 40.039229 -463.462039)
			(xy 40.059152 -463.409948) (xy 40.086448 -463.361313) (xy 40.120534 -463.31717) (xy 40.160683 -463.278461)
			(xy 40.206041 -463.24601) (xy 40.255641 -463.220509) (xy 40.308425 -463.202502) (xy 40.363268 -463.192372)
			(xy 40.419002 -463.190335) (xy 40.474439 -463.196435) (xy 40.528396 -463.210541) (xy 40.579725 -463.232353)
			(xy 40.627331 -463.261407) (xy 40.670199 -463.297082) (xy 40.707416 -463.338619) (xy 40.738189 -463.385132)
			(xy 40.761861 -463.435629) (xy 40.777929 -463.489036) (xy 40.786049 -463.544212) (xy 40.786558 -463.572098)
			(xy 40.786049 -463.599984) (xy 40.777929 -463.65516) (xy 40.761861 -463.708567) (xy 40.738189 -463.759064)
			(xy 40.707416 -463.805577) (xy 40.670199 -463.847114) (xy 40.627331 -463.882789) (xy 40.579725 -463.911843)
			(xy 40.528396 -463.933655) (xy 40.474439 -463.947761) (xy 40.419002 -463.953861) (xy 40.363268 -463.951824)
			(xy 40.308425 -463.941694) (xy 40.255641 -463.923687) (xy 40.206041 -463.898186) (xy 40.160683 -463.865735)
			(xy 40.120534 -463.827026) (xy 40.086448 -463.782883) (xy 40.059152 -463.734248) (xy 40.039229 -463.682157)
			(xy 40.027103 -463.62772) (xy 40.023032 -463.572098) (xy 36.036403 -463.572098) (xy 36.071366 -463.593746)
			(xy 36.140713 -463.646115) (xy 36.204933 -463.704659) (xy 36.263477 -463.768879) (xy 36.315846 -463.838226)
			(xy 36.361593 -463.91211) (xy 36.400327 -463.989899) (xy 36.431719 -464.070931) (xy 36.4555 -464.154513)
			(xy 36.471468 -464.239933) (xy 36.479486 -464.326462) (xy 36.479988 -464.369912) (xy 36.479486 -464.413362)
			(xy 36.471468 -464.499891) (xy 36.4555 -464.585311) (xy 36.431719 -464.668893) (xy 36.400327 -464.749925)
			(xy 36.361593 -464.827714) (xy 36.315846 -464.901598) (xy 36.263477 -464.970945) (xy 36.204933 -465.035165)
			(xy 36.140713 -465.093709) (xy 36.071366 -465.146078) (xy 36.031891 -465.17052) (xy 40.21277 -465.17052)
			(xy 40.216841 -465.114898) (xy 40.228967 -465.060461) (xy 40.24889 -465.00837) (xy 40.276186 -464.959735)
			(xy 40.310272 -464.915592) (xy 40.350421 -464.876883) (xy 40.395779 -464.844432) (xy 40.445379 -464.818931)
			(xy 40.498163 -464.800924) (xy 40.553006 -464.790794) (xy 40.60874 -464.788757) (xy 40.664177 -464.794857)
			(xy 40.718134 -464.808963) (xy 40.769463 -464.830775) (xy 40.817069 -464.859829) (xy 40.859937 -464.895504)
			(xy 40.897154 -464.937041) (xy 40.927927 -464.983554) (xy 40.951599 -465.034051) (xy 40.967667 -465.087458)
			(xy 40.975787 -465.142634) (xy 40.976296 -465.17052) (xy 40.975787 -465.198406) (xy 40.967667 -465.253582)
			(xy 40.951599 -465.306989) (xy 40.927927 -465.357486) (xy 40.897154 -465.403999) (xy 40.859937 -465.445536)
			(xy 40.817069 -465.481211) (xy 40.769463 -465.510265) (xy 40.718134 -465.532077) (xy 40.664177 -465.546183)
			(xy 40.60874 -465.552283) (xy 40.553006 -465.550246) (xy 40.498163 -465.540116) (xy 40.445379 -465.522109)
			(xy 40.395779 -465.496608) (xy 40.350421 -465.464157) (xy 40.310272 -465.425448) (xy 40.276186 -465.381305)
			(xy 40.24889 -465.33267) (xy 40.228967 -465.280579) (xy 40.216841 -465.226142) (xy 40.21277 -465.17052)
			(xy 36.031891 -465.17052) (xy 35.997482 -465.191825) (xy 35.919693 -465.230559) (xy 35.838661 -465.261951)
			(xy 35.755079 -465.285732) (xy 35.669659 -465.3017) (xy 35.58313 -465.309718) (xy 35.49623 -465.309718)
			(xy 35.409701 -465.3017) (xy 35.324281 -465.285732) (xy 35.240699 -465.261951) (xy 35.159667 -465.230559)
			(xy 35.081878 -465.191825) (xy 35.007994 -465.146078) (xy 34.938647 -465.093709) (xy 34.874427 -465.035165)
			(xy 34.815883 -464.970945) (xy 34.763514 -464.901598) (xy 34.717767 -464.827714) (xy 34.679033 -464.749925)
			(xy 34.647641 -464.668893) (xy 34.62386 -464.585311) (xy 34.607892 -464.499891) (xy 34.599874 -464.413362)
			(xy 31.399486 -464.413362) (xy 31.391468 -464.499891) (xy 31.3755 -464.585311) (xy 31.351719 -464.668893)
			(xy 31.320327 -464.749925) (xy 31.281593 -464.827714) (xy 31.235846 -464.901598) (xy 31.183477 -464.970945)
			(xy 31.124933 -465.035165) (xy 31.060713 -465.093709) (xy 30.991366 -465.146078) (xy 30.917482 -465.191825)
			(xy 30.839693 -465.230559) (xy 30.758661 -465.261951) (xy 30.675079 -465.285732) (xy 30.589659 -465.3017)
			(xy 30.50313 -465.309718) (xy 30.41623 -465.309718) (xy 30.329701 -465.3017) (xy 30.244281 -465.285732)
			(xy 30.160699 -465.261951) (xy 30.079667 -465.230559) (xy 30.001878 -465.191825) (xy 29.927994 -465.146078)
			(xy 29.858647 -465.093709) (xy 29.794427 -465.035165) (xy 29.735883 -464.970945) (xy 29.683514 -464.901598)
			(xy 29.637767 -464.827714) (xy 29.599033 -464.749925) (xy 29.567641 -464.668893) (xy 29.54386 -464.585311)
			(xy 29.527892 -464.499891) (xy 29.519874 -464.413362) (xy 1.27 -464.413362) (xy 1.27 -466.953362)
			(xy 29.519874 -466.953362) (xy 29.519874 -466.866462) (xy 29.527892 -466.779933) (xy 29.54386 -466.694513)
			(xy 29.567641 -466.610931) (xy 29.599033 -466.529899) (xy 29.637767 -466.45211) (xy 29.683514 -466.378226)
			(xy 29.735883 -466.308879) (xy 29.794427 -466.244659) (xy 29.858647 -466.186115) (xy 29.927994 -466.133746)
			(xy 30.001878 -466.087999) (xy 30.079667 -466.049265) (xy 30.160699 -466.017873) (xy 30.244281 -465.994092)
			(xy 30.329701 -465.978124) (xy 30.41623 -465.970106) (xy 30.50313 -465.970106) (xy 30.589659 -465.978124)
			(xy 30.675079 -465.994092) (xy 30.758661 -466.017873) (xy 30.839693 -466.049265) (xy 30.917482 -466.087999)
			(xy 30.991366 -466.133746) (xy 31.060713 -466.186115) (xy 31.124933 -466.244659) (xy 31.183477 -466.308879)
			(xy 31.235846 -466.378226) (xy 31.281593 -466.45211) (xy 31.320327 -466.529899) (xy 31.351719 -466.610931)
			(xy 31.3755 -466.694513) (xy 31.391468 -466.779933) (xy 31.399486 -466.866462) (xy 31.399988 -466.909912)
			(xy 31.399486 -466.953362) (xy 34.599874 -466.953362) (xy 34.599874 -466.866462) (xy 34.607892 -466.779933)
			(xy 34.62386 -466.694513) (xy 34.647641 -466.610931) (xy 34.679033 -466.529899) (xy 34.717767 -466.45211)
			(xy 34.763514 -466.378226) (xy 34.815883 -466.308879) (xy 34.874427 -466.244659) (xy 34.938647 -466.186115)
			(xy 35.007994 -466.133746) (xy 35.081878 -466.087999) (xy 35.159667 -466.049265) (xy 35.240699 -466.017873)
			(xy 35.324281 -465.994092) (xy 35.409701 -465.978124) (xy 35.49623 -465.970106) (xy 35.58313 -465.970106)
			(xy 35.669659 -465.978124) (xy 35.755079 -465.994092) (xy 35.838661 -466.017873) (xy 35.919693 -466.049265)
			(xy 35.997482 -466.087999) (xy 36.071366 -466.133746) (xy 36.140713 -466.186115) (xy 36.204933 -466.244659)
			(xy 36.263477 -466.308879) (xy 36.315846 -466.378226) (xy 36.361593 -466.45211) (xy 36.400327 -466.529899)
			(xy 36.431719 -466.610931) (xy 36.4555 -466.694513) (xy 36.471468 -466.779933) (xy 36.479486 -466.866462)
			(xy 36.479988 -466.909912) (xy 36.479486 -466.953362) (xy 36.471468 -467.039891) (xy 36.4555 -467.125311)
			(xy 36.431719 -467.208893) (xy 36.400327 -467.289925) (xy 36.361593 -467.367714) (xy 36.315846 -467.441598)
			(xy 36.263477 -467.510945) (xy 36.204933 -467.575165) (xy 36.140713 -467.633709) (xy 36.071366 -467.686078)
			(xy 35.997482 -467.731825) (xy 35.919693 -467.770559) (xy 35.838661 -467.801951) (xy 35.755079 -467.825732)
			(xy 35.669659 -467.8417) (xy 35.58313 -467.849718) (xy 35.49623 -467.849718) (xy 35.409701 -467.8417)
			(xy 35.324281 -467.825732) (xy 35.240699 -467.801951) (xy 35.159667 -467.770559) (xy 35.081878 -467.731825)
			(xy 35.007994 -467.686078) (xy 34.938647 -467.633709) (xy 34.874427 -467.575165) (xy 34.815883 -467.510945)
			(xy 34.763514 -467.441598) (xy 34.717767 -467.367714) (xy 34.679033 -467.289925) (xy 34.647641 -467.208893)
			(xy 34.62386 -467.125311) (xy 34.607892 -467.039891) (xy 34.599874 -466.953362) (xy 31.399486 -466.953362)
			(xy 31.391468 -467.039891) (xy 31.3755 -467.125311) (xy 31.351719 -467.208893) (xy 31.320327 -467.289925)
			(xy 31.281593 -467.367714) (xy 31.235846 -467.441598) (xy 31.183477 -467.510945) (xy 31.124933 -467.575165)
			(xy 31.060713 -467.633709) (xy 30.991366 -467.686078) (xy 30.917482 -467.731825) (xy 30.839693 -467.770559)
			(xy 30.758661 -467.801951) (xy 30.675079 -467.825732) (xy 30.589659 -467.8417) (xy 30.50313 -467.849718)
			(xy 30.41623 -467.849718) (xy 30.329701 -467.8417) (xy 30.244281 -467.825732) (xy 30.160699 -467.801951)
			(xy 30.079667 -467.770559) (xy 30.001878 -467.731825) (xy 29.927994 -467.686078) (xy 29.858647 -467.633709)
			(xy 29.794427 -467.575165) (xy 29.735883 -467.510945) (xy 29.683514 -467.441598) (xy 29.637767 -467.367714)
			(xy 29.599033 -467.289925) (xy 29.567641 -467.208893) (xy 29.54386 -467.125311) (xy 29.527892 -467.039891)
			(xy 29.519874 -466.953362) (xy 1.27 -466.953362) (xy 1.27 -473.69984) (xy 11.345418 -473.69984) (xy 11.345925 -473.59666)
			(xy 11.354026 -473.390459) (xy 11.370217 -473.184735) (xy 11.394472 -472.979805) (xy 11.426754 -472.775985)
			(xy 11.467013 -472.57359) (xy 11.515187 -472.372931) (xy 11.571201 -472.174319) (xy 11.63497 -471.978059)
			(xy 11.706395 -471.784453) (xy 11.785365 -471.593801) (xy 11.87176 -471.406397) (xy 11.965446 -471.222528)
			(xy 12.066278 -471.04248) (xy 12.174101 -470.866529) (xy 12.288748 -470.694946) (xy 12.410044 -470.527998)
			(xy 12.5378 -470.365939) (xy 12.671821 -470.209022) (xy 12.811898 -470.057487) (xy 12.957817 -469.911568)
			(xy 13.109352 -469.771491) (xy 13.266269 -469.63747) (xy 13.428328 -469.509714) (xy 13.595276 -469.388418)
			(xy 13.766859 -469.273771) (xy 13.94281 -469.165948) (xy 14.122858 -469.065116) (xy 14.306727 -468.97143)
			(xy 14.494131 -468.885035) (xy 14.684783 -468.806065) (xy 14.878389 -468.73464) (xy 15.074649 -468.670871)
			(xy 15.273261 -468.614857) (xy 15.47392 -468.566683) (xy 15.676315 -468.526424) (xy 15.880135 -468.494142)
			(xy 16.085065 -468.469887) (xy 16.290789 -468.453696) (xy 16.49699 -468.445595) (xy 16.60017 -468.445088)
			(xy 16.70335 -468.445595) (xy 16.909551 -468.453696) (xy 17.115275 -468.469887) (xy 17.320205 -468.494142)
			(xy 17.524025 -468.526424) (xy 17.72642 -468.566683) (xy 17.927079 -468.614857) (xy 18.125691 -468.670871)
			(xy 18.321951 -468.73464) (xy 18.515557 -468.806065) (xy 18.706209 -468.885035) (xy 18.893613 -468.97143)
			(xy 19.077482 -469.065116) (xy 19.25753 -469.165948) (xy 19.433481 -469.273771) (xy 19.605064 -469.388418)
			(xy 19.749506 -469.493362) (xy 29.519874 -469.493362) (xy 29.519874 -469.406462) (xy 29.527892 -469.319933)
			(xy 29.54386 -469.234513) (xy 29.567641 -469.150931) (xy 29.599033 -469.069899) (xy 29.637767 -468.99211)
			(xy 29.683514 -468.918226) (xy 29.735883 -468.848879) (xy 29.794427 -468.784659) (xy 29.858647 -468.726115)
			(xy 29.927994 -468.673746) (xy 30.001878 -468.627999) (xy 30.079667 -468.589265) (xy 30.160699 -468.557873)
			(xy 30.244281 -468.534092) (xy 30.329701 -468.518124) (xy 30.41623 -468.510106) (xy 30.50313 -468.510106)
			(xy 30.589659 -468.518124) (xy 30.675079 -468.534092) (xy 30.758661 -468.557873) (xy 30.839693 -468.589265)
			(xy 30.917482 -468.627999) (xy 30.991366 -468.673746) (xy 31.060713 -468.726115) (xy 31.124933 -468.784659)
			(xy 31.183477 -468.848879) (xy 31.235846 -468.918226) (xy 31.281593 -468.99211) (xy 31.320327 -469.069899)
			(xy 31.351719 -469.150931) (xy 31.3755 -469.234513) (xy 31.391468 -469.319933) (xy 31.399486 -469.406462)
			(xy 31.399988 -469.449912) (xy 31.399486 -469.493362) (xy 34.599874 -469.493362) (xy 34.599874 -469.406462)
			(xy 34.607892 -469.319933) (xy 34.62386 -469.234513) (xy 34.647641 -469.150931) (xy 34.679033 -469.069899)
			(xy 34.717767 -468.99211) (xy 34.763514 -468.918226) (xy 34.815883 -468.848879) (xy 34.874427 -468.784659)
			(xy 34.938647 -468.726115) (xy 35.007994 -468.673746) (xy 35.081878 -468.627999) (xy 35.159667 -468.589265)
			(xy 35.240699 -468.557873) (xy 35.324281 -468.534092) (xy 35.409701 -468.518124) (xy 35.49623 -468.510106)
			(xy 35.58313 -468.510106) (xy 35.669659 -468.518124) (xy 35.755079 -468.534092) (xy 35.838661 -468.557873)
			(xy 35.919693 -468.589265) (xy 35.997482 -468.627999) (xy 36.071366 -468.673746) (xy 36.140713 -468.726115)
			(xy 36.204933 -468.784659) (xy 36.263477 -468.848879) (xy 36.315846 -468.918226) (xy 36.361593 -468.99211)
			(xy 36.400327 -469.069899) (xy 36.431719 -469.150931) (xy 36.4555 -469.234513) (xy 36.471468 -469.319933)
			(xy 36.479486 -469.406462) (xy 36.479988 -469.449912) (xy 36.479486 -469.493362) (xy 36.471468 -469.579891)
			(xy 36.4555 -469.665311) (xy 36.431719 -469.748893) (xy 36.400327 -469.829925) (xy 36.361593 -469.907714)
			(xy 36.315846 -469.981598) (xy 36.263477 -470.050945) (xy 36.204933 -470.115165) (xy 36.140713 -470.173709)
			(xy 36.071366 -470.226078) (xy 35.997482 -470.271825) (xy 35.919693 -470.310559) (xy 35.838661 -470.341951)
			(xy 35.755079 -470.365732) (xy 35.669659 -470.3817) (xy 35.58313 -470.389718) (xy 35.49623 -470.389718)
			(xy 35.409701 -470.3817) (xy 35.324281 -470.365732) (xy 35.240699 -470.341951) (xy 35.159667 -470.310559)
			(xy 35.081878 -470.271825) (xy 35.007994 -470.226078) (xy 34.938647 -470.173709) (xy 34.874427 -470.115165)
			(xy 34.815883 -470.050945) (xy 34.763514 -469.981598) (xy 34.717767 -469.907714) (xy 34.679033 -469.829925)
			(xy 34.647641 -469.748893) (xy 34.62386 -469.665311) (xy 34.607892 -469.579891) (xy 34.599874 -469.493362)
			(xy 31.399486 -469.493362) (xy 31.391468 -469.579891) (xy 31.3755 -469.665311) (xy 31.351719 -469.748893)
			(xy 31.320327 -469.829925) (xy 31.281593 -469.907714) (xy 31.235846 -469.981598) (xy 31.183477 -470.050945)
			(xy 31.124933 -470.115165) (xy 31.060713 -470.173709) (xy 30.991366 -470.226078) (xy 30.917482 -470.271825)
			(xy 30.839693 -470.310559) (xy 30.758661 -470.341951) (xy 30.675079 -470.365732) (xy 30.589659 -470.3817)
			(xy 30.50313 -470.389718) (xy 30.41623 -470.389718) (xy 30.329701 -470.3817) (xy 30.244281 -470.365732)
			(xy 30.160699 -470.341951) (xy 30.079667 -470.310559) (xy 30.001878 -470.271825) (xy 29.927994 -470.226078)
			(xy 29.858647 -470.173709) (xy 29.794427 -470.115165) (xy 29.735883 -470.050945) (xy 29.683514 -469.981598)
			(xy 29.637767 -469.907714) (xy 29.599033 -469.829925) (xy 29.567641 -469.748893) (xy 29.54386 -469.665311)
			(xy 29.527892 -469.579891) (xy 29.519874 -469.493362) (xy 19.749506 -469.493362) (xy 19.772012 -469.509714)
			(xy 19.934071 -469.63747) (xy 20.090988 -469.771491) (xy 20.242523 -469.911568) (xy 20.388442 -470.057487)
			(xy 20.528519 -470.209022) (xy 20.66254 -470.365939) (xy 20.790296 -470.527998) (xy 20.911592 -470.694946)
			(xy 21.026239 -470.866529) (xy 21.134062 -471.04248) (xy 21.234894 -471.222528) (xy 21.32858 -471.406397)
			(xy 21.414975 -471.593801) (xy 21.493945 -471.784453) (xy 21.56537 -471.978059) (xy 21.583339 -472.033362)
			(xy 29.519874 -472.033362) (xy 29.519874 -471.946462) (xy 29.527892 -471.859933) (xy 29.54386 -471.774513)
			(xy 29.567641 -471.690931) (xy 29.599033 -471.609899) (xy 29.637767 -471.53211) (xy 29.683514 -471.458226)
			(xy 29.735883 -471.388879) (xy 29.794427 -471.324659) (xy 29.858647 -471.266115) (xy 29.927994 -471.213746)
			(xy 30.001878 -471.167999) (xy 30.079667 -471.129265) (xy 30.160699 -471.097873) (xy 30.244281 -471.074092)
			(xy 30.329701 -471.058124) (xy 30.41623 -471.050106) (xy 30.50313 -471.050106) (xy 30.589659 -471.058124)
			(xy 30.675079 -471.074092) (xy 30.758661 -471.097873) (xy 30.839693 -471.129265) (xy 30.917482 -471.167999)
			(xy 30.991366 -471.213746) (xy 31.060713 -471.266115) (xy 31.124933 -471.324659) (xy 31.183477 -471.388879)
			(xy 31.235846 -471.458226) (xy 31.281593 -471.53211) (xy 31.320327 -471.609899) (xy 31.351719 -471.690931)
			(xy 31.3755 -471.774513) (xy 31.391468 -471.859933) (xy 31.399486 -471.946462) (xy 31.399988 -471.989912)
			(xy 31.399486 -472.033362) (xy 34.599874 -472.033362) (xy 34.599874 -471.946462) (xy 34.607892 -471.859933)
			(xy 34.62386 -471.774513) (xy 34.647641 -471.690931) (xy 34.679033 -471.609899) (xy 34.717767 -471.53211)
			(xy 34.763514 -471.458226) (xy 34.815883 -471.388879) (xy 34.874427 -471.324659) (xy 34.938647 -471.266115)
			(xy 35.007994 -471.213746) (xy 35.081878 -471.167999) (xy 35.159667 -471.129265) (xy 35.240699 -471.097873)
			(xy 35.324281 -471.074092) (xy 35.409701 -471.058124) (xy 35.49623 -471.050106) (xy 35.58313 -471.050106)
			(xy 35.669659 -471.058124) (xy 35.755079 -471.074092) (xy 35.838661 -471.097873) (xy 35.919693 -471.129265)
			(xy 35.997482 -471.167999) (xy 36.071366 -471.213746) (xy 36.140713 -471.266115) (xy 36.204933 -471.324659)
			(xy 36.263477 -471.388879) (xy 36.315846 -471.458226) (xy 36.361593 -471.53211) (xy 36.400327 -471.609899)
			(xy 36.431719 -471.690931) (xy 36.4555 -471.774513) (xy 36.471468 -471.859933) (xy 36.479486 -471.946462)
			(xy 36.479988 -471.989912) (xy 36.479486 -472.033362) (xy 36.473156 -472.101672) (xy 70.798942 -472.101672)
			(xy 70.803013 -472.04605) (xy 70.815139 -471.991613) (xy 70.835062 -471.939522) (xy 70.862358 -471.890887)
			(xy 70.896444 -471.846744) (xy 70.936593 -471.808035) (xy 70.981951 -471.775584) (xy 71.031551 -471.750083)
			(xy 71.084335 -471.732076) (xy 71.139178 -471.721946) (xy 71.194912 -471.719909) (xy 71.250349 -471.726009)
			(xy 71.304306 -471.740115) (xy 71.355635 -471.761927) (xy 71.403241 -471.790981) (xy 71.446109 -471.826656)
			(xy 71.483326 -471.868193) (xy 71.514099 -471.914706) (xy 71.537771 -471.965203) (xy 71.553839 -472.01861)
			(xy 71.561959 -472.073786) (xy 71.562468 -472.101672) (xy 74.193906 -472.101672) (xy 74.197977 -472.04605)
			(xy 74.210103 -471.991613) (xy 74.230026 -471.939522) (xy 74.257322 -471.890887) (xy 74.291408 -471.846744)
			(xy 74.331557 -471.808035) (xy 74.376915 -471.775584) (xy 74.426515 -471.750083) (xy 74.479299 -471.732076)
			(xy 74.534142 -471.721946) (xy 74.589876 -471.719909) (xy 74.645313 -471.726009) (xy 74.69927 -471.740115)
			(xy 74.750599 -471.761927) (xy 74.798205 -471.790981) (xy 74.841073 -471.826656) (xy 74.87829 -471.868193)
			(xy 74.909063 -471.914706) (xy 74.932735 -471.965203) (xy 74.948803 -472.01861) (xy 74.956923 -472.073786)
			(xy 74.957432 -472.101672) (xy 74.956923 -472.129558) (xy 74.948803 -472.184734) (xy 74.932735 -472.238141)
			(xy 74.909063 -472.288638) (xy 74.87829 -472.335151) (xy 74.841073 -472.376688) (xy 74.798205 -472.412363)
			(xy 74.750599 -472.441417) (xy 74.69927 -472.463229) (xy 74.645313 -472.477335) (xy 74.589876 -472.483435)
			(xy 74.534142 -472.481398) (xy 74.479299 -472.471268) (xy 74.426515 -472.453261) (xy 74.376915 -472.42776)
			(xy 74.331557 -472.395309) (xy 74.291408 -472.3566) (xy 74.257322 -472.312457) (xy 74.230026 -472.263822)
			(xy 74.210103 -472.211731) (xy 74.197977 -472.157294) (xy 74.193906 -472.101672) (xy 71.562468 -472.101672)
			(xy 71.561959 -472.129558) (xy 71.553839 -472.184734) (xy 71.537771 -472.238141) (xy 71.514099 -472.288638)
			(xy 71.483326 -472.335151) (xy 71.446109 -472.376688) (xy 71.403241 -472.412363) (xy 71.355635 -472.441417)
			(xy 71.304306 -472.463229) (xy 71.250349 -472.477335) (xy 71.194912 -472.483435) (xy 71.139178 -472.481398)
			(xy 71.084335 -472.471268) (xy 71.031551 -472.453261) (xy 70.981951 -472.42776) (xy 70.936593 -472.395309)
			(xy 70.896444 -472.3566) (xy 70.862358 -472.312457) (xy 70.835062 -472.263822) (xy 70.815139 -472.211731)
			(xy 70.803013 -472.157294) (xy 70.798942 -472.101672) (xy 36.473156 -472.101672) (xy 36.471468 -472.119891)
			(xy 36.4555 -472.205311) (xy 36.431719 -472.288893) (xy 36.400327 -472.369925) (xy 36.361593 -472.447714)
			(xy 36.315846 -472.521598) (xy 36.263477 -472.590945) (xy 36.204933 -472.655165) (xy 36.140713 -472.713709)
			(xy 36.071366 -472.766078) (xy 35.997482 -472.811825) (xy 35.919693 -472.850559) (xy 35.838661 -472.881951)
			(xy 35.755079 -472.905732) (xy 35.669659 -472.9217) (xy 35.58313 -472.929718) (xy 35.49623 -472.929718)
			(xy 35.409701 -472.9217) (xy 35.324281 -472.905732) (xy 35.240699 -472.881951) (xy 35.159667 -472.850559)
			(xy 35.081878 -472.811825) (xy 35.007994 -472.766078) (xy 34.938647 -472.713709) (xy 34.874427 -472.655165)
			(xy 34.815883 -472.590945) (xy 34.763514 -472.521598) (xy 34.717767 -472.447714) (xy 34.679033 -472.369925)
			(xy 34.647641 -472.288893) (xy 34.62386 -472.205311) (xy 34.607892 -472.119891) (xy 34.599874 -472.033362)
			(xy 31.399486 -472.033362) (xy 31.391468 -472.119891) (xy 31.3755 -472.205311) (xy 31.351719 -472.288893)
			(xy 31.320327 -472.369925) (xy 31.281593 -472.447714) (xy 31.235846 -472.521598) (xy 31.183477 -472.590945)
			(xy 31.124933 -472.655165) (xy 31.060713 -472.713709) (xy 30.991366 -472.766078) (xy 30.917482 -472.811825)
			(xy 30.839693 -472.850559) (xy 30.758661 -472.881951) (xy 30.675079 -472.905732) (xy 30.589659 -472.9217)
			(xy 30.50313 -472.929718) (xy 30.41623 -472.929718) (xy 30.329701 -472.9217) (xy 30.244281 -472.905732)
			(xy 30.160699 -472.881951) (xy 30.079667 -472.850559) (xy 30.001878 -472.811825) (xy 29.927994 -472.766078)
			(xy 29.858647 -472.713709) (xy 29.794427 -472.655165) (xy 29.735883 -472.590945) (xy 29.683514 -472.521598)
			(xy 29.637767 -472.447714) (xy 29.599033 -472.369925) (xy 29.567641 -472.288893) (xy 29.54386 -472.205311)
			(xy 29.527892 -472.119891) (xy 29.519874 -472.033362) (xy 21.583339 -472.033362) (xy 21.629139 -472.174319)
			(xy 21.685153 -472.372931) (xy 21.733327 -472.57359) (xy 21.773586 -472.775985) (xy 21.805868 -472.979805)
			(xy 21.830123 -473.184735) (xy 21.846314 -473.390459) (xy 21.854415 -473.59666) (xy 21.854922 -473.69984)
			(xy 21.854428 -473.801746) (xy 21.846525 -474.005405) (xy 21.830731 -474.208605) (xy 21.80707 -474.411039)
			(xy 21.781683 -474.573362) (xy 29.519874 -474.573362) (xy 29.519874 -474.486462) (xy 29.527892 -474.399933)
			(xy 29.54386 -474.314513) (xy 29.567641 -474.230931) (xy 29.599033 -474.149899) (xy 29.637767 -474.07211)
			(xy 29.683514 -473.998226) (xy 29.735883 -473.928879) (xy 29.794427 -473.864659) (xy 29.858647 -473.806115)
			(xy 29.927994 -473.753746) (xy 30.001878 -473.707999) (xy 30.079667 -473.669265) (xy 30.160699 -473.637873)
			(xy 30.244281 -473.614092) (xy 30.329701 -473.598124) (xy 30.41623 -473.590106) (xy 30.50313 -473.590106)
			(xy 30.589659 -473.598124) (xy 30.675079 -473.614092) (xy 30.758661 -473.637873) (xy 30.839693 -473.669265)
			(xy 30.917482 -473.707999) (xy 30.991366 -473.753746) (xy 31.060713 -473.806115) (xy 31.124933 -473.864659)
			(xy 31.183477 -473.928879) (xy 31.235846 -473.998226) (xy 31.281593 -474.07211) (xy 31.320327 -474.149899)
			(xy 31.351719 -474.230931) (xy 31.3755 -474.314513) (xy 31.391468 -474.399933) (xy 31.399486 -474.486462)
			(xy 31.399988 -474.529912) (xy 31.399486 -474.573362) (xy 34.599874 -474.573362) (xy 34.599874 -474.486462)
			(xy 34.607892 -474.399933) (xy 34.62386 -474.314513) (xy 34.647641 -474.230931) (xy 34.679033 -474.149899)
			(xy 34.717767 -474.07211) (xy 34.763514 -473.998226) (xy 34.815883 -473.928879) (xy 34.874427 -473.864659)
			(xy 34.938647 -473.806115) (xy 35.007994 -473.753746) (xy 35.081878 -473.707999) (xy 35.159667 -473.669265)
			(xy 35.240699 -473.637873) (xy 35.324281 -473.614092) (xy 35.409701 -473.598124) (xy 35.49623 -473.590106)
			(xy 35.58313 -473.590106) (xy 35.669659 -473.598124) (xy 35.755079 -473.614092) (xy 35.838661 -473.637873)
			(xy 35.919693 -473.669265) (xy 35.997482 -473.707999) (xy 36.071366 -473.753746) (xy 36.140713 -473.806115)
			(xy 36.204933 -473.864659) (xy 36.263477 -473.928879) (xy 36.315846 -473.998226) (xy 36.317206 -474.000423)
			(xy 37.996106 -474.000423) (xy 37.996106 -473.929101) (xy 38.004092 -473.858227) (xy 38.019962 -473.788692)
			(xy 38.043519 -473.721372) (xy 38.074464 -473.657113) (xy 38.11241 -473.596722) (xy 38.156879 -473.54096)
			(xy 38.207312 -473.490527) (xy 38.263074 -473.446058) (xy 38.323465 -473.408112) (xy 38.387724 -473.377167)
			(xy 38.455044 -473.35361) (xy 38.524579 -473.33774) (xy 38.595453 -473.329754) (xy 38.666775 -473.329754)
			(xy 38.737649 -473.33774) (xy 38.807184 -473.35361) (xy 38.874504 -473.377167) (xy 38.938763 -473.408112)
			(xy 38.999154 -473.446058) (xy 39.054916 -473.490527) (xy 39.105349 -473.54096) (xy 39.149818 -473.596722)
			(xy 39.187764 -473.657113) (xy 39.218709 -473.721372) (xy 39.242266 -473.788692) (xy 39.258136 -473.858227)
			(xy 39.266122 -473.929101) (xy 39.266622 -473.964762) (xy 39.266122 -474.000423) (xy 39.882818 -474.000423)
			(xy 39.882818 -473.929101) (xy 39.890804 -473.858227) (xy 39.906674 -473.788692) (xy 39.930231 -473.721372)
			(xy 39.961176 -473.657113) (xy 39.999122 -473.596722) (xy 40.043591 -473.54096) (xy 40.094024 -473.490527)
			(xy 40.149786 -473.446058) (xy 40.210177 -473.408112) (xy 40.274436 -473.377167) (xy 40.341756 -473.35361)
			(xy 40.411291 -473.33774) (xy 40.482165 -473.329754) (xy 40.553487 -473.329754) (xy 40.624361 -473.33774)
			(xy 40.693896 -473.35361) (xy 40.761216 -473.377167) (xy 40.825475 -473.408112) (xy 40.885866 -473.446058)
			(xy 40.941628 -473.490527) (xy 40.992061 -473.54096) (xy 41.03653 -473.596722) (xy 41.038282 -473.59951)
			(xy 70.731886 -473.59951) (xy 70.735957 -473.543888) (xy 70.748083 -473.489451) (xy 70.768006 -473.43736)
			(xy 70.795302 -473.388725) (xy 70.829388 -473.344582) (xy 70.869537 -473.305873) (xy 70.914895 -473.273422)
			(xy 70.964495 -473.247921) (xy 71.017279 -473.229914) (xy 71.072122 -473.219784) (xy 71.127856 -473.217747)
			(xy 71.183293 -473.223847) (xy 71.23725 -473.237953) (xy 71.288579 -473.259765) (xy 71.336185 -473.288819)
			(xy 71.379053 -473.324494) (xy 71.41627 -473.366031) (xy 71.447043 -473.412544) (xy 71.470715 -473.463041)
			(xy 71.486783 -473.516448) (xy 71.494903 -473.571624) (xy 71.495412 -473.59951) (xy 71.494903 -473.627396)
			(xy 71.486783 -473.682572) (xy 71.470715 -473.735979) (xy 71.447043 -473.786476) (xy 71.41627 -473.832989)
			(xy 71.379053 -473.874526) (xy 71.336185 -473.910201) (xy 71.288579 -473.939255) (xy 71.23725 -473.961067)
			(xy 71.183293 -473.975173) (xy 71.127856 -473.981273) (xy 71.072122 -473.979236) (xy 71.017279 -473.969106)
			(xy 70.964495 -473.951099) (xy 70.914895 -473.925598) (xy 70.869537 -473.893147) (xy 70.829388 -473.854438)
			(xy 70.795302 -473.810295) (xy 70.768006 -473.76166) (xy 70.748083 -473.709569) (xy 70.735957 -473.655132)
			(xy 70.731886 -473.59951) (xy 41.038282 -473.59951) (xy 41.074476 -473.657113) (xy 41.105421 -473.721372)
			(xy 41.128978 -473.788692) (xy 41.144848 -473.858227) (xy 41.152834 -473.929101) (xy 41.153334 -473.964762)
			(xy 41.152834 -474.000423) (xy 41.144848 -474.071297) (xy 41.128978 -474.140832) (xy 41.105421 -474.208152)
			(xy 41.074476 -474.272411) (xy 41.03653 -474.332802) (xy 40.992061 -474.388564) (xy 40.941628 -474.438997)
			(xy 40.885866 -474.483466) (xy 40.825475 -474.521412) (xy 40.761216 -474.552357) (xy 40.693896 -474.575914)
			(xy 40.624361 -474.591784) (xy 40.553487 -474.59977) (xy 40.482165 -474.59977) (xy 40.411291 -474.591784)
			(xy 40.341756 -474.575914) (xy 40.274436 -474.552357) (xy 40.210177 -474.521412) (xy 40.149786 -474.483466)
			(xy 40.094024 -474.438997) (xy 40.043591 -474.388564) (xy 39.999122 -474.332802) (xy 39.961176 -474.272411)
			(xy 39.930231 -474.208152) (xy 39.906674 -474.140832) (xy 39.890804 -474.071297) (xy 39.882818 -474.000423)
			(xy 39.266122 -474.000423) (xy 39.258136 -474.071297) (xy 39.242266 -474.140832) (xy 39.218709 -474.208152)
			(xy 39.187764 -474.272411) (xy 39.149818 -474.332802) (xy 39.105349 -474.388564) (xy 39.054916 -474.438997)
			(xy 38.999154 -474.483466) (xy 38.938763 -474.521412) (xy 38.874504 -474.552357) (xy 38.807184 -474.575914)
			(xy 38.737649 -474.591784) (xy 38.666775 -474.59977) (xy 38.595453 -474.59977) (xy 38.524579 -474.591784)
			(xy 38.455044 -474.575914) (xy 38.387724 -474.552357) (xy 38.323465 -474.521412) (xy 38.263074 -474.483466)
			(xy 38.207312 -474.438997) (xy 38.156879 -474.388564) (xy 38.11241 -474.332802) (xy 38.074464 -474.272411)
			(xy 38.043519 -474.208152) (xy 38.019962 -474.140832) (xy 38.004092 -474.071297) (xy 37.996106 -474.000423)
			(xy 36.317206 -474.000423) (xy 36.361593 -474.07211) (xy 36.400327 -474.149899) (xy 36.431719 -474.230931)
			(xy 36.4555 -474.314513) (xy 36.471468 -474.399933) (xy 36.479486 -474.486462) (xy 36.479988 -474.529912)
			(xy 36.479486 -474.573362) (xy 36.471468 -474.659891) (xy 36.4555 -474.745311) (xy 36.431719 -474.828893)
			(xy 36.400327 -474.909925) (xy 36.361593 -474.987714) (xy 36.315846 -475.061598) (xy 36.263477 -475.130945)
			(xy 36.204933 -475.195165) (xy 36.140713 -475.253709) (xy 36.071366 -475.306078) (xy 35.997482 -475.351825)
			(xy 35.919693 -475.390559) (xy 35.838661 -475.421951) (xy 35.755079 -475.445732) (xy 35.669659 -475.4617)
			(xy 35.58313 -475.469718) (xy 35.49623 -475.469718) (xy 35.409701 -475.4617) (xy 35.324281 -475.445732)
			(xy 35.240699 -475.421951) (xy 35.159667 -475.390559) (xy 35.081878 -475.351825) (xy 35.007994 -475.306078)
			(xy 34.938647 -475.253709) (xy 34.874427 -475.195165) (xy 34.815883 -475.130945) (xy 34.763514 -475.061598)
			(xy 34.717767 -474.987714) (xy 34.679033 -474.909925) (xy 34.647641 -474.828893) (xy 34.62386 -474.745311)
			(xy 34.607892 -474.659891) (xy 34.599874 -474.573362) (xy 31.399486 -474.573362) (xy 31.391468 -474.659891)
			(xy 31.3755 -474.745311) (xy 31.351719 -474.828893) (xy 31.320327 -474.909925) (xy 31.281593 -474.987714)
			(xy 31.235846 -475.061598) (xy 31.183477 -475.130945) (xy 31.124933 -475.195165) (xy 31.060713 -475.253709)
			(xy 30.991366 -475.306078) (xy 30.917482 -475.351825) (xy 30.839693 -475.390559) (xy 30.758661 -475.421951)
			(xy 30.675079 -475.445732) (xy 30.589659 -475.4617) (xy 30.50313 -475.469718) (xy 30.41623 -475.469718)
			(xy 30.329701 -475.4617) (xy 30.244281 -475.445732) (xy 30.160699 -475.421951) (xy 30.079667 -475.390559)
			(xy 30.001878 -475.351825) (xy 29.927994 -475.306078) (xy 29.858647 -475.253709) (xy 29.794427 -475.195165)
			(xy 29.735883 -475.130945) (xy 29.683514 -475.061598) (xy 29.637767 -474.987714) (xy 29.599033 -474.909925)
			(xy 29.567641 -474.828893) (xy 29.54386 -474.745311) (xy 29.527892 -474.659891) (xy 29.519874 -474.573362)
			(xy 21.781683 -474.573362) (xy 21.775577 -474.612404) (xy 21.7363 -474.812396) (xy 21.689297 -475.010715)
			(xy 21.634641 -475.207062) (xy 21.572411 -475.401142) (xy 21.502703 -475.592663) (xy 21.425622 -475.781337)
			(xy 21.401661 -475.834049) (xy 37.996106 -475.834049) (xy 37.996106 -475.762727) (xy 38.004092 -475.691853)
			(xy 38.019962 -475.622318) (xy 38.043519 -475.554998) (xy 38.074464 -475.490739) (xy 38.11241 -475.430348)
			(xy 38.156879 -475.374586) (xy 38.207312 -475.324153) (xy 38.263074 -475.279684) (xy 38.323465 -475.241738)
			(xy 38.387724 -475.210793) (xy 38.455044 -475.187236) (xy 38.524579 -475.171366) (xy 38.595453 -475.16338)
			(xy 38.666775 -475.16338) (xy 38.737649 -475.171366) (xy 38.807184 -475.187236) (xy 38.874504 -475.210793)
			(xy 38.938763 -475.241738) (xy 38.999154 -475.279684) (xy 39.054916 -475.324153) (xy 39.105349 -475.374586)
			(xy 39.149818 -475.430348) (xy 39.187764 -475.490739) (xy 39.218709 -475.554998) (xy 39.242266 -475.622318)
			(xy 39.258136 -475.691853) (xy 39.266122 -475.762727) (xy 39.266622 -475.798388) (xy 39.266122 -475.834049)
			(xy 39.882818 -475.834049) (xy 39.882818 -475.762727) (xy 39.890804 -475.691853) (xy 39.906674 -475.622318)
			(xy 39.930231 -475.554998) (xy 39.961176 -475.490739) (xy 39.999122 -475.430348) (xy 40.043591 -475.374586)
			(xy 40.094024 -475.324153) (xy 40.149786 -475.279684) (xy 40.210177 -475.241738) (xy 40.274436 -475.210793)
			(xy 40.341756 -475.187236) (xy 40.411291 -475.171366) (xy 40.482165 -475.16338) (xy 40.553487 -475.16338)
			(xy 40.624361 -475.171366) (xy 40.693896 -475.187236) (xy 40.761216 -475.210793) (xy 40.825475 -475.241738)
			(xy 40.885866 -475.279684) (xy 40.941628 -475.324153) (xy 40.992061 -475.374586) (xy 41.03653 -475.430348)
			(xy 41.074476 -475.490739) (xy 41.105421 -475.554998) (xy 41.128978 -475.622318) (xy 41.144848 -475.691853)
			(xy 41.152834 -475.762727) (xy 41.153334 -475.798388) (xy 41.152834 -475.834049) (xy 42.12386 -475.834049)
			(xy 42.12386 -475.762727) (xy 42.131846 -475.691853) (xy 42.147716 -475.622318) (xy 42.171273 -475.554998)
			(xy 42.202218 -475.490739) (xy 42.240164 -475.430348) (xy 42.284633 -475.374586) (xy 42.335066 -475.324153)
			(xy 42.390828 -475.279684) (xy 42.451219 -475.241738) (xy 42.515478 -475.210793) (xy 42.582798 -475.187236)
			(xy 42.652333 -475.171366) (xy 42.723207 -475.16338) (xy 42.794529 -475.16338) (xy 42.865403 -475.171366)
			(xy 42.934938 -475.187236) (xy 43.002258 -475.210793) (xy 43.066517 -475.241738) (xy 43.126908 -475.279684)
			(xy 43.18267 -475.324153) (xy 43.233103 -475.374586) (xy 43.277572 -475.430348) (xy 43.315518 -475.490739)
			(xy 43.346463 -475.554998) (xy 43.37002 -475.622318) (xy 43.38589 -475.691853) (xy 43.393876 -475.762727)
			(xy 43.394376 -475.798388) (xy 43.393876 -475.834049) (xy 44.027844 -475.834049) (xy 44.027844 -475.762727)
			(xy 44.03583 -475.691853) (xy 44.0517 -475.622318) (xy 44.075257 -475.554998) (xy 44.106202 -475.490739)
			(xy 44.144148 -475.430348) (xy 44.188617 -475.374586) (xy 44.23905 -475.324153) (xy 44.294812 -475.279684)
			(xy 44.355203 -475.241738) (xy 44.419462 -475.210793) (xy 44.486782 -475.187236) (xy 44.556317 -475.171366)
			(xy 44.627191 -475.16338) (xy 44.698513 -475.16338) (xy 44.769387 -475.171366) (xy 44.838922 -475.187236)
			(xy 44.906242 -475.210793) (xy 44.970501 -475.241738) (xy 45.030892 -475.279684) (xy 45.086654 -475.324153)
			(xy 45.137087 -475.374586) (xy 45.181556 -475.430348) (xy 45.219502 -475.490739) (xy 45.250447 -475.554998)
			(xy 45.274004 -475.622318) (xy 45.289874 -475.691853) (xy 45.29786 -475.762727) (xy 45.29836 -475.798388)
			(xy 45.29786 -475.834049) (xy 45.289874 -475.904923) (xy 45.274004 -475.974458) (xy 45.250447 -476.041778)
			(xy 45.219502 -476.106037) (xy 45.181556 -476.166428) (xy 45.137087 -476.22219) (xy 45.086654 -476.272623)
			(xy 45.030892 -476.317092) (xy 44.970501 -476.355038) (xy 44.906242 -476.385983) (xy 44.838922 -476.40954)
			(xy 44.769387 -476.42541) (xy 44.698513 -476.433396) (xy 44.627191 -476.433396) (xy 44.556317 -476.42541)
			(xy 44.486782 -476.40954) (xy 44.419462 -476.385983) (xy 44.355203 -476.355038) (xy 44.294812 -476.317092)
			(xy 44.23905 -476.272623) (xy 44.188617 -476.22219) (xy 44.144148 -476.166428) (xy 44.106202 -476.106037)
			(xy 44.075257 -476.041778) (xy 44.0517 -475.974458) (xy 44.03583 -475.904923) (xy 44.027844 -475.834049)
			(xy 43.393876 -475.834049) (xy 43.38589 -475.904923) (xy 43.37002 -475.974458) (xy 43.346463 -476.041778)
			(xy 43.315518 -476.106037) (xy 43.277572 -476.166428) (xy 43.233103 -476.22219) (xy 43.18267 -476.272623)
			(xy 43.126908 -476.317092) (xy 43.066517 -476.355038) (xy 43.002258 -476.385983) (xy 42.934938 -476.40954)
			(xy 42.865403 -476.42541) (xy 42.794529 -476.433396) (xy 42.723207 -476.433396) (xy 42.652333 -476.42541)
			(xy 42.582798 -476.40954) (xy 42.515478 -476.385983) (xy 42.451219 -476.355038) (xy 42.390828 -476.317092)
			(xy 42.335066 -476.272623) (xy 42.284633 -476.22219) (xy 42.240164 -476.166428) (xy 42.202218 -476.106037)
			(xy 42.171273 -476.041778) (xy 42.147716 -475.974458) (xy 42.131846 -475.904923) (xy 42.12386 -475.834049)
			(xy 41.152834 -475.834049) (xy 41.144848 -475.904923) (xy 41.128978 -475.974458) (xy 41.105421 -476.041778)
			(xy 41.074476 -476.106037) (xy 41.03653 -476.166428) (xy 40.992061 -476.22219) (xy 40.941628 -476.272623)
			(xy 40.885866 -476.317092) (xy 40.825475 -476.355038) (xy 40.761216 -476.385983) (xy 40.693896 -476.40954)
			(xy 40.624361 -476.42541) (xy 40.553487 -476.433396) (xy 40.482165 -476.433396) (xy 40.411291 -476.42541)
			(xy 40.341756 -476.40954) (xy 40.274436 -476.385983) (xy 40.210177 -476.355038) (xy 40.149786 -476.317092)
			(xy 40.094024 -476.272623) (xy 40.043591 -476.22219) (xy 39.999122 -476.166428) (xy 39.961176 -476.106037)
			(xy 39.930231 -476.041778) (xy 39.906674 -475.974458) (xy 39.890804 -475.904923) (xy 39.882818 -475.834049)
			(xy 39.266122 -475.834049) (xy 39.258136 -475.904923) (xy 39.242266 -475.974458) (xy 39.218709 -476.041778)
			(xy 39.187764 -476.106037) (xy 39.149818 -476.166428) (xy 39.105349 -476.22219) (xy 39.054916 -476.272623)
			(xy 38.999154 -476.317092) (xy 38.938763 -476.355038) (xy 38.874504 -476.385983) (xy 38.807184 -476.40954)
			(xy 38.737649 -476.42541) (xy 38.666775 -476.433396) (xy 38.595453 -476.433396) (xy 38.524579 -476.42541)
			(xy 38.455044 -476.40954) (xy 38.387724 -476.385983) (xy 38.323465 -476.355038) (xy 38.263074 -476.317092)
			(xy 38.207312 -476.272623) (xy 38.156879 -476.22219) (xy 38.11241 -476.166428) (xy 38.074464 -476.106037)
			(xy 38.043519 -476.041778) (xy 38.019962 -475.974458) (xy 38.004092 -475.904923) (xy 37.996106 -475.834049)
			(xy 21.401661 -475.834049) (xy 21.341282 -475.96688) (xy 21.249811 -476.149013) (xy 21.151347 -476.327463)
			(xy 21.046037 -476.50196) (xy 20.93404 -476.672243) (xy 20.815525 -476.838055) (xy 20.690669 -476.999147)
			(xy 20.594832 -477.113362) (xy 29.519874 -477.113362) (xy 29.519874 -477.026462) (xy 29.527892 -476.939933)
			(xy 29.54386 -476.854513) (xy 29.567641 -476.770931) (xy 29.599033 -476.689899) (xy 29.637767 -476.61211)
			(xy 29.683514 -476.538226) (xy 29.735883 -476.468879) (xy 29.794427 -476.404659) (xy 29.858647 -476.346115)
			(xy 29.927994 -476.293746) (xy 30.001878 -476.247999) (xy 30.079667 -476.209265) (xy 30.160699 -476.177873)
			(xy 30.244281 -476.154092) (xy 30.329701 -476.138124) (xy 30.41623 -476.130106) (xy 30.50313 -476.130106)
			(xy 30.589659 -476.138124) (xy 30.675079 -476.154092) (xy 30.758661 -476.177873) (xy 30.839693 -476.209265)
			(xy 30.917482 -476.247999) (xy 30.991366 -476.293746) (xy 31.060713 -476.346115) (xy 31.124933 -476.404659)
			(xy 31.183477 -476.468879) (xy 31.235846 -476.538226) (xy 31.281593 -476.61211) (xy 31.320327 -476.689899)
			(xy 31.351719 -476.770931) (xy 31.3755 -476.854513) (xy 31.391468 -476.939933) (xy 31.399486 -477.026462)
			(xy 31.399988 -477.069912) (xy 31.399486 -477.113362) (xy 34.599874 -477.113362) (xy 34.599874 -477.026462)
			(xy 34.607892 -476.939933) (xy 34.62386 -476.854513) (xy 34.647641 -476.770931) (xy 34.679033 -476.689899)
			(xy 34.717767 -476.61211) (xy 34.763514 -476.538226) (xy 34.815883 -476.468879) (xy 34.874427 -476.404659)
			(xy 34.938647 -476.346115) (xy 35.007994 -476.293746) (xy 35.081878 -476.247999) (xy 35.159667 -476.209265)
			(xy 35.240699 -476.177873) (xy 35.324281 -476.154092) (xy 35.409701 -476.138124) (xy 35.49623 -476.130106)
			(xy 35.58313 -476.130106) (xy 35.669659 -476.138124) (xy 35.755079 -476.154092) (xy 35.838661 -476.177873)
			(xy 35.919693 -476.209265) (xy 35.997482 -476.247999) (xy 36.071366 -476.293746) (xy 36.140713 -476.346115)
			(xy 36.204933 -476.404659) (xy 36.263477 -476.468879) (xy 36.315846 -476.538226) (xy 36.361593 -476.61211)
			(xy 36.400327 -476.689899) (xy 36.431719 -476.770931) (xy 36.4555 -476.854513) (xy 36.471468 -476.939933)
			(xy 36.479486 -477.026462) (xy 36.479988 -477.069912) (xy 36.479486 -477.113362) (xy 36.471468 -477.199891)
			(xy 36.4555 -477.285311) (xy 36.431719 -477.368893) (xy 36.400327 -477.449925) (xy 36.361593 -477.527714)
			(xy 36.315846 -477.601598) (xy 36.263477 -477.670945) (xy 36.205097 -477.734985) (xy 37.996106 -477.734985)
			(xy 37.996106 -477.663663) (xy 38.004092 -477.592789) (xy 38.019962 -477.523254) (xy 38.043519 -477.455934)
			(xy 38.074464 -477.391675) (xy 38.11241 -477.331284) (xy 38.156879 -477.275522) (xy 38.207312 -477.225089)
			(xy 38.263074 -477.18062) (xy 38.323465 -477.142674) (xy 38.387724 -477.111729) (xy 38.455044 -477.088172)
			(xy 38.524579 -477.072302) (xy 38.595453 -477.064316) (xy 38.666775 -477.064316) (xy 38.737649 -477.072302)
			(xy 38.807184 -477.088172) (xy 38.874504 -477.111729) (xy 38.938763 -477.142674) (xy 38.999154 -477.18062)
			(xy 39.054916 -477.225089) (xy 39.105349 -477.275522) (xy 39.149818 -477.331284) (xy 39.187764 -477.391675)
			(xy 39.218709 -477.455934) (xy 39.242266 -477.523254) (xy 39.258136 -477.592789) (xy 39.266122 -477.663663)
			(xy 39.266622 -477.699324) (xy 39.266122 -477.734985) (xy 39.882818 -477.734985) (xy 39.882818 -477.663663)
			(xy 39.890804 -477.592789) (xy 39.906674 -477.523254) (xy 39.930231 -477.455934) (xy 39.961176 -477.391675)
			(xy 39.999122 -477.331284) (xy 40.043591 -477.275522) (xy 40.094024 -477.225089) (xy 40.149786 -477.18062)
			(xy 40.210177 -477.142674) (xy 40.274436 -477.111729) (xy 40.341756 -477.088172) (xy 40.411291 -477.072302)
			(xy 40.482165 -477.064316) (xy 40.553487 -477.064316) (xy 40.624361 -477.072302) (xy 40.693896 -477.088172)
			(xy 40.761216 -477.111729) (xy 40.825475 -477.142674) (xy 40.885866 -477.18062) (xy 40.941628 -477.225089)
			(xy 40.992061 -477.275522) (xy 41.03653 -477.331284) (xy 41.074476 -477.391675) (xy 41.105421 -477.455934)
			(xy 41.128978 -477.523254) (xy 41.144848 -477.592789) (xy 41.152834 -477.663663) (xy 41.153334 -477.699324)
			(xy 41.152834 -477.734985) (xy 42.12386 -477.734985) (xy 42.12386 -477.663663) (xy 42.131846 -477.592789)
			(xy 42.147716 -477.523254) (xy 42.171273 -477.455934) (xy 42.202218 -477.391675) (xy 42.240164 -477.331284)
			(xy 42.284633 -477.275522) (xy 42.335066 -477.225089) (xy 42.390828 -477.18062) (xy 42.451219 -477.142674)
			(xy 42.515478 -477.111729) (xy 42.582798 -477.088172) (xy 42.652333 -477.072302) (xy 42.723207 -477.064316)
			(xy 42.794529 -477.064316) (xy 42.865403 -477.072302) (xy 42.934938 -477.088172) (xy 43.002258 -477.111729)
			(xy 43.066517 -477.142674) (xy 43.126908 -477.18062) (xy 43.18267 -477.225089) (xy 43.233103 -477.275522)
			(xy 43.277572 -477.331284) (xy 43.315518 -477.391675) (xy 43.346463 -477.455934) (xy 43.37002 -477.523254)
			(xy 43.38589 -477.592789) (xy 43.393876 -477.663663) (xy 43.394376 -477.699324) (xy 43.393876 -477.734985)
			(xy 44.027844 -477.734985) (xy 44.027844 -477.663663) (xy 44.03583 -477.592789) (xy 44.0517 -477.523254)
			(xy 44.075257 -477.455934) (xy 44.106202 -477.391675) (xy 44.144148 -477.331284) (xy 44.188617 -477.275522)
			(xy 44.23905 -477.225089) (xy 44.294812 -477.18062) (xy 44.355203 -477.142674) (xy 44.419462 -477.111729)
			(xy 44.486782 -477.088172) (xy 44.556317 -477.072302) (xy 44.627191 -477.064316) (xy 44.698513 -477.064316)
			(xy 44.769387 -477.072302) (xy 44.838922 -477.088172) (xy 44.906242 -477.111729) (xy 44.970501 -477.142674)
			(xy 45.030892 -477.18062) (xy 45.086654 -477.225089) (xy 45.137087 -477.275522) (xy 45.181556 -477.331284)
			(xy 45.219502 -477.391675) (xy 45.250447 -477.455934) (xy 45.274004 -477.523254) (xy 45.289874 -477.592789)
			(xy 45.29786 -477.663663) (xy 45.29836 -477.699324) (xy 45.29786 -477.734985) (xy 45.289874 -477.805859)
			(xy 45.274004 -477.875394) (xy 45.250447 -477.942714) (xy 45.219502 -478.006973) (xy 45.181556 -478.067364)
			(xy 45.137087 -478.123126) (xy 45.086654 -478.173559) (xy 45.030892 -478.218028) (xy 44.970501 -478.255974)
			(xy 44.906242 -478.286919) (xy 44.838922 -478.310476) (xy 44.769387 -478.326346) (xy 44.698513 -478.334332)
			(xy 44.627191 -478.334332) (xy 44.556317 -478.326346) (xy 44.486782 -478.310476) (xy 44.419462 -478.286919)
			(xy 44.355203 -478.255974) (xy 44.294812 -478.218028) (xy 44.23905 -478.173559) (xy 44.188617 -478.123126)
			(xy 44.144148 -478.067364) (xy 44.106202 -478.006973) (xy 44.075257 -477.942714) (xy 44.0517 -477.875394)
			(xy 44.03583 -477.805859) (xy 44.027844 -477.734985) (xy 43.393876 -477.734985) (xy 43.38589 -477.805859)
			(xy 43.37002 -477.875394) (xy 43.346463 -477.942714) (xy 43.315518 -478.006973) (xy 43.277572 -478.067364)
			(xy 43.233103 -478.123126) (xy 43.18267 -478.173559) (xy 43.126908 -478.218028) (xy 43.066517 -478.255974)
			(xy 43.002258 -478.286919) (xy 42.934938 -478.310476) (xy 42.865403 -478.326346) (xy 42.794529 -478.334332)
			(xy 42.723207 -478.334332) (xy 42.652333 -478.326346) (xy 42.582798 -478.310476) (xy 42.515478 -478.286919)
			(xy 42.451219 -478.255974) (xy 42.390828 -478.218028) (xy 42.335066 -478.173559) (xy 42.284633 -478.123126)
			(xy 42.240164 -478.067364) (xy 42.202218 -478.006973) (xy 42.171273 -477.942714) (xy 42.147716 -477.875394)
			(xy 42.131846 -477.805859) (xy 42.12386 -477.734985) (xy 41.152834 -477.734985) (xy 41.144848 -477.805859)
			(xy 41.128978 -477.875394) (xy 41.105421 -477.942714) (xy 41.074476 -478.006973) (xy 41.03653 -478.067364)
			(xy 40.992061 -478.123126) (xy 40.941628 -478.173559) (xy 40.885866 -478.218028) (xy 40.825475 -478.255974)
			(xy 40.761216 -478.286919) (xy 40.693896 -478.310476) (xy 40.624361 -478.326346) (xy 40.553487 -478.334332)
			(xy 40.482165 -478.334332) (xy 40.411291 -478.326346) (xy 40.341756 -478.310476) (xy 40.274436 -478.286919)
			(xy 40.210177 -478.255974) (xy 40.149786 -478.218028) (xy 40.094024 -478.173559) (xy 40.043591 -478.123126)
			(xy 39.999122 -478.067364) (xy 39.961176 -478.006973) (xy 39.930231 -477.942714) (xy 39.906674 -477.875394)
			(xy 39.890804 -477.805859) (xy 39.882818 -477.734985) (xy 39.266122 -477.734985) (xy 39.258136 -477.805859)
			(xy 39.242266 -477.875394) (xy 39.218709 -477.942714) (xy 39.187764 -478.006973) (xy 39.149818 -478.067364)
			(xy 39.105349 -478.123126) (xy 39.054916 -478.173559) (xy 38.999154 -478.218028) (xy 38.938763 -478.255974)
			(xy 38.874504 -478.286919) (xy 38.807184 -478.310476) (xy 38.737649 -478.326346) (xy 38.666775 -478.334332)
			(xy 38.595453 -478.334332) (xy 38.524579 -478.326346) (xy 38.455044 -478.310476) (xy 38.387724 -478.286919)
			(xy 38.323465 -478.255974) (xy 38.263074 -478.218028) (xy 38.207312 -478.173559) (xy 38.156879 -478.123126)
			(xy 38.11241 -478.067364) (xy 38.074464 -478.006973) (xy 38.043519 -477.942714) (xy 38.019962 -477.875394)
			(xy 38.004092 -477.805859) (xy 37.996106 -477.734985) (xy 36.205097 -477.734985) (xy 36.204933 -477.735165)
			(xy 36.140713 -477.793709) (xy 36.071366 -477.846078) (xy 35.997482 -477.891825) (xy 35.919693 -477.930559)
			(xy 35.838661 -477.961951) (xy 35.755079 -477.985732) (xy 35.669659 -478.0017) (xy 35.58313 -478.009718)
			(xy 35.49623 -478.009718) (xy 35.409701 -478.0017) (xy 35.324281 -477.985732) (xy 35.240699 -477.961951)
			(xy 35.159667 -477.930559) (xy 35.081878 -477.891825) (xy 35.007994 -477.846078) (xy 34.938647 -477.793709)
			(xy 34.874427 -477.735165) (xy 34.815883 -477.670945) (xy 34.763514 -477.601598) (xy 34.717767 -477.527714)
			(xy 34.679033 -477.449925) (xy 34.647641 -477.368893) (xy 34.62386 -477.285311) (xy 34.607892 -477.199891)
			(xy 34.599874 -477.113362) (xy 31.399486 -477.113362) (xy 31.391468 -477.199891) (xy 31.3755 -477.285311)
			(xy 31.351719 -477.368893) (xy 31.320327 -477.449925) (xy 31.281593 -477.527714) (xy 31.235846 -477.601598)
			(xy 31.183477 -477.670945) (xy 31.124933 -477.735165) (xy 31.060713 -477.793709) (xy 30.991366 -477.846078)
			(xy 30.917482 -477.891825) (xy 30.839693 -477.930559) (xy 30.758661 -477.961951) (xy 30.675079 -477.985732)
			(xy 30.589659 -478.0017) (xy 30.50313 -478.009718) (xy 30.41623 -478.009718) (xy 30.329701 -478.0017)
			(xy 30.244281 -477.985732) (xy 30.160699 -477.961951) (xy 30.079667 -477.930559) (xy 30.001878 -477.891825)
			(xy 29.927994 -477.846078) (xy 29.858647 -477.793709) (xy 29.794427 -477.735165) (xy 29.735883 -477.670945)
			(xy 29.683514 -477.601598) (xy 29.637767 -477.527714) (xy 29.599033 -477.449925) (xy 29.567641 -477.368893)
			(xy 29.54386 -477.285311) (xy 29.527892 -477.199891) (xy 29.519874 -477.113362) (xy 20.594832 -477.113362)
			(xy 20.559661 -477.155277) (xy 20.422697 -477.306209) (xy 20.279984 -477.451716) (xy 20.131737 -477.591581)
			(xy 19.978177 -477.725592) (xy 19.819537 -477.853548) (xy 19.656054 -477.975256) (xy 19.487975 -478.090534)
			(xy 19.315552 -478.199208) (xy 19.139046 -478.301114) (xy 18.95872 -478.396099) (xy 18.774847 -478.484021)
			(xy 18.587703 -478.564747) (xy 18.39757 -478.638156) (xy 18.204733 -478.704137) (xy 18.009483 -478.762591)
			(xy 17.812113 -478.81343) (xy 17.61292 -478.856578) (xy 17.412204 -478.89197) (xy 17.210267 -478.919552)
			(xy 17.007412 -478.939283) (xy 16.803944 -478.951134) (xy 16.60017 -478.955086) (xy 16.396396 -478.951134)
			(xy 16.192928 -478.939283) (xy 15.990073 -478.919552) (xy 15.788136 -478.89197) (xy 15.58742 -478.856578)
			(xy 15.388227 -478.81343) (xy 15.190857 -478.762591) (xy 14.995607 -478.704137) (xy 14.80277 -478.638156)
			(xy 14.612637 -478.564747) (xy 14.425493 -478.484021) (xy 14.24162 -478.396099) (xy 14.061294 -478.301114)
			(xy 13.884788 -478.199208) (xy 13.712365 -478.090534) (xy 13.544286 -477.975256) (xy 13.380803 -477.853548)
			(xy 13.222163 -477.725592) (xy 13.068603 -477.591581) (xy 12.920356 -477.451716) (xy 12.777643 -477.306209)
			(xy 12.640679 -477.155277) (xy 12.509671 -476.999147) (xy 12.384815 -476.838055) (xy 12.2663 -476.672243)
			(xy 12.154303 -476.50196) (xy 12.048993 -476.327463) (xy 11.950529 -476.149013) (xy 11.859058 -475.96688)
			(xy 11.774718 -475.781337) (xy 11.697637 -475.592663) (xy 11.627929 -475.401142) (xy 11.565699 -475.207062)
			(xy 11.511043 -475.010715) (xy 11.46404 -474.812396) (xy 11.424763 -474.612404) (xy 11.39327 -474.411039)
			(xy 11.369609 -474.208605) (xy 11.353815 -474.005405) (xy 11.345912 -473.801746) (xy 11.345418 -473.69984)
			(xy 1.27 -473.69984) (xy 1.27 -479.653362) (xy 29.519874 -479.653362) (xy 29.519874 -479.566462)
			(xy 29.527892 -479.479933) (xy 29.54386 -479.394513) (xy 29.567641 -479.310931) (xy 29.599033 -479.229899)
			(xy 29.637767 -479.15211) (xy 29.683514 -479.078226) (xy 29.735883 -479.008879) (xy 29.794427 -478.944659)
			(xy 29.858647 -478.886115) (xy 29.927994 -478.833746) (xy 30.001878 -478.787999) (xy 30.079667 -478.749265)
			(xy 30.160699 -478.717873) (xy 30.244281 -478.694092) (xy 30.329701 -478.678124) (xy 30.41623 -478.670106)
			(xy 30.50313 -478.670106) (xy 30.589659 -478.678124) (xy 30.675079 -478.694092) (xy 30.758661 -478.717873)
			(xy 30.839693 -478.749265) (xy 30.917482 -478.787999) (xy 30.991366 -478.833746) (xy 31.060713 -478.886115)
			(xy 31.124933 -478.944659) (xy 31.183477 -479.008879) (xy 31.235846 -479.078226) (xy 31.281593 -479.15211)
			(xy 31.320327 -479.229899) (xy 31.351719 -479.310931) (xy 31.3755 -479.394513) (xy 31.391468 -479.479933)
			(xy 31.399486 -479.566462) (xy 31.399988 -479.609912) (xy 31.399486 -479.653362) (xy 34.599874 -479.653362)
			(xy 34.599874 -479.566462) (xy 34.607892 -479.479933) (xy 34.62386 -479.394513) (xy 34.647641 -479.310931)
			(xy 34.679033 -479.229899) (xy 34.717767 -479.15211) (xy 34.763514 -479.078226) (xy 34.815883 -479.008879)
			(xy 34.874427 -478.944659) (xy 34.938647 -478.886115) (xy 35.007994 -478.833746) (xy 35.081878 -478.787999)
			(xy 35.159667 -478.749265) (xy 35.240699 -478.717873) (xy 35.324281 -478.694092) (xy 35.409701 -478.678124)
			(xy 35.49623 -478.670106) (xy 35.58313 -478.670106) (xy 35.669659 -478.678124) (xy 35.755079 -478.694092)
			(xy 35.838661 -478.717873) (xy 35.919693 -478.749265) (xy 35.997482 -478.787999) (xy 36.071366 -478.833746)
			(xy 36.140713 -478.886115) (xy 36.204933 -478.944659) (xy 36.263477 -479.008879) (xy 36.315846 -479.078226)
			(xy 36.361593 -479.15211) (xy 36.400327 -479.229899) (xy 36.431719 -479.310931) (xy 36.4555 -479.394513)
			(xy 36.458417 -479.410115) (xy 37.996106 -479.410115) (xy 37.996106 -479.338793) (xy 38.004092 -479.267919)
			(xy 38.019962 -479.198384) (xy 38.043519 -479.131064) (xy 38.074464 -479.066805) (xy 38.11241 -479.006414)
			(xy 38.156879 -478.950652) (xy 38.207312 -478.900219) (xy 38.263074 -478.85575) (xy 38.323465 -478.817804)
			(xy 38.387724 -478.786859) (xy 38.455044 -478.763302) (xy 38.524579 -478.747432) (xy 38.595453 -478.739446)
			(xy 38.666775 -478.739446) (xy 38.737649 -478.747432) (xy 38.807184 -478.763302) (xy 38.874504 -478.786859)
			(xy 38.938763 -478.817804) (xy 38.999154 -478.85575) (xy 39.054916 -478.900219) (xy 39.105349 -478.950652)
			(xy 39.149818 -479.006414) (xy 39.187764 -479.066805) (xy 39.218709 -479.131064) (xy 39.242266 -479.198384)
			(xy 39.258136 -479.267919) (xy 39.266122 -479.338793) (xy 39.266622 -479.374454) (xy 39.266122 -479.410115)
			(xy 39.882818 -479.410115) (xy 39.882818 -479.338793) (xy 39.890804 -479.267919) (xy 39.906674 -479.198384)
			(xy 39.930231 -479.131064) (xy 39.961176 -479.066805) (xy 39.999122 -479.006414) (xy 40.043591 -478.950652)
			(xy 40.094024 -478.900219) (xy 40.149786 -478.85575) (xy 40.210177 -478.817804) (xy 40.274436 -478.786859)
			(xy 40.341756 -478.763302) (xy 40.411291 -478.747432) (xy 40.482165 -478.739446) (xy 40.553487 -478.739446)
			(xy 40.624361 -478.747432) (xy 40.693896 -478.763302) (xy 40.761216 -478.786859) (xy 40.825475 -478.817804)
			(xy 40.885866 -478.85575) (xy 40.941628 -478.900219) (xy 40.992061 -478.950652) (xy 41.03653 -479.006414)
			(xy 41.074476 -479.066805) (xy 41.105421 -479.131064) (xy 41.128978 -479.198384) (xy 41.144848 -479.267919)
			(xy 41.152834 -479.338793) (xy 41.153334 -479.374454) (xy 41.152834 -479.410115) (xy 42.12386 -479.410115)
			(xy 42.12386 -479.338793) (xy 42.131846 -479.267919) (xy 42.147716 -479.198384) (xy 42.171273 -479.131064)
			(xy 42.202218 -479.066805) (xy 42.240164 -479.006414) (xy 42.284633 -478.950652) (xy 42.335066 -478.900219)
			(xy 42.390828 -478.85575) (xy 42.451219 -478.817804) (xy 42.515478 -478.786859) (xy 42.582798 -478.763302)
			(xy 42.652333 -478.747432) (xy 42.723207 -478.739446) (xy 42.794529 -478.739446) (xy 42.865403 -478.747432)
			(xy 42.934938 -478.763302) (xy 43.002258 -478.786859) (xy 43.066517 -478.817804) (xy 43.126908 -478.85575)
			(xy 43.18267 -478.900219) (xy 43.233103 -478.950652) (xy 43.277572 -479.006414) (xy 43.315518 -479.066805)
			(xy 43.346463 -479.131064) (xy 43.37002 -479.198384) (xy 43.38589 -479.267919) (xy 43.393876 -479.338793)
			(xy 43.394376 -479.374454) (xy 43.393876 -479.410115) (xy 44.027844 -479.410115) (xy 44.027844 -479.338793)
			(xy 44.03583 -479.267919) (xy 44.0517 -479.198384) (xy 44.075257 -479.131064) (xy 44.106202 -479.066805)
			(xy 44.144148 -479.006414) (xy 44.188617 -478.950652) (xy 44.23905 -478.900219) (xy 44.294812 -478.85575)
			(xy 44.355203 -478.817804) (xy 44.419462 -478.786859) (xy 44.486782 -478.763302) (xy 44.556317 -478.747432)
			(xy 44.627191 -478.739446) (xy 44.698513 -478.739446) (xy 44.769387 -478.747432) (xy 44.838922 -478.763302)
			(xy 44.906242 -478.786859) (xy 44.923841 -478.795334) (xy 74.887836 -478.795334) (xy 74.887836 -477.804734)
			(xy 74.888285 -477.726894) (xy 74.896067 -477.571409) (xy 74.911614 -477.416508) (xy 74.934886 -477.262578)
			(xy 74.965825 -477.110003) (xy 75.004354 -476.959167) (xy 75.050376 -476.810446) (xy 75.103777 -476.664211)
			(xy 75.164423 -476.52083) (xy 75.232161 -476.38066) (xy 75.306823 -476.244052) (xy 75.388222 -476.111348)
			(xy 75.476155 -475.98288) (xy 75.5704 -475.858969) (xy 75.670723 -475.739926) (xy 75.776873 -475.626047)
			(xy 75.888584 -475.517618) (xy 75.946762 -475.465902) (xy 76.007239 -475.41338) (xy 76.132813 -475.313911)
			(xy 76.263344 -475.221041) (xy 76.398485 -475.135018) (xy 76.537878 -475.056071) (xy 76.681152 -474.984408)
			(xy 76.827927 -474.920221) (xy 76.977814 -474.863679) (xy 77.130414 -474.814933) (xy 77.285323 -474.774111)
			(xy 77.442128 -474.741323) (xy 77.600415 -474.716656) (xy 77.759761 -474.700175) (xy 77.919746 -474.691923)
			(xy 78.079942 -474.691923) (xy 78.239927 -474.700175) (xy 78.399273 -474.716656) (xy 78.55756 -474.741323)
			(xy 78.714365 -474.774111) (xy 78.869274 -474.814933) (xy 79.021874 -474.863679) (xy 79.171761 -474.920221)
			(xy 79.318536 -474.984408) (xy 79.46181 -475.056071) (xy 79.601203 -475.135018) (xy 79.736344 -475.221041)
			(xy 79.866875 -475.313911) (xy 79.992449 -475.41338) (xy 80.052926 -475.465902) (xy 80.111074 -475.517651)
			(xy 80.22278 -475.62608) (xy 80.328926 -475.739959) (xy 80.429246 -475.859002) (xy 80.523489 -475.982912)
			(xy 80.611419 -476.111379) (xy 80.692816 -476.244081) (xy 80.767477 -476.380687) (xy 80.835215 -476.520854)
			(xy 80.89586 -476.664233) (xy 80.949261 -476.810464) (xy 80.995285 -476.959183) (xy 81.033815 -477.110016)
			(xy 81.064757 -477.262588) (xy 81.088032 -477.416515) (xy 81.103582 -477.571413) (xy 81.111368 -477.726895)
			(xy 81.111852 -477.804734) (xy 81.111852 -478.795334) (xy 81.111371 -478.874704) (xy 81.103273 -479.033238)
			(xy 81.087104 -479.191153) (xy 81.062907 -479.348038) (xy 81.030744 -479.503486) (xy 80.9907 -479.657093)
			(xy 80.942878 -479.808459) (xy 80.887402 -479.95719) (xy 80.824417 -480.1029) (xy 80.754087 -480.24521)
			(xy 80.676594 -480.383751) (xy 80.59214 -480.518161) (xy 80.500944 -480.648091) (xy 80.403245 -480.773204)
			(xy 80.299294 -480.893175) (xy 80.189364 -481.00769) (xy 80.073739 -481.116454) (xy 80.013556 -481.168202)
			(xy 79.953637 -481.218513) (xy 79.829479 -481.313747) (xy 79.700688 -481.402615) (xy 79.567588 -481.484891)
			(xy 79.430517 -481.560366) (xy 79.289823 -481.628849) (xy 79.145862 -481.690167) (xy 78.998998 -481.744164)
			(xy 78.849603 -481.790704) (xy 78.698055 -481.829669) (xy 78.54474 -481.86096) (xy 78.390044 -481.884498)
			(xy 78.23436 -481.900223) (xy 78.078082 -481.908096) (xy 77.921606 -481.908096) (xy 77.765328 -481.900223)
			(xy 77.609644 -481.884498) (xy 77.454948 -481.86096) (xy 77.301633 -481.829669) (xy 77.150085 -481.790704)
			(xy 77.00069 -481.744164) (xy 76.853826 -481.690167) (xy 76.709865 -481.628849) (xy 76.569171 -481.560366)
			(xy 76.4321 -481.484891) (xy 76.299 -481.402615) (xy 76.170209 -481.313747) (xy 76.046051 -481.218513)
			(xy 75.986132 -481.168202) (xy 75.925932 -481.116473) (xy 75.810304 -481.007712) (xy 75.700371 -480.893197)
			(xy 75.596418 -480.773228) (xy 75.498717 -480.648114) (xy 75.407521 -480.518183) (xy 75.323067 -480.383772)
			(xy 75.245575 -480.24523) (xy 75.175246 -480.102918) (xy 75.112264 -479.957206) (xy 75.056791 -479.808472)
			(xy 75.008974 -479.657104) (xy 74.968934 -479.503495) (xy 74.936778 -479.348044) (xy 74.912588 -479.191157)
			(xy 74.896428 -479.03324) (xy 74.888339 -478.874705) (xy 74.887836 -478.795334) (xy 44.923841 -478.795334)
			(xy 44.970501 -478.817804) (xy 45.030892 -478.85575) (xy 45.086654 -478.900219) (xy 45.137087 -478.950652)
			(xy 45.181556 -479.006414) (xy 45.219502 -479.066805) (xy 45.250447 -479.131064) (xy 45.274004 -479.198384)
			(xy 45.289874 -479.267919) (xy 45.29786 -479.338793) (xy 45.29836 -479.374454) (xy 45.29786 -479.410115)
			(xy 45.289874 -479.480989) (xy 45.274004 -479.550524) (xy 45.250447 -479.617844) (xy 45.219502 -479.682103)
			(xy 45.181556 -479.742494) (xy 45.137087 -479.798256) (xy 45.086654 -479.848689) (xy 45.030892 -479.893158)
			(xy 44.970501 -479.931104) (xy 44.906242 -479.962049) (xy 44.838922 -479.985606) (xy 44.769387 -480.001476)
			(xy 44.698513 -480.009462) (xy 44.627191 -480.009462) (xy 44.556317 -480.001476) (xy 44.486782 -479.985606)
			(xy 44.419462 -479.962049) (xy 44.355203 -479.931104) (xy 44.294812 -479.893158) (xy 44.23905 -479.848689)
			(xy 44.188617 -479.798256) (xy 44.144148 -479.742494) (xy 44.106202 -479.682103) (xy 44.075257 -479.617844)
			(xy 44.0517 -479.550524) (xy 44.03583 -479.480989) (xy 44.027844 -479.410115) (xy 43.393876 -479.410115)
			(xy 43.38589 -479.480989) (xy 43.37002 -479.550524) (xy 43.346463 -479.617844) (xy 43.315518 -479.682103)
			(xy 43.277572 -479.742494) (xy 43.233103 -479.798256) (xy 43.18267 -479.848689) (xy 43.126908 -479.893158)
			(xy 43.066517 -479.931104) (xy 43.002258 -479.962049) (xy 42.934938 -479.985606) (xy 42.865403 -480.001476)
			(xy 42.794529 -480.009462) (xy 42.723207 -480.009462) (xy 42.652333 -480.001476) (xy 42.582798 -479.985606)
			(xy 42.515478 -479.962049) (xy 42.451219 -479.931104) (xy 42.390828 -479.893158) (xy 42.335066 -479.848689)
			(xy 42.284633 -479.798256) (xy 42.240164 -479.742494) (xy 42.202218 -479.682103) (xy 42.171273 -479.617844)
			(xy 42.147716 -479.550524) (xy 42.131846 -479.480989) (xy 42.12386 -479.410115) (xy 41.152834 -479.410115)
			(xy 41.144848 -479.480989) (xy 41.128978 -479.550524) (xy 41.105421 -479.617844) (xy 41.074476 -479.682103)
			(xy 41.03653 -479.742494) (xy 40.992061 -479.798256) (xy 40.941628 -479.848689) (xy 40.885866 -479.893158)
			(xy 40.825475 -479.931104) (xy 40.761216 -479.962049) (xy 40.693896 -479.985606) (xy 40.624361 -480.001476)
			(xy 40.553487 -480.009462) (xy 40.482165 -480.009462) (xy 40.411291 -480.001476) (xy 40.341756 -479.985606)
			(xy 40.274436 -479.962049) (xy 40.210177 -479.931104) (xy 40.149786 -479.893158) (xy 40.094024 -479.848689)
			(xy 40.043591 -479.798256) (xy 39.999122 -479.742494) (xy 39.961176 -479.682103) (xy 39.930231 -479.617844)
			(xy 39.906674 -479.550524) (xy 39.890804 -479.480989) (xy 39.882818 -479.410115) (xy 39.266122 -479.410115)
			(xy 39.258136 -479.480989) (xy 39.242266 -479.550524) (xy 39.218709 -479.617844) (xy 39.187764 -479.682103)
			(xy 39.149818 -479.742494) (xy 39.105349 -479.798256) (xy 39.054916 -479.848689) (xy 38.999154 -479.893158)
			(xy 38.938763 -479.931104) (xy 38.874504 -479.962049) (xy 38.807184 -479.985606) (xy 38.737649 -480.001476)
			(xy 38.666775 -480.009462) (xy 38.595453 -480.009462) (xy 38.524579 -480.001476) (xy 38.455044 -479.985606)
			(xy 38.387724 -479.962049) (xy 38.323465 -479.931104) (xy 38.263074 -479.893158) (xy 38.207312 -479.848689)
			(xy 38.156879 -479.798256) (xy 38.11241 -479.742494) (xy 38.074464 -479.682103) (xy 38.043519 -479.617844)
			(xy 38.019962 -479.550524) (xy 38.004092 -479.480989) (xy 37.996106 -479.410115) (xy 36.458417 -479.410115)
			(xy 36.471468 -479.479933) (xy 36.479486 -479.566462) (xy 36.479988 -479.609912) (xy 36.479486 -479.653362)
			(xy 36.471468 -479.739891) (xy 36.4555 -479.825311) (xy 36.431719 -479.908893) (xy 36.400327 -479.989925)
			(xy 36.361593 -480.067714) (xy 36.315846 -480.141598) (xy 36.263477 -480.210945) (xy 36.204933 -480.275165)
			(xy 36.140713 -480.333709) (xy 36.071366 -480.386078) (xy 35.997482 -480.431825) (xy 35.919693 -480.470559)
			(xy 35.838661 -480.501951) (xy 35.755079 -480.525732) (xy 35.669659 -480.5417) (xy 35.58313 -480.549718)
			(xy 35.49623 -480.549718) (xy 35.409701 -480.5417) (xy 35.324281 -480.525732) (xy 35.240699 -480.501951)
			(xy 35.159667 -480.470559) (xy 35.081878 -480.431825) (xy 35.007994 -480.386078) (xy 34.938647 -480.333709)
			(xy 34.874427 -480.275165) (xy 34.815883 -480.210945) (xy 34.763514 -480.141598) (xy 34.717767 -480.067714)
			(xy 34.679033 -479.989925) (xy 34.647641 -479.908893) (xy 34.62386 -479.825311) (xy 34.607892 -479.739891)
			(xy 34.599874 -479.653362) (xy 31.399486 -479.653362) (xy 31.391468 -479.739891) (xy 31.3755 -479.825311)
			(xy 31.351719 -479.908893) (xy 31.320327 -479.989925) (xy 31.281593 -480.067714) (xy 31.235846 -480.141598)
			(xy 31.183477 -480.210945) (xy 31.124933 -480.275165) (xy 31.060713 -480.333709) (xy 30.991366 -480.386078)
			(xy 30.917482 -480.431825) (xy 30.839693 -480.470559) (xy 30.758661 -480.501951) (xy 30.675079 -480.525732)
			(xy 30.589659 -480.5417) (xy 30.50313 -480.549718) (xy 30.41623 -480.549718) (xy 30.329701 -480.5417)
			(xy 30.244281 -480.525732) (xy 30.160699 -480.501951) (xy 30.079667 -480.470559) (xy 30.001878 -480.431825)
			(xy 29.927994 -480.386078) (xy 29.858647 -480.333709) (xy 29.794427 -480.275165) (xy 29.735883 -480.210945)
			(xy 29.683514 -480.141598) (xy 29.637767 -480.067714) (xy 29.599033 -479.989925) (xy 29.567641 -479.908893)
			(xy 29.54386 -479.825311) (xy 29.527892 -479.739891) (xy 29.519874 -479.653362) (xy 1.27 -479.653362)
			(xy 1.27 -482.193362) (xy 29.519874 -482.193362) (xy 29.519874 -482.106462) (xy 29.527892 -482.019933)
			(xy 29.54386 -481.934513) (xy 29.567641 -481.850931) (xy 29.599033 -481.769899) (xy 29.637767 -481.69211)
			(xy 29.683514 -481.618226) (xy 29.735883 -481.548879) (xy 29.794427 -481.484659) (xy 29.858647 -481.426115)
			(xy 29.927994 -481.373746) (xy 30.001878 -481.327999) (xy 30.079667 -481.289265) (xy 30.160699 -481.257873)
			(xy 30.244281 -481.234092) (xy 30.329701 -481.218124) (xy 30.41623 -481.210106) (xy 30.50313 -481.210106)
			(xy 30.589659 -481.218124) (xy 30.675079 -481.234092) (xy 30.758661 -481.257873) (xy 30.839693 -481.289265)
			(xy 30.917482 -481.327999) (xy 30.991366 -481.373746) (xy 31.060713 -481.426115) (xy 31.124933 -481.484659)
			(xy 31.183477 -481.548879) (xy 31.235846 -481.618226) (xy 31.281593 -481.69211) (xy 31.320327 -481.769899)
			(xy 31.351719 -481.850931) (xy 31.3755 -481.934513) (xy 31.391468 -482.019933) (xy 31.399486 -482.106462)
			(xy 31.399988 -482.149912) (xy 31.399486 -482.193362) (xy 34.599874 -482.193362) (xy 34.599874 -482.106462)
			(xy 34.607892 -482.019933) (xy 34.62386 -481.934513) (xy 34.647641 -481.850931) (xy 34.679033 -481.769899)
			(xy 34.717767 -481.69211) (xy 34.763514 -481.618226) (xy 34.815883 -481.548879) (xy 34.874427 -481.484659)
			(xy 34.938647 -481.426115) (xy 35.007994 -481.373746) (xy 35.081878 -481.327999) (xy 35.159667 -481.289265)
			(xy 35.240699 -481.257873) (xy 35.324281 -481.234092) (xy 35.409701 -481.218124) (xy 35.49623 -481.210106)
			(xy 35.58313 -481.210106) (xy 35.669659 -481.218124) (xy 35.755079 -481.234092) (xy 35.838661 -481.257873)
			(xy 35.919693 -481.289265) (xy 35.997482 -481.327999) (xy 36.071366 -481.373746) (xy 36.13432 -481.421287)
			(xy 37.952672 -481.421287) (xy 37.952672 -481.349965) (xy 37.960658 -481.279091) (xy 37.976528 -481.209556)
			(xy 38.000085 -481.142236) (xy 38.03103 -481.077977) (xy 38.068976 -481.017586) (xy 38.113445 -480.961824)
			(xy 38.163878 -480.911391) (xy 38.21964 -480.866922) (xy 38.280031 -480.828976) (xy 38.34429 -480.798031)
			(xy 38.41161 -480.774474) (xy 38.481145 -480.758604) (xy 38.552019 -480.750618) (xy 38.623341 -480.750618)
			(xy 38.694215 -480.758604) (xy 38.76375 -480.774474) (xy 38.83107 -480.798031) (xy 38.895329 -480.828976)
			(xy 38.95572 -480.866922) (xy 39.011482 -480.911391) (xy 39.061915 -480.961824) (xy 39.106384 -481.017586)
			(xy 39.14433 -481.077977) (xy 39.175275 -481.142236) (xy 39.198832 -481.209556) (xy 39.214702 -481.279091)
			(xy 39.222688 -481.349965) (xy 39.223188 -481.385626) (xy 39.222688 -481.421287) (xy 39.839384 -481.421287)
			(xy 39.839384 -481.349965) (xy 39.84737 -481.279091) (xy 39.86324 -481.209556) (xy 39.886797 -481.142236)
			(xy 39.917742 -481.077977) (xy 39.955688 -481.017586) (xy 40.000157 -480.961824) (xy 40.05059 -480.911391)
			(xy 40.106352 -480.866922) (xy 40.166743 -480.828976) (xy 40.231002 -480.798031) (xy 40.298322 -480.774474)
			(xy 40.367857 -480.758604) (xy 40.438731 -480.750618) (xy 40.510053 -480.750618) (xy 40.580927 -480.758604)
			(xy 40.650462 -480.774474) (xy 40.717782 -480.798031) (xy 40.782041 -480.828976) (xy 40.842432 -480.866922)
			(xy 40.898194 -480.911391) (xy 40.948627 -480.961824) (xy 40.993096 -481.017586) (xy 41.031042 -481.077977)
			(xy 41.061987 -481.142236) (xy 41.085544 -481.209556) (xy 41.101414 -481.279091) (xy 41.1094 -481.349965)
			(xy 41.1099 -481.385626) (xy 41.1094 -481.421287) (xy 42.080426 -481.421287) (xy 42.080426 -481.349965)
			(xy 42.088412 -481.279091) (xy 42.104282 -481.209556) (xy 42.127839 -481.142236) (xy 42.158784 -481.077977)
			(xy 42.19673 -481.017586) (xy 42.241199 -480.961824) (xy 42.291632 -480.911391) (xy 42.347394 -480.866922)
			(xy 42.407785 -480.828976) (xy 42.472044 -480.798031) (xy 42.539364 -480.774474) (xy 42.608899 -480.758604)
			(xy 42.679773 -480.750618) (xy 42.751095 -480.750618) (xy 42.821969 -480.758604) (xy 42.891504 -480.774474)
			(xy 42.958824 -480.798031) (xy 43.023083 -480.828976) (xy 43.083474 -480.866922) (xy 43.139236 -480.911391)
			(xy 43.189669 -480.961824) (xy 43.234138 -481.017586) (xy 43.272084 -481.077977) (xy 43.303029 -481.142236)
			(xy 43.326586 -481.209556) (xy 43.342456 -481.279091) (xy 43.350442 -481.349965) (xy 43.350942 -481.385626)
			(xy 43.350442 -481.421287) (xy 43.98441 -481.421287) (xy 43.98441 -481.349965) (xy 43.992396 -481.279091)
			(xy 44.008266 -481.209556) (xy 44.031823 -481.142236) (xy 44.062768 -481.077977) (xy 44.100714 -481.017586)
			(xy 44.145183 -480.961824) (xy 44.195616 -480.911391) (xy 44.251378 -480.866922) (xy 44.311769 -480.828976)
			(xy 44.376028 -480.798031) (xy 44.443348 -480.774474) (xy 44.512883 -480.758604) (xy 44.583757 -480.750618)
			(xy 44.655079 -480.750618) (xy 44.725953 -480.758604) (xy 44.795488 -480.774474) (xy 44.862808 -480.798031)
			(xy 44.927067 -480.828976) (xy 44.987458 -480.866922) (xy 45.04322 -480.911391) (xy 45.093653 -480.961824)
			(xy 45.138122 -481.017586) (xy 45.176068 -481.077977) (xy 45.207013 -481.142236) (xy 45.23057 -481.209556)
			(xy 45.24644 -481.279091) (xy 45.254426 -481.349965) (xy 45.254926 -481.385626) (xy 45.254426 -481.421287)
			(xy 45.24644 -481.492161) (xy 45.23057 -481.561696) (xy 45.207013 -481.629016) (xy 45.176068 -481.693275)
			(xy 45.138122 -481.753666) (xy 45.093653 -481.809428) (xy 45.04322 -481.859861) (xy 44.987458 -481.90433)
			(xy 44.927067 -481.942276) (xy 44.862808 -481.973221) (xy 44.795488 -481.996778) (xy 44.725953 -482.012648)
			(xy 44.655079 -482.020634) (xy 44.583757 -482.020634) (xy 44.512883 -482.012648) (xy 44.443348 -481.996778)
			(xy 44.376028 -481.973221) (xy 44.311769 -481.942276) (xy 44.251378 -481.90433) (xy 44.195616 -481.859861)
			(xy 44.145183 -481.809428) (xy 44.100714 -481.753666) (xy 44.062768 -481.693275) (xy 44.031823 -481.629016)
			(xy 44.008266 -481.561696) (xy 43.992396 -481.492161) (xy 43.98441 -481.421287) (xy 43.350442 -481.421287)
			(xy 43.342456 -481.492161) (xy 43.326586 -481.561696) (xy 43.303029 -481.629016) (xy 43.272084 -481.693275)
			(xy 43.234138 -481.753666) (xy 43.189669 -481.809428) (xy 43.139236 -481.859861) (xy 43.083474 -481.90433)
			(xy 43.023083 -481.942276) (xy 42.958824 -481.973221) (xy 42.891504 -481.996778) (xy 42.821969 -482.012648)
			(xy 42.751095 -482.020634) (xy 42.679773 -482.020634) (xy 42.608899 -482.012648) (xy 42.539364 -481.996778)
			(xy 42.472044 -481.973221) (xy 42.407785 -481.942276) (xy 42.347394 -481.90433) (xy 42.291632 -481.859861)
			(xy 42.241199 -481.809428) (xy 42.19673 -481.753666) (xy 42.158784 -481.693275) (xy 42.127839 -481.629016)
			(xy 42.104282 -481.561696) (xy 42.088412 -481.492161) (xy 42.080426 -481.421287) (xy 41.1094 -481.421287)
			(xy 41.101414 -481.492161) (xy 41.085544 -481.561696) (xy 41.061987 -481.629016) (xy 41.031042 -481.693275)
			(xy 40.993096 -481.753666) (xy 40.948627 -481.809428) (xy 40.898194 -481.859861) (xy 40.842432 -481.90433)
			(xy 40.782041 -481.942276) (xy 40.717782 -481.973221) (xy 40.650462 -481.996778) (xy 40.580927 -482.012648)
			(xy 40.510053 -482.020634) (xy 40.438731 -482.020634) (xy 40.367857 -482.012648) (xy 40.298322 -481.996778)
			(xy 40.231002 -481.973221) (xy 40.166743 -481.942276) (xy 40.106352 -481.90433) (xy 40.05059 -481.859861)
			(xy 40.000157 -481.809428) (xy 39.955688 -481.753666) (xy 39.917742 -481.693275) (xy 39.886797 -481.629016)
			(xy 39.86324 -481.561696) (xy 39.84737 -481.492161) (xy 39.839384 -481.421287) (xy 39.222688 -481.421287)
			(xy 39.214702 -481.492161) (xy 39.198832 -481.561696) (xy 39.175275 -481.629016) (xy 39.14433 -481.693275)
			(xy 39.106384 -481.753666) (xy 39.061915 -481.809428) (xy 39.011482 -481.859861) (xy 38.95572 -481.90433)
			(xy 38.895329 -481.942276) (xy 38.83107 -481.973221) (xy 38.76375 -481.996778) (xy 38.694215 -482.012648)
			(xy 38.623341 -482.020634) (xy 38.552019 -482.020634) (xy 38.481145 -482.012648) (xy 38.41161 -481.996778)
			(xy 38.34429 -481.973221) (xy 38.280031 -481.942276) (xy 38.21964 -481.90433) (xy 38.163878 -481.859861)
			(xy 38.113445 -481.809428) (xy 38.068976 -481.753666) (xy 38.03103 -481.693275) (xy 38.000085 -481.629016)
			(xy 37.976528 -481.561696) (xy 37.960658 -481.492161) (xy 37.952672 -481.421287) (xy 36.13432 -481.421287)
			(xy 36.140713 -481.426115) (xy 36.204933 -481.484659) (xy 36.263477 -481.548879) (xy 36.315846 -481.618226)
			(xy 36.361593 -481.69211) (xy 36.400327 -481.769899) (xy 36.431719 -481.850931) (xy 36.4555 -481.934513)
			(xy 36.471468 -482.019933) (xy 36.479486 -482.106462) (xy 36.479988 -482.149912) (xy 36.479486 -482.193362)
			(xy 36.471468 -482.279891) (xy 36.4555 -482.365311) (xy 36.431719 -482.448893) (xy 36.400327 -482.529925)
			(xy 36.361593 -482.607714) (xy 36.315846 -482.681598) (xy 36.263477 -482.750945) (xy 36.204933 -482.815165)
			(xy 36.140713 -482.873709) (xy 36.071366 -482.926078) (xy 35.997482 -482.971825) (xy 35.919693 -483.010559)
			(xy 35.838661 -483.041951) (xy 35.755079 -483.065732) (xy 35.669659 -483.0817) (xy 35.58313 -483.089718)
			(xy 35.49623 -483.089718) (xy 35.409701 -483.0817) (xy 35.324281 -483.065732) (xy 35.240699 -483.041951)
			(xy 35.159667 -483.010559) (xy 35.081878 -482.971825) (xy 35.007994 -482.926078) (xy 34.938647 -482.873709)
			(xy 34.874427 -482.815165) (xy 34.815883 -482.750945) (xy 34.763514 -482.681598) (xy 34.717767 -482.607714)
			(xy 34.679033 -482.529925) (xy 34.647641 -482.448893) (xy 34.62386 -482.365311) (xy 34.607892 -482.279891)
			(xy 34.599874 -482.193362) (xy 31.399486 -482.193362) (xy 31.391468 -482.279891) (xy 31.3755 -482.365311)
			(xy 31.351719 -482.448893) (xy 31.320327 -482.529925) (xy 31.281593 -482.607714) (xy 31.235846 -482.681598)
			(xy 31.183477 -482.750945) (xy 31.124933 -482.815165) (xy 31.060713 -482.873709) (xy 30.991366 -482.926078)
			(xy 30.917482 -482.971825) (xy 30.839693 -483.010559) (xy 30.758661 -483.041951) (xy 30.675079 -483.065732)
			(xy 30.589659 -483.0817) (xy 30.50313 -483.089718) (xy 30.41623 -483.089718) (xy 30.329701 -483.0817)
			(xy 30.244281 -483.065732) (xy 30.160699 -483.041951) (xy 30.079667 -483.010559) (xy 30.001878 -482.971825)
			(xy 29.927994 -482.926078) (xy 29.858647 -482.873709) (xy 29.794427 -482.815165) (xy 29.735883 -482.750945)
			(xy 29.683514 -482.681598) (xy 29.637767 -482.607714) (xy 29.599033 -482.529925) (xy 29.567641 -482.448893)
			(xy 29.54386 -482.365311) (xy 29.527892 -482.279891) (xy 29.519874 -482.193362) (xy 1.27 -482.193362)
			(xy 1.27 -483.311809) (xy 37.952672 -483.311809) (xy 37.952672 -483.240487) (xy 37.960658 -483.169613)
			(xy 37.976528 -483.100078) (xy 38.000085 -483.032758) (xy 38.03103 -482.968499) (xy 38.068976 -482.908108)
			(xy 38.113445 -482.852346) (xy 38.163878 -482.801913) (xy 38.21964 -482.757444) (xy 38.280031 -482.719498)
			(xy 38.34429 -482.688553) (xy 38.41161 -482.664996) (xy 38.481145 -482.649126) (xy 38.552019 -482.64114)
			(xy 38.623341 -482.64114) (xy 38.694215 -482.649126) (xy 38.76375 -482.664996) (xy 38.83107 -482.688553)
			(xy 38.895329 -482.719498) (xy 38.95572 -482.757444) (xy 39.011482 -482.801913) (xy 39.061915 -482.852346)
			(xy 39.106384 -482.908108) (xy 39.14433 -482.968499) (xy 39.175275 -483.032758) (xy 39.198832 -483.100078)
			(xy 39.214702 -483.169613) (xy 39.222688 -483.240487) (xy 39.223188 -483.276148) (xy 39.222688 -483.311809)
			(xy 39.839384 -483.311809) (xy 39.839384 -483.240487) (xy 39.84737 -483.169613) (xy 39.86324 -483.100078)
			(xy 39.886797 -483.032758) (xy 39.917742 -482.968499) (xy 39.955688 -482.908108) (xy 40.000157 -482.852346)
			(xy 40.05059 -482.801913) (xy 40.106352 -482.757444) (xy 40.166743 -482.719498) (xy 40.231002 -482.688553)
			(xy 40.298322 -482.664996) (xy 40.367857 -482.649126) (xy 40.438731 -482.64114) (xy 40.510053 -482.64114)
			(xy 40.580927 -482.649126) (xy 40.650462 -482.664996) (xy 40.717782 -482.688553) (xy 40.782041 -482.719498)
			(xy 40.842432 -482.757444) (xy 40.898194 -482.801913) (xy 40.948627 -482.852346) (xy 40.993096 -482.908108)
			(xy 41.031042 -482.968499) (xy 41.061987 -483.032758) (xy 41.085544 -483.100078) (xy 41.101414 -483.169613)
			(xy 41.1094 -483.240487) (xy 41.1099 -483.276148) (xy 41.1094 -483.311809) (xy 42.080426 -483.311809)
			(xy 42.080426 -483.240487) (xy 42.088412 -483.169613) (xy 42.104282 -483.100078) (xy 42.127839 -483.032758)
			(xy 42.158784 -482.968499) (xy 42.19673 -482.908108) (xy 42.241199 -482.852346) (xy 42.291632 -482.801913)
			(xy 42.347394 -482.757444) (xy 42.407785 -482.719498) (xy 42.472044 -482.688553) (xy 42.539364 -482.664996)
			(xy 42.608899 -482.649126) (xy 42.679773 -482.64114) (xy 42.751095 -482.64114) (xy 42.821969 -482.649126)
			(xy 42.891504 -482.664996) (xy 42.958824 -482.688553) (xy 43.023083 -482.719498) (xy 43.083474 -482.757444)
			(xy 43.139236 -482.801913) (xy 43.189669 -482.852346) (xy 43.234138 -482.908108) (xy 43.272084 -482.968499)
			(xy 43.303029 -483.032758) (xy 43.326586 -483.100078) (xy 43.342456 -483.169613) (xy 43.350442 -483.240487)
			(xy 43.350942 -483.276148) (xy 43.350442 -483.311809) (xy 43.98441 -483.311809) (xy 43.98441 -483.240487)
			(xy 43.992396 -483.169613) (xy 44.008266 -483.100078) (xy 44.031823 -483.032758) (xy 44.062768 -482.968499)
			(xy 44.100714 -482.908108) (xy 44.145183 -482.852346) (xy 44.195616 -482.801913) (xy 44.251378 -482.757444)
			(xy 44.311769 -482.719498) (xy 44.376028 -482.688553) (xy 44.443348 -482.664996) (xy 44.512883 -482.649126)
			(xy 44.583757 -482.64114) (xy 44.655079 -482.64114) (xy 44.725953 -482.649126) (xy 44.795488 -482.664996)
			(xy 44.862808 -482.688553) (xy 44.927067 -482.719498) (xy 44.97121 -482.747235) (xy 47.507896 -482.747235)
			(xy 47.507896 -482.666125) (xy 47.515846 -482.585406) (xy 47.531669 -482.505855) (xy 47.555214 -482.428239)
			(xy 47.586253 -482.353303) (xy 47.624488 -482.281771) (xy 47.66955 -482.214331) (xy 47.721005 -482.151632)
			(xy 47.778358 -482.094279) (xy 47.841057 -482.042824) (xy 47.908497 -481.997762) (xy 47.980029 -481.959527)
			(xy 48.054965 -481.928488) (xy 48.132581 -481.904943) (xy 48.212132 -481.88912) (xy 48.292851 -481.88117)
			(xy 48.373961 -481.88117) (xy 48.45468 -481.88912) (xy 48.534231 -481.904943) (xy 48.611847 -481.928488)
			(xy 48.686783 -481.959527) (xy 48.758315 -481.997762) (xy 48.825755 -482.042824) (xy 48.888454 -482.094279)
			(xy 48.945807 -482.151632) (xy 48.997262 -482.214331) (xy 49.042324 -482.281771) (xy 49.080559 -482.353303)
			(xy 49.111598 -482.428239) (xy 49.135143 -482.505855) (xy 49.150966 -482.585406) (xy 49.158916 -482.666125)
			(xy 49.159414 -482.70668) (xy 49.158916 -482.747235) (xy 49.150966 -482.827954) (xy 49.135143 -482.907505)
			(xy 49.111598 -482.985121) (xy 49.080559 -483.060057) (xy 49.042324 -483.131589) (xy 48.997262 -483.199029)
			(xy 48.945807 -483.261728) (xy 48.888454 -483.319081) (xy 48.825755 -483.370536) (xy 48.758315 -483.415598)
			(xy 48.686783 -483.453833) (xy 48.611847 -483.484872) (xy 48.534231 -483.508417) (xy 48.45468 -483.52424)
			(xy 48.373961 -483.53219) (xy 48.292851 -483.53219) (xy 48.212132 -483.52424) (xy 48.132581 -483.508417)
			(xy 48.054965 -483.484872) (xy 47.980029 -483.453833) (xy 47.908497 -483.415598) (xy 47.841057 -483.370536)
			(xy 47.778358 -483.319081) (xy 47.721005 -483.261728) (xy 47.66955 -483.199029) (xy 47.624488 -483.131589)
			(xy 47.586253 -483.060057) (xy 47.555214 -482.985121) (xy 47.531669 -482.907505) (xy 47.515846 -482.827954)
			(xy 47.507896 -482.747235) (xy 44.97121 -482.747235) (xy 44.987458 -482.757444) (xy 45.04322 -482.801913)
			(xy 45.093653 -482.852346) (xy 45.138122 -482.908108) (xy 45.176068 -482.968499) (xy 45.207013 -483.032758)
			(xy 45.23057 -483.100078) (xy 45.24644 -483.169613) (xy 45.254426 -483.240487) (xy 45.254926 -483.276148)
			(xy 45.254426 -483.311809) (xy 45.24644 -483.382683) (xy 45.23057 -483.452218) (xy 45.207013 -483.519538)
			(xy 45.176068 -483.583797) (xy 45.138122 -483.644188) (xy 45.093653 -483.69995) (xy 45.04322 -483.750383)
			(xy 44.987458 -483.794852) (xy 44.927067 -483.832798) (xy 44.862808 -483.863743) (xy 44.795488 -483.8873)
			(xy 44.725953 -483.90317) (xy 44.655079 -483.911156) (xy 44.583757 -483.911156) (xy 44.512883 -483.90317)
			(xy 44.443348 -483.8873) (xy 44.376028 -483.863743) (xy 44.311769 -483.832798) (xy 44.251378 -483.794852)
			(xy 44.195616 -483.750383) (xy 44.145183 -483.69995) (xy 44.100714 -483.644188) (xy 44.062768 -483.583797)
			(xy 44.031823 -483.519538) (xy 44.008266 -483.452218) (xy 43.992396 -483.382683) (xy 43.98441 -483.311809)
			(xy 43.350442 -483.311809) (xy 43.342456 -483.382683) (xy 43.326586 -483.452218) (xy 43.303029 -483.519538)
			(xy 43.272084 -483.583797) (xy 43.234138 -483.644188) (xy 43.189669 -483.69995) (xy 43.139236 -483.750383)
			(xy 43.083474 -483.794852) (xy 43.023083 -483.832798) (xy 42.958824 -483.863743) (xy 42.891504 -483.8873)
			(xy 42.821969 -483.90317) (xy 42.751095 -483.911156) (xy 42.679773 -483.911156) (xy 42.608899 -483.90317)
			(xy 42.539364 -483.8873) (xy 42.472044 -483.863743) (xy 42.407785 -483.832798) (xy 42.347394 -483.794852)
			(xy 42.291632 -483.750383) (xy 42.241199 -483.69995) (xy 42.19673 -483.644188) (xy 42.158784 -483.583797)
			(xy 42.127839 -483.519538) (xy 42.104282 -483.452218) (xy 42.088412 -483.382683) (xy 42.080426 -483.311809)
			(xy 41.1094 -483.311809) (xy 41.101414 -483.382683) (xy 41.085544 -483.452218) (xy 41.061987 -483.519538)
			(xy 41.031042 -483.583797) (xy 40.993096 -483.644188) (xy 40.948627 -483.69995) (xy 40.898194 -483.750383)
			(xy 40.842432 -483.794852) (xy 40.782041 -483.832798) (xy 40.717782 -483.863743) (xy 40.650462 -483.8873)
			(xy 40.580927 -483.90317) (xy 40.510053 -483.911156) (xy 40.438731 -483.911156) (xy 40.367857 -483.90317)
			(xy 40.298322 -483.8873) (xy 40.231002 -483.863743) (xy 40.166743 -483.832798) (xy 40.106352 -483.794852)
			(xy 40.05059 -483.750383) (xy 40.000157 -483.69995) (xy 39.955688 -483.644188) (xy 39.917742 -483.583797)
			(xy 39.886797 -483.519538) (xy 39.86324 -483.452218) (xy 39.84737 -483.382683) (xy 39.839384 -483.311809)
			(xy 39.222688 -483.311809) (xy 39.214702 -483.382683) (xy 39.198832 -483.452218) (xy 39.175275 -483.519538)
			(xy 39.14433 -483.583797) (xy 39.106384 -483.644188) (xy 39.061915 -483.69995) (xy 39.011482 -483.750383)
			(xy 38.95572 -483.794852) (xy 38.895329 -483.832798) (xy 38.83107 -483.863743) (xy 38.76375 -483.8873)
			(xy 38.694215 -483.90317) (xy 38.623341 -483.911156) (xy 38.552019 -483.911156) (xy 38.481145 -483.90317)
			(xy 38.41161 -483.8873) (xy 38.34429 -483.863743) (xy 38.280031 -483.832798) (xy 38.21964 -483.794852)
			(xy 38.163878 -483.750383) (xy 38.113445 -483.69995) (xy 38.068976 -483.644188) (xy 38.03103 -483.583797)
			(xy 38.000085 -483.519538) (xy 37.976528 -483.452218) (xy 37.960658 -483.382683) (xy 37.952672 -483.311809)
			(xy 1.27 -483.311809) (xy 1.27 -484.733362) (xy 29.519874 -484.733362) (xy 29.519874 -484.646462)
			(xy 29.527892 -484.559933) (xy 29.54386 -484.474513) (xy 29.567641 -484.390931) (xy 29.599033 -484.309899)
			(xy 29.637767 -484.23211) (xy 29.683514 -484.158226) (xy 29.735883 -484.088879) (xy 29.794427 -484.024659)
			(xy 29.858647 -483.966115) (xy 29.927994 -483.913746) (xy 30.001878 -483.867999) (xy 30.079667 -483.829265)
			(xy 30.160699 -483.797873) (xy 30.244281 -483.774092) (xy 30.329701 -483.758124) (xy 30.41623 -483.750106)
			(xy 30.50313 -483.750106) (xy 30.589659 -483.758124) (xy 30.675079 -483.774092) (xy 30.758661 -483.797873)
			(xy 30.839693 -483.829265) (xy 30.917482 -483.867999) (xy 30.991366 -483.913746) (xy 31.060713 -483.966115)
			(xy 31.124933 -484.024659) (xy 31.183477 -484.088879) (xy 31.235846 -484.158226) (xy 31.281593 -484.23211)
			(xy 31.320327 -484.309899) (xy 31.351719 -484.390931) (xy 31.3755 -484.474513) (xy 31.391468 -484.559933)
			(xy 31.399486 -484.646462) (xy 31.399988 -484.689912) (xy 31.399486 -484.733362) (xy 34.599874 -484.733362)
			(xy 34.599874 -484.646462) (xy 34.607892 -484.559933) (xy 34.62386 -484.474513) (xy 34.647641 -484.390931)
			(xy 34.679033 -484.309899) (xy 34.717767 -484.23211) (xy 34.763514 -484.158226) (xy 34.815883 -484.088879)
			(xy 34.874427 -484.024659) (xy 34.938647 -483.966115) (xy 35.007994 -483.913746) (xy 35.081878 -483.867999)
			(xy 35.159667 -483.829265) (xy 35.240699 -483.797873) (xy 35.324281 -483.774092) (xy 35.409701 -483.758124)
			(xy 35.49623 -483.750106) (xy 35.58313 -483.750106) (xy 35.669659 -483.758124) (xy 35.755079 -483.774092)
			(xy 35.838661 -483.797873) (xy 35.919693 -483.829265) (xy 35.997482 -483.867999) (xy 36.071366 -483.913746)
			(xy 36.140713 -483.966115) (xy 36.204933 -484.024659) (xy 36.263477 -484.088879) (xy 36.315846 -484.158226)
			(xy 36.361593 -484.23211) (xy 36.400327 -484.309899) (xy 36.431719 -484.390931) (xy 36.4555 -484.474513)
			(xy 36.471468 -484.559933) (xy 36.479486 -484.646462) (xy 36.479988 -484.689912) (xy 36.479486 -484.733362)
			(xy 36.471468 -484.819891) (xy 36.4555 -484.905311) (xy 36.431719 -484.988893) (xy 36.400327 -485.069925)
			(xy 36.361593 -485.147714) (xy 36.315846 -485.221598) (xy 36.263477 -485.290945) (xy 36.206949 -485.352953)
			(xy 37.952672 -485.352953) (xy 37.952672 -485.281631) (xy 37.960658 -485.210757) (xy 37.976528 -485.141222)
			(xy 38.000085 -485.073902) (xy 38.03103 -485.009643) (xy 38.068976 -484.949252) (xy 38.113445 -484.89349)
			(xy 38.163878 -484.843057) (xy 38.21964 -484.798588) (xy 38.280031 -484.760642) (xy 38.34429 -484.729697)
			(xy 38.41161 -484.70614) (xy 38.481145 -484.69027) (xy 38.552019 -484.682284) (xy 38.623341 -484.682284)
			(xy 38.694215 -484.69027) (xy 38.76375 -484.70614) (xy 38.83107 -484.729697) (xy 38.895329 -484.760642)
			(xy 38.95572 -484.798588) (xy 39.011482 -484.843057) (xy 39.061915 -484.89349) (xy 39.106384 -484.949252)
			(xy 39.14433 -485.009643) (xy 39.175275 -485.073902) (xy 39.198832 -485.141222) (xy 39.214702 -485.210757)
			(xy 39.222688 -485.281631) (xy 39.223188 -485.317292) (xy 39.222688 -485.352953) (xy 39.839384 -485.352953)
			(xy 39.839384 -485.281631) (xy 39.84737 -485.210757) (xy 39.86324 -485.141222) (xy 39.886797 -485.073902)
			(xy 39.917742 -485.009643) (xy 39.955688 -484.949252) (xy 40.000157 -484.89349) (xy 40.05059 -484.843057)
			(xy 40.106352 -484.798588) (xy 40.166743 -484.760642) (xy 40.231002 -484.729697) (xy 40.298322 -484.70614)
			(xy 40.367857 -484.69027) (xy 40.438731 -484.682284) (xy 40.510053 -484.682284) (xy 40.580927 -484.69027)
			(xy 40.650462 -484.70614) (xy 40.717782 -484.729697) (xy 40.782041 -484.760642) (xy 40.842432 -484.798588)
			(xy 40.898194 -484.843057) (xy 40.948627 -484.89349) (xy 40.993096 -484.949252) (xy 41.031042 -485.009643)
			(xy 41.061987 -485.073902) (xy 41.085544 -485.141222) (xy 41.101414 -485.210757) (xy 41.1094 -485.281631)
			(xy 41.1099 -485.317292) (xy 41.1094 -485.352953) (xy 42.080426 -485.352953) (xy 42.080426 -485.281631)
			(xy 42.088412 -485.210757) (xy 42.104282 -485.141222) (xy 42.127839 -485.073902) (xy 42.158784 -485.009643)
			(xy 42.19673 -484.949252) (xy 42.241199 -484.89349) (xy 42.291632 -484.843057) (xy 42.347394 -484.798588)
			(xy 42.407785 -484.760642) (xy 42.472044 -484.729697) (xy 42.539364 -484.70614) (xy 42.608899 -484.69027)
			(xy 42.679773 -484.682284) (xy 42.751095 -484.682284) (xy 42.821969 -484.69027) (xy 42.891504 -484.70614)
			(xy 42.958824 -484.729697) (xy 43.023083 -484.760642) (xy 43.083474 -484.798588) (xy 43.139236 -484.843057)
			(xy 43.189669 -484.89349) (xy 43.234138 -484.949252) (xy 43.272084 -485.009643) (xy 43.303029 -485.073902)
			(xy 43.326586 -485.141222) (xy 43.342456 -485.210757) (xy 43.350442 -485.281631) (xy 43.350942 -485.317292)
			(xy 43.350442 -485.352953) (xy 43.98441 -485.352953) (xy 43.98441 -485.281631) (xy 43.992396 -485.210757)
			(xy 44.008266 -485.141222) (xy 44.031823 -485.073902) (xy 44.062768 -485.009643) (xy 44.100714 -484.949252)
			(xy 44.145183 -484.89349) (xy 44.195616 -484.843057) (xy 44.251378 -484.798588) (xy 44.311769 -484.760642)
			(xy 44.376028 -484.729697) (xy 44.443348 -484.70614) (xy 44.512883 -484.69027) (xy 44.583757 -484.682284)
			(xy 44.655079 -484.682284) (xy 44.725953 -484.69027) (xy 44.795488 -484.70614) (xy 44.862808 -484.729697)
			(xy 44.927067 -484.760642) (xy 44.987458 -484.798588) (xy 45.04322 -484.843057) (xy 45.093653 -484.89349)
			(xy 45.138122 -484.949252) (xy 45.176068 -485.009643) (xy 45.207013 -485.073902) (xy 45.23057 -485.141222)
			(xy 45.24644 -485.210757) (xy 45.254426 -485.281631) (xy 45.254926 -485.317292) (xy 45.254426 -485.352953)
			(xy 45.24644 -485.423827) (xy 45.23057 -485.493362) (xy 45.207013 -485.560682) (xy 45.176068 -485.624941)
			(xy 45.138122 -485.685332) (xy 45.093653 -485.741094) (xy 45.04322 -485.791527) (xy 44.987458 -485.835996)
			(xy 44.927067 -485.873942) (xy 44.862808 -485.904887) (xy 44.795488 -485.928444) (xy 44.725953 -485.944314)
			(xy 44.655079 -485.9523) (xy 44.583757 -485.9523) (xy 44.512883 -485.944314) (xy 44.443348 -485.928444)
			(xy 44.376028 -485.904887) (xy 44.311769 -485.873942) (xy 44.251378 -485.835996) (xy 44.195616 -485.791527)
			(xy 44.145183 -485.741094) (xy 44.100714 -485.685332) (xy 44.062768 -485.624941) (xy 44.031823 -485.560682)
			(xy 44.008266 -485.493362) (xy 43.992396 -485.423827) (xy 43.98441 -485.352953) (xy 43.350442 -485.352953)
			(xy 43.342456 -485.423827) (xy 43.326586 -485.493362) (xy 43.303029 -485.560682) (xy 43.272084 -485.624941)
			(xy 43.234138 -485.685332) (xy 43.189669 -485.741094) (xy 43.139236 -485.791527) (xy 43.083474 -485.835996)
			(xy 43.023083 -485.873942) (xy 42.958824 -485.904887) (xy 42.891504 -485.928444) (xy 42.821969 -485.944314)
			(xy 42.751095 -485.9523) (xy 42.679773 -485.9523) (xy 42.608899 -485.944314) (xy 42.539364 -485.928444)
			(xy 42.472044 -485.904887) (xy 42.407785 -485.873942) (xy 42.347394 -485.835996) (xy 42.291632 -485.791527)
			(xy 42.241199 -485.741094) (xy 42.19673 -485.685332) (xy 42.158784 -485.624941) (xy 42.127839 -485.560682)
			(xy 42.104282 -485.493362) (xy 42.088412 -485.423827) (xy 42.080426 -485.352953) (xy 41.1094 -485.352953)
			(xy 41.101414 -485.423827) (xy 41.085544 -485.493362) (xy 41.061987 -485.560682) (xy 41.031042 -485.624941)
			(xy 40.993096 -485.685332) (xy 40.948627 -485.741094) (xy 40.898194 -485.791527) (xy 40.842432 -485.835996)
			(xy 40.782041 -485.873942) (xy 40.717782 -485.904887) (xy 40.650462 -485.928444) (xy 40.580927 -485.944314)
			(xy 40.510053 -485.9523) (xy 40.438731 -485.9523) (xy 40.367857 -485.944314) (xy 40.298322 -485.928444)
			(xy 40.231002 -485.904887) (xy 40.166743 -485.873942) (xy 40.106352 -485.835996) (xy 40.05059 -485.791527)
			(xy 40.000157 -485.741094) (xy 39.955688 -485.685332) (xy 39.917742 -485.624941) (xy 39.886797 -485.560682)
			(xy 39.86324 -485.493362) (xy 39.84737 -485.423827) (xy 39.839384 -485.352953) (xy 39.222688 -485.352953)
			(xy 39.214702 -485.423827) (xy 39.198832 -485.493362) (xy 39.175275 -485.560682) (xy 39.14433 -485.624941)
			(xy 39.106384 -485.685332) (xy 39.061915 -485.741094) (xy 39.011482 -485.791527) (xy 38.95572 -485.835996)
			(xy 38.895329 -485.873942) (xy 38.83107 -485.904887) (xy 38.76375 -485.928444) (xy 38.694215 -485.944314)
			(xy 38.623341 -485.9523) (xy 38.552019 -485.9523) (xy 38.481145 -485.944314) (xy 38.41161 -485.928444)
			(xy 38.34429 -485.904887) (xy 38.280031 -485.873942) (xy 38.21964 -485.835996) (xy 38.163878 -485.791527)
			(xy 38.113445 -485.741094) (xy 38.068976 -485.685332) (xy 38.03103 -485.624941) (xy 38.000085 -485.560682)
			(xy 37.976528 -485.493362) (xy 37.960658 -485.423827) (xy 37.952672 -485.352953) (xy 36.206949 -485.352953)
			(xy 36.204933 -485.355165) (xy 36.140713 -485.413709) (xy 36.071366 -485.466078) (xy 35.997482 -485.511825)
			(xy 35.919693 -485.550559) (xy 35.838661 -485.581951) (xy 35.755079 -485.605732) (xy 35.669659 -485.6217)
			(xy 35.58313 -485.629718) (xy 35.49623 -485.629718) (xy 35.409701 -485.6217) (xy 35.324281 -485.605732)
			(xy 35.240699 -485.581951) (xy 35.159667 -485.550559) (xy 35.081878 -485.511825) (xy 35.007994 -485.466078)
			(xy 34.938647 -485.413709) (xy 34.874427 -485.355165) (xy 34.815883 -485.290945) (xy 34.763514 -485.221598)
			(xy 34.717767 -485.147714) (xy 34.679033 -485.069925) (xy 34.647641 -484.988893) (xy 34.62386 -484.905311)
			(xy 34.607892 -484.819891) (xy 34.599874 -484.733362) (xy 31.399486 -484.733362) (xy 31.391468 -484.819891)
			(xy 31.3755 -484.905311) (xy 31.351719 -484.988893) (xy 31.320327 -485.069925) (xy 31.281593 -485.147714)
			(xy 31.235846 -485.221598) (xy 31.183477 -485.290945) (xy 31.124933 -485.355165) (xy 31.060713 -485.413709)
			(xy 30.991366 -485.466078) (xy 30.917482 -485.511825) (xy 30.839693 -485.550559) (xy 30.758661 -485.581951)
			(xy 30.675079 -485.605732) (xy 30.589659 -485.6217) (xy 30.50313 -485.629718) (xy 30.41623 -485.629718)
			(xy 30.329701 -485.6217) (xy 30.244281 -485.605732) (xy 30.160699 -485.581951) (xy 30.079667 -485.550559)
			(xy 30.001878 -485.511825) (xy 29.927994 -485.466078) (xy 29.858647 -485.413709) (xy 29.794427 -485.355165)
			(xy 29.735883 -485.290945) (xy 29.683514 -485.221598) (xy 29.637767 -485.147714) (xy 29.599033 -485.069925)
			(xy 29.567641 -484.988893) (xy 29.54386 -484.905311) (xy 29.527892 -484.819891) (xy 29.519874 -484.733362)
			(xy 1.27 -484.733362) (xy 1.27 -485.985058) (xy 69.1675 -485.985058) (xy 69.171571 -485.929436) (xy 69.183697 -485.874999)
			(xy 69.20362 -485.822908) (xy 69.230916 -485.774273) (xy 69.265002 -485.73013) (xy 69.305151 -485.691421)
			(xy 69.350509 -485.65897) (xy 69.400109 -485.633469) (xy 69.452893 -485.615462) (xy 69.507736 -485.605332)
			(xy 69.56347 -485.603295) (xy 69.618907 -485.609395) (xy 69.672864 -485.623501) (xy 69.724193 -485.645313)
			(xy 69.771799 -485.674367) (xy 69.814667 -485.710042) (xy 69.851884 -485.751579) (xy 69.882657 -485.798092)
			(xy 69.906329 -485.848589) (xy 69.922397 -485.901996) (xy 69.930517 -485.957172) (xy 69.931026 -485.985058)
			(xy 70.29653 -485.985058) (xy 70.300601 -485.929436) (xy 70.312727 -485.874999) (xy 70.33265 -485.822908)
			(xy 70.359946 -485.774273) (xy 70.394032 -485.73013) (xy 70.434181 -485.691421) (xy 70.479539 -485.65897)
			(xy 70.529139 -485.633469) (xy 70.581923 -485.615462) (xy 70.636766 -485.605332) (xy 70.6925 -485.603295)
			(xy 70.747937 -485.609395) (xy 70.801894 -485.623501) (xy 70.853223 -485.645313) (xy 70.900829 -485.674367)
			(xy 70.943697 -485.710042) (xy 70.980914 -485.751579) (xy 71.011687 -485.798092) (xy 71.035359 -485.848589)
			(xy 71.051427 -485.901996) (xy 71.059547 -485.957172) (xy 71.060056 -485.985058) (xy 71.4281 -485.985058)
			(xy 71.432171 -485.929436) (xy 71.444297 -485.874999) (xy 71.46422 -485.822908) (xy 71.491516 -485.774273)
			(xy 71.525602 -485.73013) (xy 71.565751 -485.691421) (xy 71.611109 -485.65897) (xy 71.660709 -485.633469)
			(xy 71.713493 -485.615462) (xy 71.768336 -485.605332) (xy 71.82407 -485.603295) (xy 71.879507 -485.609395)
			(xy 71.933464 -485.623501) (xy 71.984793 -485.645313) (xy 72.032399 -485.674367) (xy 72.075267 -485.710042)
			(xy 72.112484 -485.751579) (xy 72.143257 -485.798092) (xy 72.166929 -485.848589) (xy 72.182997 -485.901996)
			(xy 72.191117 -485.957172) (xy 72.191626 -485.985058) (xy 72.546716 -485.985058) (xy 72.550787 -485.929436)
			(xy 72.562913 -485.874999) (xy 72.582836 -485.822908) (xy 72.610132 -485.774273) (xy 72.644218 -485.73013)
			(xy 72.684367 -485.691421) (xy 72.729725 -485.65897) (xy 72.779325 -485.633469) (xy 72.832109 -485.615462)
			(xy 72.886952 -485.605332) (xy 72.942686 -485.603295) (xy 72.998123 -485.609395) (xy 73.05208 -485.623501)
			(xy 73.103409 -485.645313) (xy 73.151015 -485.674367) (xy 73.193883 -485.710042) (xy 73.2311 -485.751579)
			(xy 73.261873 -485.798092) (xy 73.285545 -485.848589) (xy 73.301613 -485.901996) (xy 73.309733 -485.957172)
			(xy 73.310242 -485.985058) (xy 73.309733 -486.012944) (xy 73.301613 -486.06812) (xy 73.285545 -486.121527)
			(xy 73.261873 -486.172024) (xy 73.2311 -486.218537) (xy 73.193883 -486.260074) (xy 73.151015 -486.295749)
			(xy 73.103409 -486.324803) (xy 73.05208 -486.346615) (xy 72.998123 -486.360721) (xy 72.942686 -486.366821)
			(xy 72.886952 -486.364784) (xy 72.832109 -486.354654) (xy 72.779325 -486.336647) (xy 72.729725 -486.311146)
			(xy 72.684367 -486.278695) (xy 72.644218 -486.239986) (xy 72.610132 -486.195843) (xy 72.582836 -486.147208)
			(xy 72.562913 -486.095117) (xy 72.550787 -486.04068) (xy 72.546716 -485.985058) (xy 72.191626 -485.985058)
			(xy 72.191117 -486.012944) (xy 72.182997 -486.06812) (xy 72.166929 -486.121527) (xy 72.143257 -486.172024)
			(xy 72.112484 -486.218537) (xy 72.075267 -486.260074) (xy 72.032399 -486.295749) (xy 71.984793 -486.324803)
			(xy 71.933464 -486.346615) (xy 71.879507 -486.360721) (xy 71.82407 -486.366821) (xy 71.768336 -486.364784)
			(xy 71.713493 -486.354654) (xy 71.660709 -486.336647) (xy 71.611109 -486.311146) (xy 71.565751 -486.278695)
			(xy 71.525602 -486.239986) (xy 71.491516 -486.195843) (xy 71.46422 -486.147208) (xy 71.444297 -486.095117)
			(xy 71.432171 -486.04068) (xy 71.4281 -485.985058) (xy 71.060056 -485.985058) (xy 71.059547 -486.012944)
			(xy 71.051427 -486.06812) (xy 71.035359 -486.121527) (xy 71.011687 -486.172024) (xy 70.980914 -486.218537)
			(xy 70.943697 -486.260074) (xy 70.900829 -486.295749) (xy 70.853223 -486.324803) (xy 70.801894 -486.346615)
			(xy 70.747937 -486.360721) (xy 70.6925 -486.366821) (xy 70.636766 -486.364784) (xy 70.581923 -486.354654)
			(xy 70.529139 -486.336647) (xy 70.479539 -486.311146) (xy 70.434181 -486.278695) (xy 70.394032 -486.239986)
			(xy 70.359946 -486.195843) (xy 70.33265 -486.147208) (xy 70.312727 -486.095117) (xy 70.300601 -486.04068)
			(xy 70.29653 -485.985058) (xy 69.931026 -485.985058) (xy 69.930517 -486.012944) (xy 69.922397 -486.06812)
			(xy 69.906329 -486.121527) (xy 69.882657 -486.172024) (xy 69.851884 -486.218537) (xy 69.814667 -486.260074)
			(xy 69.771799 -486.295749) (xy 69.724193 -486.324803) (xy 69.672864 -486.346615) (xy 69.618907 -486.360721)
			(xy 69.56347 -486.366821) (xy 69.507736 -486.364784) (xy 69.452893 -486.354654) (xy 69.400109 -486.336647)
			(xy 69.350509 -486.311146) (xy 69.305151 -486.278695) (xy 69.265002 -486.239986) (xy 69.230916 -486.195843)
			(xy 69.20362 -486.147208) (xy 69.183697 -486.095117) (xy 69.171571 -486.04068) (xy 69.1675 -485.985058)
			(xy 1.27 -485.985058) (xy 1.27 -486.669334) (xy 1.270551 -486.692696) (xy 1.279134 -486.738627) (xy 1.29597 -486.782214)
			(xy 1.320492 -486.821989) (xy 1.351871 -486.85661) (xy 1.389052 -486.88491) (xy 1.430779 -486.905936)
			(xy 1.475648 -486.918978) (xy 1.522145 -486.923598) (xy 1.568703 -486.919638) (xy 1.613752 -486.907234)
			(xy 1.655774 -486.886802) (xy 1.693352 -486.859032) (xy 1.709674 -486.842308) (xy 1.754144 -486.795272)
			(xy 1.848064 -486.706175) (xy 1.947334 -486.623082) (xy 2.051571 -486.546313) (xy 2.160374 -486.476164)
			(xy 2.273323 -486.412906) (xy 2.389982 -486.356783) (xy 2.5099 -486.308012) (xy 2.632615 -486.26678)
			(xy 2.757653 -486.233247) (xy 2.884532 -486.207542) (xy 3.012762 -486.189765) (xy 3.141848 -486.179983)
			(xy 3.271293 -486.178236) (xy 3.400597 -486.184529) (xy 3.52926 -486.198838) (xy 3.656786 -486.221108)
			(xy 3.782684 -486.251253) (xy 3.906468 -486.289157) (xy 4.027658 -486.334673) (xy 4.14579 -486.387627)
			(xy 4.260405 -486.447812) (xy 4.371062 -486.514999) (xy 4.477334 -486.588926) (xy 4.578812 -486.669308)
			(xy 4.675102 -486.755837) (xy 4.765834 -486.848177) (xy 4.850658 -486.945972) (xy 4.929246 -487.048845)
			(xy 5.001295 -487.1564) (xy 5.066527 -487.26822) (xy 5.124691 -487.383875) (xy 5.175561 -487.502918)
			(xy 5.218942 -487.624889) (xy 5.254666 -487.749319) (xy 5.282595 -487.875727) (xy 5.302622 -488.003625)
			(xy 5.314669 -488.13252) (xy 5.31869 -488.261914) (xy 12.580624 -488.261914) (xy 12.584655 -488.132348)
			(xy 12.596734 -488.003284) (xy 12.616813 -487.87522) (xy 12.644815 -487.748653) (xy 12.680632 -487.62407)
			(xy 12.724124 -487.501956) (xy 12.775124 -487.382782) (xy 12.833435 -487.267009) (xy 12.89883 -487.155085)
			(xy 12.971057 -487.047443) (xy 13.049837 -486.9445) (xy 13.134864 -486.846654) (xy 13.225809 -486.754282)
			(xy 13.322321 -486.667744) (xy 13.424027 -486.587373) (xy 13.530533 -486.513481) (xy 13.641426 -486.446353)
			(xy 13.756278 -486.386249) (xy 13.874645 -486.333402) (xy 13.996068 -486.288015) (xy 14.120078 -486.250266)
			(xy 14.246195 -486.220299) (xy 14.373931 -486.19823) (xy 14.502792 -486.184146) (xy 14.632279 -486.1781)
			(xy 14.761892 -486.180116) (xy 14.891128 -486.190186) (xy 15.019489 -486.208271) (xy 15.146477 -486.234301)
			(xy 15.271601 -486.268176) (xy 15.394377 -486.309764) (xy 15.51433 -486.358905) (xy 15.630995 -486.415408)
			(xy 15.743923 -486.479055) (xy 15.852675 -486.549599) (xy 15.956831 -486.626768) (xy 16.055988 -486.710263)
			(xy 16.149762 -486.799761) (xy 16.237791 -486.894916) (xy 16.319734 -486.995359) (xy 16.395273 -487.100702)
			(xy 16.464118 -487.210538) (xy 16.49825 -487.273362) (xy 29.519874 -487.273362) (xy 29.519874 -487.186462)
			(xy 29.527892 -487.099933) (xy 29.54386 -487.014513) (xy 29.567641 -486.930931) (xy 29.599033 -486.849899)
			(xy 29.637767 -486.77211) (xy 29.683514 -486.698226) (xy 29.735883 -486.628879) (xy 29.794427 -486.564659)
			(xy 29.858647 -486.506115) (xy 29.927994 -486.453746) (xy 30.001878 -486.407999) (xy 30.079667 -486.369265)
			(xy 30.160699 -486.337873) (xy 30.244281 -486.314092) (xy 30.329701 -486.298124) (xy 30.41623 -486.290106)
			(xy 30.50313 -486.290106) (xy 30.589659 -486.298124) (xy 30.675079 -486.314092) (xy 30.758661 -486.337873)
			(xy 30.839693 -486.369265) (xy 30.917482 -486.407999) (xy 30.991366 -486.453746) (xy 31.060713 -486.506115)
			(xy 31.124933 -486.564659) (xy 31.183477 -486.628879) (xy 31.235846 -486.698226) (xy 31.281593 -486.77211)
			(xy 31.320327 -486.849899) (xy 31.351719 -486.930931) (xy 31.3755 -487.014513) (xy 31.391468 -487.099933)
			(xy 31.399486 -487.186462) (xy 31.399988 -487.229912) (xy 31.399486 -487.273362) (xy 34.599874 -487.273362)
			(xy 34.599874 -487.186462) (xy 34.607892 -487.099933) (xy 34.62386 -487.014513) (xy 34.647641 -486.930931)
			(xy 34.679033 -486.849899) (xy 34.717767 -486.77211) (xy 34.763514 -486.698226) (xy 34.815883 -486.628879)
			(xy 34.874427 -486.564659) (xy 34.938647 -486.506115) (xy 35.007994 -486.453746) (xy 35.081878 -486.407999)
			(xy 35.159667 -486.369265) (xy 35.240699 -486.337873) (xy 35.324281 -486.314092) (xy 35.409701 -486.298124)
			(xy 35.49623 -486.290106) (xy 35.58313 -486.290106) (xy 35.669659 -486.298124) (xy 35.755079 -486.314092)
			(xy 35.838661 -486.337873) (xy 35.919693 -486.369265) (xy 35.997482 -486.407999) (xy 36.071366 -486.453746)
			(xy 36.140713 -486.506115) (xy 36.204933 -486.564659) (xy 36.263477 -486.628879) (xy 36.315846 -486.698226)
			(xy 36.361593 -486.77211) (xy 36.400327 -486.849899) (xy 36.431719 -486.930931) (xy 36.4555 -487.014513)
			(xy 36.471468 -487.099933) (xy 36.479486 -487.186462) (xy 36.479988 -487.229912) (xy 36.479608 -487.262779)
			(xy 37.952672 -487.262779) (xy 37.952672 -487.191457) (xy 37.960658 -487.120583) (xy 37.976528 -487.051048)
			(xy 38.000085 -486.983728) (xy 38.03103 -486.919469) (xy 38.068976 -486.859078) (xy 38.113445 -486.803316)
			(xy 38.163878 -486.752883) (xy 38.21964 -486.708414) (xy 38.280031 -486.670468) (xy 38.34429 -486.639523)
			(xy 38.41161 -486.615966) (xy 38.481145 -486.600096) (xy 38.552019 -486.59211) (xy 38.623341 -486.59211)
			(xy 38.694215 -486.600096) (xy 38.76375 -486.615966) (xy 38.83107 -486.639523) (xy 38.895329 -486.670468)
			(xy 38.95572 -486.708414) (xy 39.011482 -486.752883) (xy 39.061915 -486.803316) (xy 39.106384 -486.859078)
			(xy 39.14433 -486.919469) (xy 39.175275 -486.983728) (xy 39.198832 -487.051048) (xy 39.214702 -487.120583)
			(xy 39.222688 -487.191457) (xy 39.223188 -487.227118) (xy 39.222688 -487.262779) (xy 39.839384 -487.262779)
			(xy 39.839384 -487.191457) (xy 39.84737 -487.120583) (xy 39.86324 -487.051048) (xy 39.886797 -486.983728)
			(xy 39.917742 -486.919469) (xy 39.955688 -486.859078) (xy 40.000157 -486.803316) (xy 40.05059 -486.752883)
			(xy 40.106352 -486.708414) (xy 40.166743 -486.670468) (xy 40.231002 -486.639523) (xy 40.298322 -486.615966)
			(xy 40.367857 -486.600096) (xy 40.438731 -486.59211) (xy 40.510053 -486.59211) (xy 40.580927 -486.600096)
			(xy 40.650462 -486.615966) (xy 40.717782 -486.639523) (xy 40.782041 -486.670468) (xy 40.842432 -486.708414)
			(xy 40.898194 -486.752883) (xy 40.948627 -486.803316) (xy 40.993096 -486.859078) (xy 41.031042 -486.919469)
			(xy 41.061987 -486.983728) (xy 41.085544 -487.051048) (xy 41.101414 -487.120583) (xy 41.1094 -487.191457)
			(xy 41.1099 -487.227118) (xy 41.1094 -487.262779) (xy 42.080426 -487.262779) (xy 42.080426 -487.191457)
			(xy 42.088412 -487.120583) (xy 42.104282 -487.051048) (xy 42.127839 -486.983728) (xy 42.158784 -486.919469)
			(xy 42.19673 -486.859078) (xy 42.241199 -486.803316) (xy 42.291632 -486.752883) (xy 42.347394 -486.708414)
			(xy 42.407785 -486.670468) (xy 42.472044 -486.639523) (xy 42.539364 -486.615966) (xy 42.608899 -486.600096)
			(xy 42.679773 -486.59211) (xy 42.751095 -486.59211) (xy 42.821969 -486.600096) (xy 42.891504 -486.615966)
			(xy 42.958824 -486.639523) (xy 43.023083 -486.670468) (xy 43.083474 -486.708414) (xy 43.139236 -486.752883)
			(xy 43.189669 -486.803316) (xy 43.234138 -486.859078) (xy 43.272084 -486.919469) (xy 43.303029 -486.983728)
			(xy 43.326586 -487.051048) (xy 43.342456 -487.120583) (xy 43.350442 -487.191457) (xy 43.350942 -487.227118)
			(xy 43.350442 -487.262779) (xy 43.98441 -487.262779) (xy 43.98441 -487.191457) (xy 43.992396 -487.120583)
			(xy 44.008266 -487.051048) (xy 44.031823 -486.983728) (xy 44.062768 -486.919469) (xy 44.100714 -486.859078)
			(xy 44.145183 -486.803316) (xy 44.195616 -486.752883) (xy 44.251378 -486.708414) (xy 44.311769 -486.670468)
			(xy 44.376028 -486.639523) (xy 44.443348 -486.615966) (xy 44.512883 -486.600096) (xy 44.583757 -486.59211)
			(xy 44.655079 -486.59211) (xy 44.725953 -486.600096) (xy 44.795488 -486.615966) (xy 44.862808 -486.639523)
			(xy 44.927067 -486.670468) (xy 44.987458 -486.708414) (xy 45.04322 -486.752883) (xy 45.093653 -486.803316)
			(xy 45.138122 -486.859078) (xy 45.176068 -486.919469) (xy 45.207013 -486.983728) (xy 45.23057 -487.051048)
			(xy 45.24644 -487.120583) (xy 45.254426 -487.191457) (xy 45.254926 -487.227118) (xy 45.254426 -487.262779)
			(xy 45.24644 -487.333653) (xy 45.23057 -487.403188) (xy 45.207013 -487.470508) (xy 45.176068 -487.534767)
			(xy 45.138122 -487.595158) (xy 45.093653 -487.65092) (xy 45.04322 -487.701353) (xy 44.987458 -487.745822)
			(xy 44.927067 -487.783768) (xy 44.862808 -487.814713) (xy 44.795488 -487.83827) (xy 44.725953 -487.85414)
			(xy 44.655079 -487.862126) (xy 44.583757 -487.862126) (xy 44.512883 -487.85414) (xy 44.443348 -487.83827)
			(xy 44.376028 -487.814713) (xy 44.311769 -487.783768) (xy 44.251378 -487.745822) (xy 44.195616 -487.701353)
			(xy 44.145183 -487.65092) (xy 44.100714 -487.595158) (xy 44.062768 -487.534767) (xy 44.031823 -487.470508)
			(xy 44.008266 -487.403188) (xy 43.992396 -487.333653) (xy 43.98441 -487.262779) (xy 43.350442 -487.262779)
			(xy 43.342456 -487.333653) (xy 43.326586 -487.403188) (xy 43.303029 -487.470508) (xy 43.272084 -487.534767)
			(xy 43.234138 -487.595158) (xy 43.189669 -487.65092) (xy 43.139236 -487.701353) (xy 43.083474 -487.745822)
			(xy 43.023083 -487.783768) (xy 42.958824 -487.814713) (xy 42.891504 -487.83827) (xy 42.821969 -487.85414)
			(xy 42.751095 -487.862126) (xy 42.679773 -487.862126) (xy 42.608899 -487.85414) (xy 42.539364 -487.83827)
			(xy 42.472044 -487.814713) (xy 42.407785 -487.783768) (xy 42.347394 -487.745822) (xy 42.291632 -487.701353)
			(xy 42.241199 -487.65092) (xy 42.19673 -487.595158) (xy 42.158784 -487.534767) (xy 42.127839 -487.470508)
			(xy 42.104282 -487.403188) (xy 42.088412 -487.333653) (xy 42.080426 -487.262779) (xy 41.1094 -487.262779)
			(xy 41.101414 -487.333653) (xy 41.085544 -487.403188) (xy 41.061987 -487.470508) (xy 41.031042 -487.534767)
			(xy 40.993096 -487.595158) (xy 40.948627 -487.65092) (xy 40.898194 -487.701353) (xy 40.842432 -487.745822)
			(xy 40.782041 -487.783768) (xy 40.717782 -487.814713) (xy 40.650462 -487.83827) (xy 40.580927 -487.85414)
			(xy 40.510053 -487.862126) (xy 40.438731 -487.862126) (xy 40.367857 -487.85414) (xy 40.298322 -487.83827)
			(xy 40.231002 -487.814713) (xy 40.166743 -487.783768) (xy 40.106352 -487.745822) (xy 40.05059 -487.701353)
			(xy 40.000157 -487.65092) (xy 39.955688 -487.595158) (xy 39.917742 -487.534767) (xy 39.886797 -487.470508)
			(xy 39.86324 -487.403188) (xy 39.84737 -487.333653) (xy 39.839384 -487.262779) (xy 39.222688 -487.262779)
			(xy 39.214702 -487.333653) (xy 39.198832 -487.403188) (xy 39.175275 -487.470508) (xy 39.14433 -487.534767)
			(xy 39.106384 -487.595158) (xy 39.061915 -487.65092) (xy 39.011482 -487.701353) (xy 38.95572 -487.745822)
			(xy 38.895329 -487.783768) (xy 38.83107 -487.814713) (xy 38.76375 -487.83827) (xy 38.694215 -487.85414)
			(xy 38.623341 -487.862126) (xy 38.552019 -487.862126) (xy 38.481145 -487.85414) (xy 38.41161 -487.83827)
			(xy 38.34429 -487.814713) (xy 38.280031 -487.783768) (xy 38.21964 -487.745822) (xy 38.163878 -487.701353)
			(xy 38.113445 -487.65092) (xy 38.068976 -487.595158) (xy 38.03103 -487.534767) (xy 38.000085 -487.470508)
			(xy 37.976528 -487.403188) (xy 37.960658 -487.333653) (xy 37.952672 -487.262779) (xy 36.479608 -487.262779)
			(xy 36.479486 -487.273362) (xy 36.471468 -487.359891) (xy 36.4555 -487.445311) (xy 36.431719 -487.528893)
			(xy 36.400327 -487.609925) (xy 36.361593 -487.687714) (xy 36.315846 -487.761598) (xy 36.263477 -487.830945)
			(xy 36.204933 -487.895165) (xy 36.140713 -487.953709) (xy 36.071366 -488.006078) (xy 35.997482 -488.051825)
			(xy 35.919693 -488.090559) (xy 35.838661 -488.121951) (xy 35.755079 -488.145732) (xy 35.669659 -488.1617)
			(xy 35.58313 -488.169718) (xy 35.49623 -488.169718) (xy 35.409701 -488.1617) (xy 35.324281 -488.145732)
			(xy 35.240699 -488.121951) (xy 35.159667 -488.090559) (xy 35.081878 -488.051825) (xy 35.007994 -488.006078)
			(xy 34.938647 -487.953709) (xy 34.874427 -487.895165) (xy 34.815883 -487.830945) (xy 34.763514 -487.761598)
			(xy 34.717767 -487.687714) (xy 34.679033 -487.609925) (xy 34.647641 -487.528893) (xy 34.62386 -487.445311)
			(xy 34.607892 -487.359891) (xy 34.599874 -487.273362) (xy 31.399486 -487.273362) (xy 31.391468 -487.359891)
			(xy 31.3755 -487.445311) (xy 31.351719 -487.528893) (xy 31.320327 -487.609925) (xy 31.281593 -487.687714)
			(xy 31.235846 -487.761598) (xy 31.183477 -487.830945) (xy 31.124933 -487.895165) (xy 31.060713 -487.953709)
			(xy 30.991366 -488.006078) (xy 30.917482 -488.051825) (xy 30.839693 -488.090559) (xy 30.758661 -488.121951)
			(xy 30.675079 -488.145732) (xy 30.589659 -488.1617) (xy 30.50313 -488.169718) (xy 30.41623 -488.169718)
			(xy 30.329701 -488.1617) (xy 30.244281 -488.145732) (xy 30.160699 -488.121951) (xy 30.079667 -488.090559)
			(xy 30.001878 -488.051825) (xy 29.927994 -488.006078) (xy 29.858647 -487.953709) (xy 29.794427 -487.895165)
			(xy 29.735883 -487.830945) (xy 29.683514 -487.761598) (xy 29.637767 -487.687714) (xy 29.599033 -487.609925)
			(xy 29.567641 -487.528893) (xy 29.54386 -487.445311) (xy 29.527892 -487.359891) (xy 29.519874 -487.273362)
			(xy 16.49825 -487.273362) (xy 16.526001 -487.324442) (xy 16.580682 -487.441972) (xy 16.627952 -487.562675)
			(xy 16.667625 -487.686083) (xy 16.69955 -487.811719) (xy 16.723602 -487.939096) (xy 16.739689 -488.067722)
			(xy 16.747748 -488.1971) (xy 16.748252 -488.261914) (xy 16.747748 -488.326728) (xy 16.739689 -488.456106)
			(xy 16.723602 -488.584732) (xy 16.69955 -488.712109) (xy 16.667625 -488.837745) (xy 16.627952 -488.961153)
			(xy 16.580682 -489.081856) (xy 16.526001 -489.199386) (xy 16.464118 -489.31329) (xy 16.395273 -489.423126)
			(xy 16.319734 -489.528469) (xy 16.237791 -489.628912) (xy 16.149762 -489.724067) (xy 16.056201 -489.813362)
			(xy 29.519874 -489.813362) (xy 29.519874 -489.726462) (xy 29.527892 -489.639933) (xy 29.54386 -489.554513)
			(xy 29.567641 -489.470931) (xy 29.599033 -489.389899) (xy 29.637767 -489.31211) (xy 29.683514 -489.238226)
			(xy 29.735883 -489.168879) (xy 29.794427 -489.104659) (xy 29.858647 -489.046115) (xy 29.927994 -488.993746)
			(xy 30.001878 -488.947999) (xy 30.079667 -488.909265) (xy 30.160699 -488.877873) (xy 30.244281 -488.854092)
			(xy 30.329701 -488.838124) (xy 30.41623 -488.830106) (xy 30.50313 -488.830106) (xy 30.589659 -488.838124)
			(xy 30.675079 -488.854092) (xy 30.758661 -488.877873) (xy 30.839693 -488.909265) (xy 30.917482 -488.947999)
			(xy 30.991366 -488.993746) (xy 31.060713 -489.046115) (xy 31.124933 -489.104659) (xy 31.183477 -489.168879)
			(xy 31.235846 -489.238226) (xy 31.281593 -489.31211) (xy 31.320327 -489.389899) (xy 31.351719 -489.470931)
			(xy 31.3755 -489.554513) (xy 31.391468 -489.639933) (xy 31.399486 -489.726462) (xy 31.399988 -489.769912)
			(xy 31.399486 -489.813362) (xy 34.599874 -489.813362) (xy 34.599874 -489.726462) (xy 34.607892 -489.639933)
			(xy 34.62386 -489.554513) (xy 34.647641 -489.470931) (xy 34.679033 -489.389899) (xy 34.717767 -489.31211)
			(xy 34.763514 -489.238226) (xy 34.815883 -489.168879) (xy 34.874427 -489.104659) (xy 34.938647 -489.046115)
			(xy 35.007994 -488.993746) (xy 35.081878 -488.947999) (xy 35.159667 -488.909265) (xy 35.240699 -488.877873)
			(xy 35.324281 -488.854092) (xy 35.409701 -488.838124) (xy 35.49623 -488.830106) (xy 35.58313 -488.830106)
			(xy 35.669659 -488.838124) (xy 35.755079 -488.854092) (xy 35.838661 -488.877873) (xy 35.919693 -488.909265)
			(xy 35.997482 -488.947999) (xy 36.071366 -488.993746) (xy 36.140713 -489.046115) (xy 36.204933 -489.104659)
			(xy 36.263477 -489.168879) (xy 36.315846 -489.238226) (xy 36.361593 -489.31211) (xy 36.400327 -489.389899)
			(xy 36.431719 -489.470931) (xy 36.4555 -489.554513) (xy 36.471468 -489.639933) (xy 36.479486 -489.726462)
			(xy 36.479988 -489.769912) (xy 36.479486 -489.813362) (xy 36.471468 -489.899891) (xy 36.4555 -489.985311)
			(xy 36.431719 -490.068893) (xy 36.400327 -490.149925) (xy 36.361593 -490.227714) (xy 36.315846 -490.301598)
			(xy 36.263477 -490.370945) (xy 36.204933 -490.435165) (xy 36.140713 -490.493709) (xy 36.071366 -490.546078)
			(xy 35.997482 -490.591825) (xy 35.919693 -490.630559) (xy 35.838661 -490.661951) (xy 35.755079 -490.685732)
			(xy 35.669659 -490.7017) (xy 35.58313 -490.709718) (xy 35.49623 -490.709718) (xy 35.409701 -490.7017)
			(xy 35.324281 -490.685732) (xy 35.240699 -490.661951) (xy 35.159667 -490.630559) (xy 35.081878 -490.591825)
			(xy 35.007994 -490.546078) (xy 34.938647 -490.493709) (xy 34.874427 -490.435165) (xy 34.815883 -490.370945)
			(xy 34.763514 -490.301598) (xy 34.717767 -490.227714) (xy 34.679033 -490.149925) (xy 34.647641 -490.068893)
			(xy 34.62386 -489.985311) (xy 34.607892 -489.899891) (xy 34.599874 -489.813362) (xy 31.399486 -489.813362)
			(xy 31.391468 -489.899891) (xy 31.3755 -489.985311) (xy 31.351719 -490.068893) (xy 31.320327 -490.149925)
			(xy 31.281593 -490.227714) (xy 31.235846 -490.301598) (xy 31.183477 -490.370945) (xy 31.124933 -490.435165)
			(xy 31.060713 -490.493709) (xy 30.991366 -490.546078) (xy 30.917482 -490.591825) (xy 30.839693 -490.630559)
			(xy 30.758661 -490.661951) (xy 30.675079 -490.685732) (xy 30.589659 -490.7017) (xy 30.50313 -490.709718)
			(xy 30.41623 -490.709718) (xy 30.329701 -490.7017) (xy 30.244281 -490.685732) (xy 30.160699 -490.661951)
			(xy 30.079667 -490.630559) (xy 30.001878 -490.591825) (xy 29.927994 -490.546078) (xy 29.858647 -490.493709)
			(xy 29.794427 -490.435165) (xy 29.735883 -490.370945) (xy 29.683514 -490.301598) (xy 29.637767 -490.227714)
			(xy 29.599033 -490.149925) (xy 29.567641 -490.068893) (xy 29.54386 -489.985311) (xy 29.527892 -489.899891)
			(xy 29.519874 -489.813362) (xy 16.056201 -489.813362) (xy 16.055988 -489.813565) (xy 15.956831 -489.89706)
			(xy 15.852675 -489.974229) (xy 15.743923 -490.044773) (xy 15.630995 -490.10842) (xy 15.51433 -490.164923)
			(xy 15.394377 -490.214064) (xy 15.271601 -490.255652) (xy 15.146477 -490.289527) (xy 15.019489 -490.315557)
			(xy 14.891128 -490.333642) (xy 14.761892 -490.343712) (xy 14.632279 -490.345728) (xy 14.502792 -490.339682)
			(xy 14.373931 -490.325598) (xy 14.246195 -490.303529) (xy 14.120078 -490.273562) (xy 13.996068 -490.235813)
			(xy 13.874645 -490.190426) (xy 13.756278 -490.137579) (xy 13.641426 -490.077475) (xy 13.530533 -490.010347)
			(xy 13.424027 -489.936455) (xy 13.322321 -489.856084) (xy 13.225809 -489.769546) (xy 13.134864 -489.677174)
			(xy 13.049837 -489.579328) (xy 12.971057 -489.476385) (xy 12.89883 -489.368743) (xy 12.833435 -489.256819)
			(xy 12.775124 -489.141046) (xy 12.724124 -489.021872) (xy 12.680632 -488.899758) (xy 12.644815 -488.775175)
			(xy 12.616813 -488.648608) (xy 12.596734 -488.520544) (xy 12.584655 -488.39148) (xy 12.580624 -488.261914)
			(xy 5.31869 -488.261914) (xy 5.314669 -488.391308) (xy 5.302622 -488.520203) (xy 5.282595 -488.648101)
			(xy 5.254666 -488.774509) (xy 5.218942 -488.898939) (xy 5.175561 -489.02091) (xy 5.124691 -489.139953)
			(xy 5.066527 -489.255608) (xy 5.001295 -489.367428) (xy 4.929246 -489.474983) (xy 4.850658 -489.577856)
			(xy 4.765834 -489.675651) (xy 4.675102 -489.767991) (xy 4.578812 -489.85452) (xy 4.477334 -489.934902)
			(xy 4.371062 -490.008829) (xy 4.260405 -490.076016) (xy 4.14579 -490.136201) (xy 4.027658 -490.189155)
			(xy 3.906468 -490.234671) (xy 3.782684 -490.272575) (xy 3.656786 -490.30272) (xy 3.52926 -490.32499)
			(xy 3.400597 -490.339299) (xy 3.271293 -490.345592) (xy 3.141848 -490.343845) (xy 3.012762 -490.334063)
			(xy 2.884532 -490.316286) (xy 2.757653 -490.290581) (xy 2.632615 -490.257048) (xy 2.5099 -490.215816)
			(xy 2.389982 -490.167045) (xy 2.273323 -490.110922) (xy 2.160374 -490.047664) (xy 2.051571 -489.977515)
			(xy 1.947334 -489.900746) (xy 1.848064 -489.817653) (xy 1.754144 -489.728556) (xy 1.709674 -489.68152)
			(xy 1.693349 -489.664804) (xy 1.655769 -489.637051) (xy 1.613749 -489.616634) (xy 1.568705 -489.60424)
			(xy 1.522155 -489.600288) (xy 1.475666 -489.604911) (xy 1.430806 -489.617953) (xy 1.389085 -489.638974)
			(xy 1.351908 -489.667267) (xy 1.320529 -489.701877) (xy 1.296005 -489.74164) (xy 1.279161 -489.785216)
			(xy 1.270565 -489.831136) (xy 1.27 -489.854494) (xy 1.27 -492.353362) (xy 29.519874 -492.353362)
			(xy 29.519874 -492.266462) (xy 29.527892 -492.179933) (xy 29.54386 -492.094513) (xy 29.567641 -492.010931)
			(xy 29.599033 -491.929899) (xy 29.637767 -491.85211) (xy 29.683514 -491.778226) (xy 29.735883 -491.708879)
			(xy 29.794427 -491.644659) (xy 29.858647 -491.586115) (xy 29.927994 -491.533746) (xy 30.001878 -491.487999)
			(xy 30.079667 -491.449265) (xy 30.160699 -491.417873) (xy 30.244281 -491.394092) (xy 30.329701 -491.378124)
			(xy 30.41623 -491.370106) (xy 30.50313 -491.370106) (xy 30.589659 -491.378124) (xy 30.675079 -491.394092)
			(xy 30.758661 -491.417873) (xy 30.839693 -491.449265) (xy 30.917482 -491.487999) (xy 30.991366 -491.533746)
			(xy 31.060713 -491.586115) (xy 31.124933 -491.644659) (xy 31.183477 -491.708879) (xy 31.235846 -491.778226)
			(xy 31.281593 -491.85211) (xy 31.320327 -491.929899) (xy 31.351719 -492.010931) (xy 31.3755 -492.094513)
			(xy 31.391468 -492.179933) (xy 31.399486 -492.266462) (xy 31.399988 -492.309912) (xy 31.399486 -492.353362)
			(xy 34.599874 -492.353362) (xy 34.599874 -492.266462) (xy 34.607892 -492.179933) (xy 34.62386 -492.094513)
			(xy 34.647641 -492.010931) (xy 34.679033 -491.929899) (xy 34.717767 -491.85211) (xy 34.763514 -491.778226)
			(xy 34.815883 -491.708879) (xy 34.874427 -491.644659) (xy 34.938647 -491.586115) (xy 35.007994 -491.533746)
			(xy 35.081878 -491.487999) (xy 35.159667 -491.449265) (xy 35.240699 -491.417873) (xy 35.324281 -491.394092)
			(xy 35.409701 -491.378124) (xy 35.49623 -491.370106) (xy 35.58313 -491.370106) (xy 35.669659 -491.378124)
			(xy 35.755079 -491.394092) (xy 35.838661 -491.417873) (xy 35.919693 -491.449265) (xy 35.997482 -491.487999)
			(xy 36.071366 -491.533746) (xy 36.140713 -491.586115) (xy 36.204933 -491.644659) (xy 36.263477 -491.708879)
			(xy 36.315846 -491.778226) (xy 36.361593 -491.85211) (xy 36.400327 -491.929899) (xy 36.431719 -492.010931)
			(xy 36.4555 -492.094513) (xy 36.471468 -492.179933) (xy 36.479486 -492.266462) (xy 36.479988 -492.309912)
			(xy 36.479486 -492.353362) (xy 36.471468 -492.439891) (xy 36.4555 -492.525311) (xy 36.431719 -492.608893)
			(xy 36.400327 -492.689925) (xy 36.361593 -492.767714) (xy 36.315846 -492.841598) (xy 36.263477 -492.910945)
			(xy 36.204933 -492.975165) (xy 36.140713 -493.033709) (xy 36.071366 -493.086078) (xy 35.997482 -493.131825)
			(xy 35.919693 -493.170559) (xy 35.838661 -493.201951) (xy 35.755079 -493.225732) (xy 35.669659 -493.2417)
			(xy 35.58313 -493.249718) (xy 35.49623 -493.249718) (xy 35.409701 -493.2417) (xy 35.324281 -493.225732)
			(xy 35.240699 -493.201951) (xy 35.159667 -493.170559) (xy 35.081878 -493.131825) (xy 35.007994 -493.086078)
			(xy 34.938647 -493.033709) (xy 34.874427 -492.975165) (xy 34.815883 -492.910945) (xy 34.763514 -492.841598)
			(xy 34.717767 -492.767714) (xy 34.679033 -492.689925) (xy 34.647641 -492.608893) (xy 34.62386 -492.525311)
			(xy 34.607892 -492.439891) (xy 34.599874 -492.353362) (xy 31.399486 -492.353362) (xy 31.391468 -492.439891)
			(xy 31.3755 -492.525311) (xy 31.351719 -492.608893) (xy 31.320327 -492.689925) (xy 31.281593 -492.767714)
			(xy 31.235846 -492.841598) (xy 31.183477 -492.910945) (xy 31.124933 -492.975165) (xy 31.060713 -493.033709)
			(xy 30.991366 -493.086078) (xy 30.917482 -493.131825) (xy 30.839693 -493.170559) (xy 30.758661 -493.201951)
			(xy 30.675079 -493.225732) (xy 30.589659 -493.2417) (xy 30.50313 -493.249718) (xy 30.41623 -493.249718)
			(xy 30.329701 -493.2417) (xy 30.244281 -493.225732) (xy 30.160699 -493.201951) (xy 30.079667 -493.170559)
			(xy 30.001878 -493.131825) (xy 29.927994 -493.086078) (xy 29.858647 -493.033709) (xy 29.794427 -492.975165)
			(xy 29.735883 -492.910945) (xy 29.683514 -492.841598) (xy 29.637767 -492.767714) (xy 29.599033 -492.689925)
			(xy 29.567641 -492.608893) (xy 29.54386 -492.525311) (xy 29.527892 -492.439891) (xy 29.519874 -492.353362)
			(xy 1.27 -492.353362) (xy 1.27 -494.652469) (xy 3.67918 -494.652469) (xy 3.67918 -494.571359) (xy 3.68713 -494.49064)
			(xy 3.702953 -494.411089) (xy 3.726498 -494.333473) (xy 3.757537 -494.258537) (xy 3.795772 -494.187005)
			(xy 3.840834 -494.119565) (xy 3.892289 -494.056866) (xy 3.949642 -493.999513) (xy 4.012341 -493.948058)
			(xy 4.079781 -493.902996) (xy 4.151313 -493.864761) (xy 4.226249 -493.833722) (xy 4.303865 -493.810177)
			(xy 4.383416 -493.794354) (xy 4.464135 -493.786404) (xy 4.545245 -493.786404) (xy 4.625964 -493.794354)
			(xy 4.705515 -493.810177) (xy 4.783131 -493.833722) (xy 4.858067 -493.864761) (xy 4.929599 -493.902996)
			(xy 4.997039 -493.948058) (xy 5.059738 -493.999513) (xy 5.117091 -494.056866) (xy 5.168546 -494.119565)
			(xy 5.213608 -494.187005) (xy 5.251843 -494.258537) (xy 5.282882 -494.333473) (xy 5.306427 -494.411089)
			(xy 5.32225 -494.49064) (xy 5.3302 -494.571359) (xy 5.330698 -494.611914) (xy 5.3302 -494.652469)
			(xy 6.21918 -494.652469) (xy 6.21918 -494.571359) (xy 6.22713 -494.49064) (xy 6.242953 -494.411089)
			(xy 6.266498 -494.333473) (xy 6.297537 -494.258537) (xy 6.335772 -494.187005) (xy 6.380834 -494.119565)
			(xy 6.432289 -494.056866) (xy 6.489642 -493.999513) (xy 6.552341 -493.948058) (xy 6.619781 -493.902996)
			(xy 6.691313 -493.864761) (xy 6.766249 -493.833722) (xy 6.843865 -493.810177) (xy 6.923416 -493.794354)
			(xy 7.004135 -493.786404) (xy 7.085245 -493.786404) (xy 7.165964 -493.794354) (xy 7.245515 -493.810177)
			(xy 7.323131 -493.833722) (xy 7.398067 -493.864761) (xy 7.469599 -493.902996) (xy 7.537039 -493.948058)
			(xy 7.599738 -493.999513) (xy 7.657091 -494.056866) (xy 7.708546 -494.119565) (xy 7.753608 -494.187005)
			(xy 7.791843 -494.258537) (xy 7.822882 -494.333473) (xy 7.846427 -494.411089) (xy 7.86225 -494.49064)
			(xy 7.8702 -494.571359) (xy 7.870698 -494.611914) (xy 7.8702 -494.652469) (xy 8.75918 -494.652469)
			(xy 8.75918 -494.571359) (xy 8.76713 -494.49064) (xy 8.782953 -494.411089) (xy 8.806498 -494.333473)
			(xy 8.837537 -494.258537) (xy 8.875772 -494.187005) (xy 8.920834 -494.119565) (xy 8.972289 -494.056866)
			(xy 9.029642 -493.999513) (xy 9.092341 -493.948058) (xy 9.159781 -493.902996) (xy 9.231313 -493.864761)
			(xy 9.306249 -493.833722) (xy 9.383865 -493.810177) (xy 9.463416 -493.794354) (xy 9.544135 -493.786404)
			(xy 9.625245 -493.786404) (xy 9.705964 -493.794354) (xy 9.785515 -493.810177) (xy 9.863131 -493.833722)
			(xy 9.938067 -493.864761) (xy 10.009599 -493.902996) (xy 10.077039 -493.948058) (xy 10.139738 -493.999513)
			(xy 10.197091 -494.056866) (xy 10.248546 -494.119565) (xy 10.293608 -494.187005) (xy 10.331843 -494.258537)
			(xy 10.362882 -494.333473) (xy 10.386427 -494.411089) (xy 10.40225 -494.49064) (xy 10.4102 -494.571359)
			(xy 10.410698 -494.611914) (xy 10.4102 -494.652469) (xy 11.29918 -494.652469) (xy 11.29918 -494.571359)
			(xy 11.30713 -494.49064) (xy 11.322953 -494.411089) (xy 11.346498 -494.333473) (xy 11.377537 -494.258537)
			(xy 11.415772 -494.187005) (xy 11.460834 -494.119565) (xy 11.512289 -494.056866) (xy 11.569642 -493.999513)
			(xy 11.632341 -493.948058) (xy 11.699781 -493.902996) (xy 11.771313 -493.864761) (xy 11.846249 -493.833722)
			(xy 11.923865 -493.810177) (xy 12.003416 -493.794354) (xy 12.084135 -493.786404) (xy 12.165245 -493.786404)
			(xy 12.245964 -493.794354) (xy 12.325515 -493.810177) (xy 12.403131 -493.833722) (xy 12.478067 -493.864761)
			(xy 12.549599 -493.902996) (xy 12.617039 -493.948058) (xy 12.679738 -493.999513) (xy 12.737091 -494.056866)
			(xy 12.788546 -494.119565) (xy 12.833608 -494.187005) (xy 12.871843 -494.258537) (xy 12.902882 -494.333473)
			(xy 12.926427 -494.411089) (xy 12.94225 -494.49064) (xy 12.9502 -494.571359) (xy 12.950698 -494.611914)
			(xy 12.9502 -494.652469) (xy 12.94225 -494.733188) (xy 12.926427 -494.812739) (xy 12.902882 -494.890355)
			(xy 12.901636 -494.893362) (xy 29.519874 -494.893362) (xy 29.519874 -494.806462) (xy 29.527892 -494.719933)
			(xy 29.54386 -494.634513) (xy 29.567641 -494.550931) (xy 29.599033 -494.469899) (xy 29.637767 -494.39211)
			(xy 29.683514 -494.318226) (xy 29.735883 -494.248879) (xy 29.794427 -494.184659) (xy 29.858647 -494.126115)
			(xy 29.927994 -494.073746) (xy 30.001878 -494.027999) (xy 30.079667 -493.989265) (xy 30.160699 -493.957873)
			(xy 30.244281 -493.934092) (xy 30.329701 -493.918124) (xy 30.41623 -493.910106) (xy 30.50313 -493.910106)
			(xy 30.589659 -493.918124) (xy 30.675079 -493.934092) (xy 30.758661 -493.957873) (xy 30.839693 -493.989265)
			(xy 30.917482 -494.027999) (xy 30.991366 -494.073746) (xy 31.060713 -494.126115) (xy 31.124933 -494.184659)
			(xy 31.183477 -494.248879) (xy 31.235846 -494.318226) (xy 31.281593 -494.39211) (xy 31.320327 -494.469899)
			(xy 31.351719 -494.550931) (xy 31.3755 -494.634513) (xy 31.391468 -494.719933) (xy 31.399486 -494.806462)
			(xy 31.399988 -494.849912) (xy 31.399486 -494.893362) (xy 34.599874 -494.893362) (xy 34.599874 -494.806462)
			(xy 34.607892 -494.719933) (xy 34.62386 -494.634513) (xy 34.647641 -494.550931) (xy 34.679033 -494.469899)
			(xy 34.717767 -494.39211) (xy 34.763514 -494.318226) (xy 34.815883 -494.248879) (xy 34.874427 -494.184659)
			(xy 34.938647 -494.126115) (xy 35.007994 -494.073746) (xy 35.081878 -494.027999) (xy 35.159667 -493.989265)
			(xy 35.240699 -493.957873) (xy 35.324281 -493.934092) (xy 35.409701 -493.918124) (xy 35.49623 -493.910106)
			(xy 35.58313 -493.910106) (xy 35.669659 -493.918124) (xy 35.755079 -493.934092) (xy 35.838661 -493.957873)
			(xy 35.919693 -493.989265) (xy 35.997482 -494.027999) (xy 36.071366 -494.073746) (xy 36.140713 -494.126115)
			(xy 36.204933 -494.184659) (xy 36.263477 -494.248879) (xy 36.315846 -494.318226) (xy 36.361593 -494.39211)
			(xy 36.400327 -494.469899) (xy 36.431719 -494.550931) (xy 36.4555 -494.634513) (xy 36.471468 -494.719933)
			(xy 36.479486 -494.806462) (xy 36.479988 -494.849912) (xy 36.479486 -494.893362) (xy 36.471468 -494.979891)
			(xy 36.4555 -495.065311) (xy 36.431719 -495.148893) (xy 36.400327 -495.229925) (xy 36.361593 -495.307714)
			(xy 36.315846 -495.381598) (xy 36.263477 -495.450945) (xy 36.204933 -495.515165) (xy 36.140713 -495.573709)
			(xy 36.071366 -495.626078) (xy 35.997482 -495.671825) (xy 35.919693 -495.710559) (xy 35.838661 -495.741951)
			(xy 35.755079 -495.765732) (xy 35.669659 -495.7817) (xy 35.58313 -495.789718) (xy 35.49623 -495.789718)
			(xy 35.409701 -495.7817) (xy 35.324281 -495.765732) (xy 35.240699 -495.741951) (xy 35.159667 -495.710559)
			(xy 35.081878 -495.671825) (xy 35.007994 -495.626078) (xy 34.938647 -495.573709) (xy 34.874427 -495.515165)
			(xy 34.815883 -495.450945) (xy 34.763514 -495.381598) (xy 34.717767 -495.307714) (xy 34.679033 -495.229925)
			(xy 34.647641 -495.148893) (xy 34.62386 -495.065311) (xy 34.607892 -494.979891) (xy 34.599874 -494.893362)
			(xy 31.399486 -494.893362) (xy 31.391468 -494.979891) (xy 31.3755 -495.065311) (xy 31.351719 -495.148893)
			(xy 31.320327 -495.229925) (xy 31.281593 -495.307714) (xy 31.235846 -495.381598) (xy 31.183477 -495.450945)
			(xy 31.124933 -495.515165) (xy 31.060713 -495.573709) (xy 30.991366 -495.626078) (xy 30.917482 -495.671825)
			(xy 30.839693 -495.710559) (xy 30.758661 -495.741951) (xy 30.675079 -495.765732) (xy 30.589659 -495.7817)
			(xy 30.50313 -495.789718) (xy 30.41623 -495.789718) (xy 30.329701 -495.7817) (xy 30.244281 -495.765732)
			(xy 30.160699 -495.741951) (xy 30.079667 -495.710559) (xy 30.001878 -495.671825) (xy 29.927994 -495.626078)
			(xy 29.858647 -495.573709) (xy 29.794427 -495.515165) (xy 29.735883 -495.450945) (xy 29.683514 -495.381598)
			(xy 29.637767 -495.307714) (xy 29.599033 -495.229925) (xy 29.567641 -495.148893) (xy 29.54386 -495.065311)
			(xy 29.527892 -494.979891) (xy 29.519874 -494.893362) (xy 12.901636 -494.893362) (xy 12.871843 -494.965291)
			(xy 12.833608 -495.036823) (xy 12.788546 -495.104263) (xy 12.737091 -495.166962) (xy 12.679738 -495.224315)
			(xy 12.617039 -495.27577) (xy 12.549599 -495.320832) (xy 12.478067 -495.359067) (xy 12.403131 -495.390106)
			(xy 12.325515 -495.413651) (xy 12.245964 -495.429474) (xy 12.165245 -495.437424) (xy 12.084135 -495.437424)
			(xy 12.003416 -495.429474) (xy 11.923865 -495.413651) (xy 11.846249 -495.390106) (xy 11.771313 -495.359067)
			(xy 11.699781 -495.320832) (xy 11.632341 -495.27577) (xy 11.569642 -495.224315) (xy 11.512289 -495.166962)
			(xy 11.460834 -495.104263) (xy 11.415772 -495.036823) (xy 11.377537 -494.965291) (xy 11.346498 -494.890355)
			(xy 11.322953 -494.812739) (xy 11.30713 -494.733188) (xy 11.29918 -494.652469) (xy 10.4102 -494.652469)
			(xy 10.40225 -494.733188) (xy 10.386427 -494.812739) (xy 10.362882 -494.890355) (xy 10.331843 -494.965291)
			(xy 10.293608 -495.036823) (xy 10.248546 -495.104263) (xy 10.197091 -495.166962) (xy 10.139738 -495.224315)
			(xy 10.077039 -495.27577) (xy 10.009599 -495.320832) (xy 9.938067 -495.359067) (xy 9.863131 -495.390106)
			(xy 9.785515 -495.413651) (xy 9.705964 -495.429474) (xy 9.625245 -495.437424) (xy 9.544135 -495.437424)
			(xy 9.463416 -495.429474) (xy 9.383865 -495.413651) (xy 9.306249 -495.390106) (xy 9.231313 -495.359067)
			(xy 9.159781 -495.320832) (xy 9.092341 -495.27577) (xy 9.029642 -495.224315) (xy 8.972289 -495.166962)
			(xy 8.920834 -495.104263) (xy 8.875772 -495.036823) (xy 8.837537 -494.965291) (xy 8.806498 -494.890355)
			(xy 8.782953 -494.812739) (xy 8.76713 -494.733188) (xy 8.75918 -494.652469) (xy 7.8702 -494.652469)
			(xy 7.86225 -494.733188) (xy 7.846427 -494.812739) (xy 7.822882 -494.890355) (xy 7.791843 -494.965291)
			(xy 7.753608 -495.036823) (xy 7.708546 -495.104263) (xy 7.657091 -495.166962) (xy 7.599738 -495.224315)
			(xy 7.537039 -495.27577) (xy 7.469599 -495.320832) (xy 7.398067 -495.359067) (xy 7.323131 -495.390106)
			(xy 7.245515 -495.413651) (xy 7.165964 -495.429474) (xy 7.085245 -495.437424) (xy 7.004135 -495.437424)
			(xy 6.923416 -495.429474) (xy 6.843865 -495.413651) (xy 6.766249 -495.390106) (xy 6.691313 -495.359067)
			(xy 6.619781 -495.320832) (xy 6.552341 -495.27577) (xy 6.489642 -495.224315) (xy 6.432289 -495.166962)
			(xy 6.380834 -495.104263) (xy 6.335772 -495.036823) (xy 6.297537 -494.965291) (xy 6.266498 -494.890355)
			(xy 6.242953 -494.812739) (xy 6.22713 -494.733188) (xy 6.21918 -494.652469) (xy 5.3302 -494.652469)
			(xy 5.32225 -494.733188) (xy 5.306427 -494.812739) (xy 5.282882 -494.890355) (xy 5.251843 -494.965291)
			(xy 5.213608 -495.036823) (xy 5.168546 -495.104263) (xy 5.117091 -495.166962) (xy 5.059738 -495.224315)
			(xy 4.997039 -495.27577) (xy 4.929599 -495.320832) (xy 4.858067 -495.359067) (xy 4.783131 -495.390106)
			(xy 4.705515 -495.413651) (xy 4.625964 -495.429474) (xy 4.545245 -495.437424) (xy 4.464135 -495.437424)
			(xy 4.383416 -495.429474) (xy 4.303865 -495.413651) (xy 4.226249 -495.390106) (xy 4.151313 -495.359067)
			(xy 4.079781 -495.320832) (xy 4.012341 -495.27577) (xy 3.949642 -495.224315) (xy 3.892289 -495.166962)
			(xy 3.840834 -495.104263) (xy 3.795772 -495.036823) (xy 3.757537 -494.965291) (xy 3.726498 -494.890355)
			(xy 3.702953 -494.812739) (xy 3.68713 -494.733188) (xy 3.67918 -494.652469) (xy 1.27 -494.652469)
			(xy 1.27 -495.86007) (xy 39.818063 -495.86007) (xy 39.82207 -495.744046) (xy 39.834072 -495.628574)
			(xy 39.854012 -495.514206) (xy 39.881795 -495.401486) (xy 39.917289 -495.290952) (xy 39.960324 -495.183129)
			(xy 40.010695 -495.078532) (xy 40.068162 -494.97766) (xy 40.132452 -494.880993) (xy 40.203257 -494.788992)
			(xy 40.280241 -494.702095) (xy 40.363037 -494.620716) (xy 40.45125 -494.545243) (xy 40.54446 -494.476036)
			(xy 40.642223 -494.413424) (xy 40.744072 -494.357707) (xy 40.849522 -494.309149) (xy 40.958071 -494.267981)
			(xy 41.069202 -494.234401) (xy 41.182385 -494.208568) (xy 41.29708 -494.190605) (xy 41.412742 -494.180597)
			(xy 41.528818 -494.178594) (xy 41.644756 -494.184603) (xy 41.760003 -494.198596) (xy 41.874009 -494.220507)
			(xy 41.986233 -494.250232) (xy 42.096139 -494.287628) (xy 42.203202 -494.332517) (xy 42.306914 -494.384686)
			(xy 42.406779 -494.443886) (xy 42.502322 -494.509835) (xy 42.502604 -494.51006) (xy 43.327577 -494.51006)
			(xy 43.331612 -494.434356) (xy 43.343671 -494.359511) (xy 43.363617 -494.28637) (xy 43.391224 -494.215765)
			(xy 43.42618 -494.148494) (xy 43.468088 -494.085319) (xy 43.516474 -494.026957) (xy 43.57079 -493.974069)
			(xy 43.630419 -493.927254) (xy 43.694687 -493.887042) (xy 43.762864 -493.85389) (xy 43.83418 -493.828172)
			(xy 43.907825 -493.81018) (xy 43.982965 -493.800118) (xy 44.058749 -493.798099) (xy 44.134319 -493.804148)
			(xy 44.208817 -493.818195) (xy 44.2814 -493.840081) (xy 44.351246 -493.869558) (xy 44.417563 -493.906293)
			(xy 44.479599 -493.949868) (xy 44.536652 -493.99979) (xy 44.588076 -494.055494) (xy 44.633287 -494.116349)
			(xy 44.671774 -494.181664) (xy 44.7031 -494.2507) (xy 44.72691 -494.322675) (xy 44.742935 -494.396773)
			(xy 44.750994 -494.472154) (xy 44.751498 -494.51006) (xy 45.867577 -494.51006) (xy 45.871612 -494.434356)
			(xy 45.883671 -494.359511) (xy 45.903617 -494.28637) (xy 45.931224 -494.215765) (xy 45.96618 -494.148494)
			(xy 46.008088 -494.085319) (xy 46.056474 -494.026957) (xy 46.11079 -493.974069) (xy 46.170419 -493.927254)
			(xy 46.234687 -493.887042) (xy 46.302864 -493.85389) (xy 46.37418 -493.828172) (xy 46.447825 -493.81018)
			(xy 46.522965 -493.800118) (xy 46.598749 -493.798099) (xy 46.674319 -493.804148) (xy 46.748817 -493.818195)
			(xy 46.8214 -493.840081) (xy 46.891246 -493.869558) (xy 46.957563 -493.906293) (xy 47.019599 -493.949868)
			(xy 47.076652 -493.99979) (xy 47.128076 -494.055494) (xy 47.173287 -494.116349) (xy 47.211774 -494.181664)
			(xy 47.2431 -494.2507) (xy 47.26691 -494.322675) (xy 47.282935 -494.396773) (xy 47.290994 -494.472154)
			(xy 47.291498 -494.51006) (xy 48.407577 -494.51006) (xy 48.411612 -494.434356) (xy 48.423671 -494.359511)
			(xy 48.443617 -494.28637) (xy 48.471224 -494.215765) (xy 48.50618 -494.148494) (xy 48.548088 -494.085319)
			(xy 48.596474 -494.026957) (xy 48.65079 -493.974069) (xy 48.710419 -493.927254) (xy 48.774687 -493.887042)
			(xy 48.842864 -493.85389) (xy 48.91418 -493.828172) (xy 48.987825 -493.81018) (xy 49.062965 -493.800118)
			(xy 49.138749 -493.798099) (xy 49.214319 -493.804148) (xy 49.288817 -493.818195) (xy 49.3614 -493.840081)
			(xy 49.431246 -493.869558) (xy 49.497563 -493.906293) (xy 49.559599 -493.949868) (xy 49.616652 -493.99979)
			(xy 49.668076 -494.055494) (xy 49.713287 -494.116349) (xy 49.751774 -494.181664) (xy 49.7831 -494.2507)
			(xy 49.80691 -494.322675) (xy 49.822935 -494.396773) (xy 49.830994 -494.472154) (xy 49.831498 -494.51006)
			(xy 50.947577 -494.51006) (xy 50.951612 -494.434356) (xy 50.963671 -494.359511) (xy 50.983617 -494.28637)
			(xy 51.011224 -494.215765) (xy 51.04618 -494.148494) (xy 51.088088 -494.085319) (xy 51.136474 -494.026957)
			(xy 51.19079 -493.974069) (xy 51.250419 -493.927254) (xy 51.314687 -493.887042) (xy 51.382864 -493.85389)
			(xy 51.45418 -493.828172) (xy 51.527825 -493.81018) (xy 51.602965 -493.800118) (xy 51.678749 -493.798099)
			(xy 51.754319 -493.804148) (xy 51.828817 -493.818195) (xy 51.9014 -493.840081) (xy 51.971246 -493.869558)
			(xy 52.037563 -493.906293) (xy 52.099599 -493.949868) (xy 52.156652 -493.99979) (xy 52.208076 -494.055494)
			(xy 52.253287 -494.116349) (xy 52.291774 -494.181664) (xy 52.3231 -494.2507) (xy 52.34691 -494.322675)
			(xy 52.362935 -494.396773) (xy 52.370994 -494.472154) (xy 52.371498 -494.51006) (xy 53.487577 -494.51006)
			(xy 53.491612 -494.434356) (xy 53.503671 -494.359511) (xy 53.523617 -494.28637) (xy 53.551224 -494.215765)
			(xy 53.58618 -494.148494) (xy 53.628088 -494.085319) (xy 53.676474 -494.026957) (xy 53.73079 -493.974069)
			(xy 53.790419 -493.927254) (xy 53.854687 -493.887042) (xy 53.922864 -493.85389) (xy 53.99418 -493.828172)
			(xy 54.067825 -493.81018) (xy 54.142965 -493.800118) (xy 54.218749 -493.798099) (xy 54.294319 -493.804148)
			(xy 54.368817 -493.818195) (xy 54.4414 -493.840081) (xy 54.511246 -493.869558) (xy 54.577563 -493.906293)
			(xy 54.639599 -493.949868) (xy 54.696652 -493.99979) (xy 54.748076 -494.055494) (xy 54.793287 -494.116349)
			(xy 54.831774 -494.181664) (xy 54.8631 -494.2507) (xy 54.88691 -494.322675) (xy 54.902935 -494.396773)
			(xy 54.910994 -494.472154) (xy 54.911498 -494.51006) (xy 56.027577 -494.51006) (xy 56.031612 -494.434356)
			(xy 56.043671 -494.359511) (xy 56.063617 -494.28637) (xy 56.091224 -494.215765) (xy 56.12618 -494.148494)
			(xy 56.168088 -494.085319) (xy 56.216474 -494.026957) (xy 56.27079 -493.974069) (xy 56.330419 -493.927254)
			(xy 56.394687 -493.887042) (xy 56.462864 -493.85389) (xy 56.53418 -493.828172) (xy 56.607825 -493.81018)
			(xy 56.682965 -493.800118) (xy 56.758749 -493.798099) (xy 56.834319 -493.804148) (xy 56.908817 -493.818195)
			(xy 56.9814 -493.840081) (xy 57.051246 -493.869558) (xy 57.117563 -493.906293) (xy 57.179599 -493.949868)
			(xy 57.236652 -493.99979) (xy 57.288076 -494.055494) (xy 57.333287 -494.116349) (xy 57.371774 -494.181664)
			(xy 57.4031 -494.2507) (xy 57.42691 -494.322675) (xy 57.442935 -494.396773) (xy 57.450994 -494.472154)
			(xy 57.451498 -494.51006) (xy 58.567577 -494.51006) (xy 58.571612 -494.434356) (xy 58.583671 -494.359511)
			(xy 58.603617 -494.28637) (xy 58.631224 -494.215765) (xy 58.66618 -494.148494) (xy 58.708088 -494.085319)
			(xy 58.756474 -494.026957) (xy 58.81079 -493.974069) (xy 58.870419 -493.927254) (xy 58.934687 -493.887042)
			(xy 59.002864 -493.85389) (xy 59.07418 -493.828172) (xy 59.147825 -493.81018) (xy 59.222965 -493.800118)
			(xy 59.298749 -493.798099) (xy 59.374319 -493.804148) (xy 59.448817 -493.818195) (xy 59.5214 -493.840081)
			(xy 59.591246 -493.869558) (xy 59.657563 -493.906293) (xy 59.719599 -493.949868) (xy 59.776652 -493.99979)
			(xy 59.828076 -494.055494) (xy 59.873287 -494.116349) (xy 59.911774 -494.181664) (xy 59.9431 -494.2507)
			(xy 59.96691 -494.322675) (xy 59.982935 -494.396773) (xy 59.990994 -494.472154) (xy 59.991498 -494.51006)
			(xy 61.107577 -494.51006) (xy 61.111612 -494.434356) (xy 61.123671 -494.359511) (xy 61.143617 -494.28637)
			(xy 61.171224 -494.215765) (xy 61.20618 -494.148494) (xy 61.248088 -494.085319) (xy 61.296474 -494.026957)
			(xy 61.35079 -493.974069) (xy 61.410419 -493.927254) (xy 61.474687 -493.887042) (xy 61.542864 -493.85389)
			(xy 61.61418 -493.828172) (xy 61.687825 -493.81018) (xy 61.762965 -493.800118) (xy 61.838749 -493.798099)
			(xy 61.914319 -493.804148) (xy 61.988817 -493.818195) (xy 62.0614 -493.840081) (xy 62.131246 -493.869558)
			(xy 62.197563 -493.906293) (xy 62.259599 -493.949868) (xy 62.316652 -493.99979) (xy 62.368076 -494.055494)
			(xy 62.413287 -494.116349) (xy 62.451774 -494.181664) (xy 62.4831 -494.2507) (xy 62.50691 -494.322675)
			(xy 62.522935 -494.396773) (xy 62.530994 -494.472154) (xy 62.531498 -494.51006) (xy 62.530994 -494.547966)
			(xy 62.522935 -494.623347) (xy 62.50691 -494.697445) (xy 62.4831 -494.76942) (xy 62.451774 -494.838456)
			(xy 62.413287 -494.903771) (xy 62.368076 -494.964626) (xy 62.316652 -495.02033) (xy 62.259599 -495.070252)
			(xy 62.197563 -495.113827) (xy 62.131246 -495.150562) (xy 62.0614 -495.180039) (xy 61.988817 -495.201925)
			(xy 61.914319 -495.215972) (xy 61.838749 -495.222021) (xy 61.762965 -495.220002) (xy 61.687825 -495.20994)
			(xy 61.61418 -495.191948) (xy 61.542864 -495.16623) (xy 61.474687 -495.133078) (xy 61.410419 -495.092866)
			(xy 61.35079 -495.046051) (xy 61.296474 -494.993163) (xy 61.248088 -494.934801) (xy 61.20618 -494.871626)
			(xy 61.171224 -494.804355) (xy 61.143617 -494.73375) (xy 61.123671 -494.660609) (xy 61.111612 -494.585764)
			(xy 61.107577 -494.51006) (xy 59.991498 -494.51006) (xy 59.990994 -494.547966) (xy 59.982935 -494.623347)
			(xy 59.96691 -494.697445) (xy 59.9431 -494.76942) (xy 59.911774 -494.838456) (xy 59.873287 -494.903771)
			(xy 59.828076 -494.964626) (xy 59.776652 -495.02033) (xy 59.719599 -495.070252) (xy 59.657563 -495.113827)
			(xy 59.591246 -495.150562) (xy 59.5214 -495.180039) (xy 59.448817 -495.201925) (xy 59.374319 -495.215972)
			(xy 59.298749 -495.222021) (xy 59.222965 -495.220002) (xy 59.147825 -495.20994) (xy 59.07418 -495.191948)
			(xy 59.002864 -495.16623) (xy 58.934687 -495.133078) (xy 58.870419 -495.092866) (xy 58.81079 -495.046051)
			(xy 58.756474 -494.993163) (xy 58.708088 -494.934801) (xy 58.66618 -494.871626) (xy 58.631224 -494.804355)
			(xy 58.603617 -494.73375) (xy 58.583671 -494.660609) (xy 58.571612 -494.585764) (xy 58.567577 -494.51006)
			(xy 57.451498 -494.51006) (xy 57.450994 -494.547966) (xy 57.442935 -494.623347) (xy 57.42691 -494.697445)
			(xy 57.4031 -494.76942) (xy 57.371774 -494.838456) (xy 57.333287 -494.903771) (xy 57.288076 -494.964626)
			(xy 57.236652 -495.02033) (xy 57.179599 -495.070252) (xy 57.117563 -495.113827) (xy 57.051246 -495.150562)
			(xy 56.9814 -495.180039) (xy 56.908817 -495.201925) (xy 56.834319 -495.215972) (xy 56.758749 -495.222021)
			(xy 56.682965 -495.220002) (xy 56.607825 -495.20994) (xy 56.53418 -495.191948) (xy 56.462864 -495.16623)
			(xy 56.394687 -495.133078) (xy 56.330419 -495.092866) (xy 56.27079 -495.046051) (xy 56.216474 -494.993163)
			(xy 56.168088 -494.934801) (xy 56.12618 -494.871626) (xy 56.091224 -494.804355) (xy 56.063617 -494.73375)
			(xy 56.043671 -494.660609) (xy 56.031612 -494.585764) (xy 56.027577 -494.51006) (xy 54.911498 -494.51006)
			(xy 54.910994 -494.547966) (xy 54.902935 -494.623347) (xy 54.88691 -494.697445) (xy 54.8631 -494.76942)
			(xy 54.831774 -494.838456) (xy 54.793287 -494.903771) (xy 54.748076 -494.964626) (xy 54.696652 -495.02033)
			(xy 54.639599 -495.070252) (xy 54.577563 -495.113827) (xy 54.511246 -495.150562) (xy 54.4414 -495.180039)
			(xy 54.368817 -495.201925) (xy 54.294319 -495.215972) (xy 54.218749 -495.222021) (xy 54.142965 -495.220002)
			(xy 54.067825 -495.20994) (xy 53.99418 -495.191948) (xy 53.922864 -495.16623) (xy 53.854687 -495.133078)
			(xy 53.790419 -495.092866) (xy 53.73079 -495.046051) (xy 53.676474 -494.993163) (xy 53.628088 -494.934801)
			(xy 53.58618 -494.871626) (xy 53.551224 -494.804355) (xy 53.523617 -494.73375) (xy 53.503671 -494.660609)
			(xy 53.491612 -494.585764) (xy 53.487577 -494.51006) (xy 52.371498 -494.51006) (xy 52.370994 -494.547966)
			(xy 52.362935 -494.623347) (xy 52.34691 -494.697445) (xy 52.3231 -494.76942) (xy 52.291774 -494.838456)
			(xy 52.253287 -494.903771) (xy 52.208076 -494.964626) (xy 52.156652 -495.02033) (xy 52.099599 -495.070252)
			(xy 52.037563 -495.113827) (xy 51.971246 -495.150562) (xy 51.9014 -495.180039) (xy 51.828817 -495.201925)
			(xy 51.754319 -495.215972) (xy 51.678749 -495.222021) (xy 51.602965 -495.220002) (xy 51.527825 -495.20994)
			(xy 51.45418 -495.191948) (xy 51.382864 -495.16623) (xy 51.314687 -495.133078) (xy 51.250419 -495.092866)
			(xy 51.19079 -495.046051) (xy 51.136474 -494.993163) (xy 51.088088 -494.934801) (xy 51.04618 -494.871626)
			(xy 51.011224 -494.804355) (xy 50.983617 -494.73375) (xy 50.963671 -494.660609) (xy 50.951612 -494.585764)
			(xy 50.947577 -494.51006) (xy 49.831498 -494.51006) (xy 49.830994 -494.547966) (xy 49.822935 -494.623347)
			(xy 49.80691 -494.697445) (xy 49.7831 -494.76942) (xy 49.751774 -494.838456) (xy 49.713287 -494.903771)
			(xy 49.668076 -494.964626) (xy 49.616652 -495.02033) (xy 49.559599 -495.070252) (xy 49.497563 -495.113827)
			(xy 49.431246 -495.150562) (xy 49.3614 -495.180039) (xy 49.288817 -495.201925) (xy 49.214319 -495.215972)
			(xy 49.138749 -495.222021) (xy 49.062965 -495.220002) (xy 48.987825 -495.20994) (xy 48.91418 -495.191948)
			(xy 48.842864 -495.16623) (xy 48.774687 -495.133078) (xy 48.710419 -495.092866) (xy 48.65079 -495.046051)
			(xy 48.596474 -494.993163) (xy 48.548088 -494.934801) (xy 48.50618 -494.871626) (xy 48.471224 -494.804355)
			(xy 48.443617 -494.73375) (xy 48.423671 -494.660609) (xy 48.411612 -494.585764) (xy 48.407577 -494.51006)
			(xy 47.291498 -494.51006) (xy 47.290994 -494.547966) (xy 47.282935 -494.623347) (xy 47.26691 -494.697445)
			(xy 47.2431 -494.76942) (xy 47.211774 -494.838456) (xy 47.173287 -494.903771) (xy 47.128076 -494.964626)
			(xy 47.076652 -495.02033) (xy 47.019599 -495.070252) (xy 46.957563 -495.113827) (xy 46.891246 -495.150562)
			(xy 46.8214 -495.180039) (xy 46.748817 -495.201925) (xy 46.674319 -495.215972) (xy 46.598749 -495.222021)
			(xy 46.522965 -495.220002) (xy 46.447825 -495.20994) (xy 46.37418 -495.191948) (xy 46.302864 -495.16623)
			(xy 46.234687 -495.133078) (xy 46.170419 -495.092866) (xy 46.11079 -495.046051) (xy 46.056474 -494.993163)
			(xy 46.008088 -494.934801) (xy 45.96618 -494.871626) (xy 45.931224 -494.804355) (xy 45.903617 -494.73375)
			(xy 45.883671 -494.660609) (xy 45.871612 -494.585764) (xy 45.867577 -494.51006) (xy 44.751498 -494.51006)
			(xy 44.750994 -494.547966) (xy 44.742935 -494.623347) (xy 44.72691 -494.697445) (xy 44.7031 -494.76942)
			(xy 44.671774 -494.838456) (xy 44.633287 -494.903771) (xy 44.588076 -494.964626) (xy 44.536652 -495.02033)
			(xy 44.479599 -495.070252) (xy 44.417563 -495.113827) (xy 44.351246 -495.150562) (xy 44.2814 -495.180039)
			(xy 44.208817 -495.201925) (xy 44.134319 -495.215972) (xy 44.058749 -495.222021) (xy 43.982965 -495.220002)
			(xy 43.907825 -495.20994) (xy 43.83418 -495.191948) (xy 43.762864 -495.16623) (xy 43.694687 -495.133078)
			(xy 43.630419 -495.092866) (xy 43.57079 -495.046051) (xy 43.516474 -494.993163) (xy 43.468088 -494.934801)
			(xy 43.42618 -494.871626) (xy 43.391224 -494.804355) (xy 43.363617 -494.73375) (xy 43.343671 -494.660609)
			(xy 43.331612 -494.585764) (xy 43.327577 -494.51006) (xy 42.502604 -494.51006) (xy 42.593088 -494.582218)
			(xy 42.678643 -494.660691) (xy 42.758581 -494.744879) (xy 42.83252 -494.834381) (xy 42.900108 -494.928772)
			(xy 42.961022 -495.0276) (xy 43.014974 -495.130396) (xy 43.061704 -495.236669) (xy 43.100992 -495.345913)
			(xy 43.132649 -495.457606) (xy 43.156525 -495.571218) (xy 43.172506 -495.686206) (xy 43.180515 -495.802023)
			(xy 43.181016 -495.86007) (xy 43.180515 -495.918117) (xy 43.172506 -496.033934) (xy 43.156525 -496.148922)
			(xy 43.132649 -496.262534) (xy 43.100992 -496.374227) (xy 43.061704 -496.483471) (xy 43.014974 -496.589744)
			(xy 42.961022 -496.69254) (xy 42.900108 -496.791368) (xy 42.83252 -496.885759) (xy 42.758581 -496.975261)
			(xy 42.678643 -497.059449) (xy 42.593088 -497.137922) (xy 42.502604 -497.21008) (xy 43.327577 -497.21008)
			(xy 43.331612 -497.134376) (xy 43.343671 -497.059531) (xy 43.363617 -496.98639) (xy 43.391224 -496.915785)
			(xy 43.42618 -496.848514) (xy 43.468088 -496.785339) (xy 43.516474 -496.726977) (xy 43.57079 -496.674089)
			(xy 43.630419 -496.627274) (xy 43.694687 -496.587062) (xy 43.762864 -496.55391) (xy 43.83418 -496.528192)
			(xy 43.907825 -496.5102) (xy 43.982965 -496.500138) (xy 44.058749 -496.498119) (xy 44.134319 -496.504168)
			(xy 44.208817 -496.518215) (xy 44.2814 -496.540101) (xy 44.351246 -496.569578) (xy 44.417563 -496.606313)
			(xy 44.479599 -496.649888) (xy 44.536652 -496.69981) (xy 44.588076 -496.755514) (xy 44.633287 -496.816369)
			(xy 44.671774 -496.881684) (xy 44.7031 -496.95072) (xy 44.72691 -497.022695) (xy 44.742935 -497.096793)
			(xy 44.750994 -497.172174) (xy 44.751498 -497.21008) (xy 45.867577 -497.21008) (xy 45.871612 -497.134376)
			(xy 45.883671 -497.059531) (xy 45.903617 -496.98639) (xy 45.931224 -496.915785) (xy 45.96618 -496.848514)
			(xy 46.008088 -496.785339) (xy 46.056474 -496.726977) (xy 46.11079 -496.674089) (xy 46.170419 -496.627274)
			(xy 46.234687 -496.587062) (xy 46.302864 -496.55391) (xy 46.37418 -496.528192) (xy 46.447825 -496.5102)
			(xy 46.522965 -496.500138) (xy 46.598749 -496.498119) (xy 46.674319 -496.504168) (xy 46.748817 -496.518215)
			(xy 46.8214 -496.540101) (xy 46.891246 -496.569578) (xy 46.957563 -496.606313) (xy 47.019599 -496.649888)
			(xy 47.076652 -496.69981) (xy 47.128076 -496.755514) (xy 47.173287 -496.816369) (xy 47.211774 -496.881684)
			(xy 47.2431 -496.95072) (xy 47.26691 -497.022695) (xy 47.282935 -497.096793) (xy 47.290994 -497.172174)
			(xy 47.291498 -497.21008) (xy 48.407577 -497.21008) (xy 48.411612 -497.134376) (xy 48.423671 -497.059531)
			(xy 48.443617 -496.98639) (xy 48.471224 -496.915785) (xy 48.50618 -496.848514) (xy 48.548088 -496.785339)
			(xy 48.596474 -496.726977) (xy 48.65079 -496.674089) (xy 48.710419 -496.627274) (xy 48.774687 -496.587062)
			(xy 48.842864 -496.55391) (xy 48.91418 -496.528192) (xy 48.987825 -496.5102) (xy 49.062965 -496.500138)
			(xy 49.138749 -496.498119) (xy 49.214319 -496.504168) (xy 49.288817 -496.518215) (xy 49.3614 -496.540101)
			(xy 49.431246 -496.569578) (xy 49.497563 -496.606313) (xy 49.559599 -496.649888) (xy 49.616652 -496.69981)
			(xy 49.668076 -496.755514) (xy 49.713287 -496.816369) (xy 49.751774 -496.881684) (xy 49.7831 -496.95072)
			(xy 49.80691 -497.022695) (xy 49.822935 -497.096793) (xy 49.830994 -497.172174) (xy 49.831498 -497.21008)
			(xy 50.947577 -497.21008) (xy 50.951612 -497.134376) (xy 50.963671 -497.059531) (xy 50.983617 -496.98639)
			(xy 51.011224 -496.915785) (xy 51.04618 -496.848514) (xy 51.088088 -496.785339) (xy 51.136474 -496.726977)
			(xy 51.19079 -496.674089) (xy 51.250419 -496.627274) (xy 51.314687 -496.587062) (xy 51.382864 -496.55391)
			(xy 51.45418 -496.528192) (xy 51.527825 -496.5102) (xy 51.602965 -496.500138) (xy 51.678749 -496.498119)
			(xy 51.754319 -496.504168) (xy 51.828817 -496.518215) (xy 51.9014 -496.540101) (xy 51.971246 -496.569578)
			(xy 52.037563 -496.606313) (xy 52.099599 -496.649888) (xy 52.156652 -496.69981) (xy 52.208076 -496.755514)
			(xy 52.253287 -496.816369) (xy 52.291774 -496.881684) (xy 52.3231 -496.95072) (xy 52.34691 -497.022695)
			(xy 52.362935 -497.096793) (xy 52.370994 -497.172174) (xy 52.371498 -497.21008) (xy 53.487577 -497.21008)
			(xy 53.491612 -497.134376) (xy 53.503671 -497.059531) (xy 53.523617 -496.98639) (xy 53.551224 -496.915785)
			(xy 53.58618 -496.848514) (xy 53.628088 -496.785339) (xy 53.676474 -496.726977) (xy 53.73079 -496.674089)
			(xy 53.790419 -496.627274) (xy 53.854687 -496.587062) (xy 53.922864 -496.55391) (xy 53.99418 -496.528192)
			(xy 54.067825 -496.5102) (xy 54.142965 -496.500138) (xy 54.218749 -496.498119) (xy 54.294319 -496.504168)
			(xy 54.368817 -496.518215) (xy 54.4414 -496.540101) (xy 54.511246 -496.569578) (xy 54.577563 -496.606313)
			(xy 54.639599 -496.649888) (xy 54.696652 -496.69981) (xy 54.748076 -496.755514) (xy 54.793287 -496.816369)
			(xy 54.831774 -496.881684) (xy 54.8631 -496.95072) (xy 54.88691 -497.022695) (xy 54.902935 -497.096793)
			(xy 54.910994 -497.172174) (xy 54.911498 -497.21008) (xy 56.027577 -497.21008) (xy 56.031612 -497.134376)
			(xy 56.043671 -497.059531) (xy 56.063617 -496.98639) (xy 56.091224 -496.915785) (xy 56.12618 -496.848514)
			(xy 56.168088 -496.785339) (xy 56.216474 -496.726977) (xy 56.27079 -496.674089) (xy 56.330419 -496.627274)
			(xy 56.394687 -496.587062) (xy 56.462864 -496.55391) (xy 56.53418 -496.528192) (xy 56.607825 -496.5102)
			(xy 56.682965 -496.500138) (xy 56.758749 -496.498119) (xy 56.834319 -496.504168) (xy 56.908817 -496.518215)
			(xy 56.9814 -496.540101) (xy 57.051246 -496.569578) (xy 57.117563 -496.606313) (xy 57.179599 -496.649888)
			(xy 57.236652 -496.69981) (xy 57.288076 -496.755514) (xy 57.333287 -496.816369) (xy 57.371774 -496.881684)
			(xy 57.4031 -496.95072) (xy 57.42691 -497.022695) (xy 57.442935 -497.096793) (xy 57.450994 -497.172174)
			(xy 57.451498 -497.21008) (xy 58.567577 -497.21008) (xy 58.571612 -497.134376) (xy 58.583671 -497.059531)
			(xy 58.603617 -496.98639) (xy 58.631224 -496.915785) (xy 58.66618 -496.848514) (xy 58.708088 -496.785339)
			(xy 58.756474 -496.726977) (xy 58.81079 -496.674089) (xy 58.870419 -496.627274) (xy 58.934687 -496.587062)
			(xy 59.002864 -496.55391) (xy 59.07418 -496.528192) (xy 59.147825 -496.5102) (xy 59.222965 -496.500138)
			(xy 59.298749 -496.498119) (xy 59.374319 -496.504168) (xy 59.448817 -496.518215) (xy 59.5214 -496.540101)
			(xy 59.591246 -496.569578) (xy 59.657563 -496.606313) (xy 59.719599 -496.649888) (xy 59.776652 -496.69981)
			(xy 59.828076 -496.755514) (xy 59.873287 -496.816369) (xy 59.911774 -496.881684) (xy 59.9431 -496.95072)
			(xy 59.96691 -497.022695) (xy 59.982935 -497.096793) (xy 59.990994 -497.172174) (xy 59.991498 -497.21008)
			(xy 61.107577 -497.21008) (xy 61.111612 -497.134376) (xy 61.123671 -497.059531) (xy 61.143617 -496.98639)
			(xy 61.171224 -496.915785) (xy 61.20618 -496.848514) (xy 61.248088 -496.785339) (xy 61.296474 -496.726977)
			(xy 61.35079 -496.674089) (xy 61.410419 -496.627274) (xy 61.474687 -496.587062) (xy 61.542864 -496.55391)
			(xy 61.61418 -496.528192) (xy 61.687825 -496.5102) (xy 61.762965 -496.500138) (xy 61.838749 -496.498119)
			(xy 61.914319 -496.504168) (xy 61.988817 -496.518215) (xy 62.0614 -496.540101) (xy 62.131246 -496.569578)
			(xy 62.197563 -496.606313) (xy 62.259599 -496.649888) (xy 62.316652 -496.69981) (xy 62.368076 -496.755514)
			(xy 62.413287 -496.816369) (xy 62.451774 -496.881684) (xy 62.4831 -496.95072) (xy 62.50691 -497.022695)
			(xy 62.522935 -497.096793) (xy 62.530994 -497.172174) (xy 62.531498 -497.21008) (xy 62.530994 -497.247986)
			(xy 62.522935 -497.323367) (xy 62.50691 -497.397465) (xy 62.4831 -497.46944) (xy 62.451774 -497.538476)
			(xy 62.413287 -497.603791) (xy 62.368076 -497.664646) (xy 62.316652 -497.72035) (xy 62.259599 -497.770272)
			(xy 62.197563 -497.813847) (xy 62.131246 -497.850582) (xy 62.0614 -497.880059) (xy 61.988817 -497.901945)
			(xy 61.914319 -497.915992) (xy 61.838749 -497.922041) (xy 61.762965 -497.920022) (xy 61.687825 -497.90996)
			(xy 61.61418 -497.891968) (xy 61.542864 -497.86625) (xy 61.474687 -497.833098) (xy 61.410419 -497.792886)
			(xy 61.35079 -497.746071) (xy 61.296474 -497.693183) (xy 61.248088 -497.634821) (xy 61.20618 -497.571646)
			(xy 61.171224 -497.504375) (xy 61.143617 -497.43377) (xy 61.123671 -497.360629) (xy 61.111612 -497.285784)
			(xy 61.107577 -497.21008) (xy 59.991498 -497.21008) (xy 59.990994 -497.247986) (xy 59.982935 -497.323367)
			(xy 59.96691 -497.397465) (xy 59.9431 -497.46944) (xy 59.911774 -497.538476) (xy 59.873287 -497.603791)
			(xy 59.828076 -497.664646) (xy 59.776652 -497.72035) (xy 59.719599 -497.770272) (xy 59.657563 -497.813847)
			(xy 59.591246 -497.850582) (xy 59.5214 -497.880059) (xy 59.448817 -497.901945) (xy 59.374319 -497.915992)
			(xy 59.298749 -497.922041) (xy 59.222965 -497.920022) (xy 59.147825 -497.90996) (xy 59.07418 -497.891968)
			(xy 59.002864 -497.86625) (xy 58.934687 -497.833098) (xy 58.870419 -497.792886) (xy 58.81079 -497.746071)
			(xy 58.756474 -497.693183) (xy 58.708088 -497.634821) (xy 58.66618 -497.571646) (xy 58.631224 -497.504375)
			(xy 58.603617 -497.43377) (xy 58.583671 -497.360629) (xy 58.571612 -497.285784) (xy 58.567577 -497.21008)
			(xy 57.451498 -497.21008) (xy 57.450994 -497.247986) (xy 57.442935 -497.323367) (xy 57.42691 -497.397465)
			(xy 57.4031 -497.46944) (xy 57.371774 -497.538476) (xy 57.333287 -497.603791) (xy 57.288076 -497.664646)
			(xy 57.236652 -497.72035) (xy 57.179599 -497.770272) (xy 57.117563 -497.813847) (xy 57.051246 -497.850582)
			(xy 56.9814 -497.880059) (xy 56.908817 -497.901945) (xy 56.834319 -497.915992) (xy 56.758749 -497.922041)
			(xy 56.682965 -497.920022) (xy 56.607825 -497.90996) (xy 56.53418 -497.891968) (xy 56.462864 -497.86625)
			(xy 56.394687 -497.833098) (xy 56.330419 -497.792886) (xy 56.27079 -497.746071) (xy 56.216474 -497.693183)
			(xy 56.168088 -497.634821) (xy 56.12618 -497.571646) (xy 56.091224 -497.504375) (xy 56.063617 -497.43377)
			(xy 56.043671 -497.360629) (xy 56.031612 -497.285784) (xy 56.027577 -497.21008) (xy 54.911498 -497.21008)
			(xy 54.910994 -497.247986) (xy 54.902935 -497.323367) (xy 54.88691 -497.397465) (xy 54.8631 -497.46944)
			(xy 54.831774 -497.538476) (xy 54.793287 -497.603791) (xy 54.748076 -497.664646) (xy 54.696652 -497.72035)
			(xy 54.639599 -497.770272) (xy 54.577563 -497.813847) (xy 54.511246 -497.850582) (xy 54.4414 -497.880059)
			(xy 54.368817 -497.901945) (xy 54.294319 -497.915992) (xy 54.218749 -497.922041) (xy 54.142965 -497.920022)
			(xy 54.067825 -497.90996) (xy 53.99418 -497.891968) (xy 53.922864 -497.86625) (xy 53.854687 -497.833098)
			(xy 53.790419 -497.792886) (xy 53.73079 -497.746071) (xy 53.676474 -497.693183) (xy 53.628088 -497.634821)
			(xy 53.58618 -497.571646) (xy 53.551224 -497.504375) (xy 53.523617 -497.43377) (xy 53.503671 -497.360629)
			(xy 53.491612 -497.285784) (xy 53.487577 -497.21008) (xy 52.371498 -497.21008) (xy 52.370994 -497.247986)
			(xy 52.362935 -497.323367) (xy 52.34691 -497.397465) (xy 52.3231 -497.46944) (xy 52.291774 -497.538476)
			(xy 52.253287 -497.603791) (xy 52.208076 -497.664646) (xy 52.156652 -497.72035) (xy 52.099599 -497.770272)
			(xy 52.037563 -497.813847) (xy 51.971246 -497.850582) (xy 51.9014 -497.880059) (xy 51.828817 -497.901945)
			(xy 51.754319 -497.915992) (xy 51.678749 -497.922041) (xy 51.602965 -497.920022) (xy 51.527825 -497.90996)
			(xy 51.45418 -497.891968) (xy 51.382864 -497.86625) (xy 51.314687 -497.833098) (xy 51.250419 -497.792886)
			(xy 51.19079 -497.746071) (xy 51.136474 -497.693183) (xy 51.088088 -497.634821) (xy 51.04618 -497.571646)
			(xy 51.011224 -497.504375) (xy 50.983617 -497.43377) (xy 50.963671 -497.360629) (xy 50.951612 -497.285784)
			(xy 50.947577 -497.21008) (xy 49.831498 -497.21008) (xy 49.830994 -497.247986) (xy 49.822935 -497.323367)
			(xy 49.80691 -497.397465) (xy 49.7831 -497.46944) (xy 49.751774 -497.538476) (xy 49.713287 -497.603791)
			(xy 49.668076 -497.664646) (xy 49.616652 -497.72035) (xy 49.559599 -497.770272) (xy 49.497563 -497.813847)
			(xy 49.431246 -497.850582) (xy 49.3614 -497.880059) (xy 49.288817 -497.901945) (xy 49.214319 -497.915992)
			(xy 49.138749 -497.922041) (xy 49.062965 -497.920022) (xy 48.987825 -497.90996) (xy 48.91418 -497.891968)
			(xy 48.842864 -497.86625) (xy 48.774687 -497.833098) (xy 48.710419 -497.792886) (xy 48.65079 -497.746071)
			(xy 48.596474 -497.693183) (xy 48.548088 -497.634821) (xy 48.50618 -497.571646) (xy 48.471224 -497.504375)
			(xy 48.443617 -497.43377) (xy 48.423671 -497.360629) (xy 48.411612 -497.285784) (xy 48.407577 -497.21008)
			(xy 47.291498 -497.21008) (xy 47.290994 -497.247986) (xy 47.282935 -497.323367) (xy 47.26691 -497.397465)
			(xy 47.2431 -497.46944) (xy 47.211774 -497.538476) (xy 47.173287 -497.603791) (xy 47.128076 -497.664646)
			(xy 47.076652 -497.72035) (xy 47.019599 -497.770272) (xy 46.957563 -497.813847) (xy 46.891246 -497.850582)
			(xy 46.8214 -497.880059) (xy 46.748817 -497.901945) (xy 46.674319 -497.915992) (xy 46.598749 -497.922041)
			(xy 46.522965 -497.920022) (xy 46.447825 -497.90996) (xy 46.37418 -497.891968) (xy 46.302864 -497.86625)
			(xy 46.234687 -497.833098) (xy 46.170419 -497.792886) (xy 46.11079 -497.746071) (xy 46.056474 -497.693183)
			(xy 46.008088 -497.634821) (xy 45.96618 -497.571646) (xy 45.931224 -497.504375) (xy 45.903617 -497.43377)
			(xy 45.883671 -497.360629) (xy 45.871612 -497.285784) (xy 45.867577 -497.21008) (xy 44.751498 -497.21008)
			(xy 44.750994 -497.247986) (xy 44.742935 -497.323367) (xy 44.72691 -497.397465) (xy 44.7031 -497.46944)
			(xy 44.671774 -497.538476) (xy 44.633287 -497.603791) (xy 44.588076 -497.664646) (xy 44.536652 -497.72035)
			(xy 44.479599 -497.770272) (xy 44.417563 -497.813847) (xy 44.351246 -497.850582) (xy 44.2814 -497.880059)
			(xy 44.208817 -497.901945) (xy 44.134319 -497.915992) (xy 44.058749 -497.922041) (xy 43.982965 -497.920022)
			(xy 43.907825 -497.90996) (xy 43.83418 -497.891968) (xy 43.762864 -497.86625) (xy 43.694687 -497.833098)
			(xy 43.630419 -497.792886) (xy 43.57079 -497.746071) (xy 43.516474 -497.693183) (xy 43.468088 -497.634821)
			(xy 43.42618 -497.571646) (xy 43.391224 -497.504375) (xy 43.363617 -497.43377) (xy 43.343671 -497.360629)
			(xy 43.331612 -497.285784) (xy 43.327577 -497.21008) (xy 42.502604 -497.21008) (xy 42.502322 -497.210305)
			(xy 42.406779 -497.276254) (xy 42.306914 -497.335454) (xy 42.203202 -497.387623) (xy 42.096139 -497.432512)
			(xy 41.986233 -497.469908) (xy 41.874009 -497.499633) (xy 41.760003 -497.521544) (xy 41.644756 -497.535537)
			(xy 41.528818 -497.541546) (xy 41.412742 -497.539543) (xy 41.29708 -497.529535) (xy 41.182385 -497.511572)
			(xy 41.069202 -497.485739) (xy 40.958071 -497.452159) (xy 40.849522 -497.410991) (xy 40.744072 -497.362433)
			(xy 40.642223 -497.306716) (xy 40.54446 -497.244104) (xy 40.45125 -497.174897) (xy 40.363037 -497.099424)
			(xy 40.280241 -497.018045) (xy 40.203257 -496.931148) (xy 40.132452 -496.839147) (xy 40.068162 -496.74248)
			(xy 40.010695 -496.641608) (xy 39.960324 -496.537011) (xy 39.917289 -496.429188) (xy 39.881795 -496.318654)
			(xy 39.854012 -496.205934) (xy 39.834072 -496.091566) (xy 39.82207 -495.976094) (xy 39.818063 -495.86007)
			(xy 1.27 -495.86007) (xy 1.27 -497.192469) (xy 4.94918 -497.192469) (xy 4.94918 -497.111359) (xy 4.95713 -497.03064)
			(xy 4.972953 -496.951089) (xy 4.996498 -496.873473) (xy 5.027537 -496.798537) (xy 5.065772 -496.727005)
			(xy 5.110834 -496.659565) (xy 5.162289 -496.596866) (xy 5.219642 -496.539513) (xy 5.282341 -496.488058)
			(xy 5.349781 -496.442996) (xy 5.421313 -496.404761) (xy 5.496249 -496.373722) (xy 5.573865 -496.350177)
			(xy 5.653416 -496.334354) (xy 5.734135 -496.326404) (xy 5.815245 -496.326404) (xy 5.895964 -496.334354)
			(xy 5.975515 -496.350177) (xy 6.053131 -496.373722) (xy 6.128067 -496.404761) (xy 6.199599 -496.442996)
			(xy 6.267039 -496.488058) (xy 6.329738 -496.539513) (xy 6.387091 -496.596866) (xy 6.438546 -496.659565)
			(xy 6.483608 -496.727005) (xy 6.521843 -496.798537) (xy 6.552882 -496.873473) (xy 6.576427 -496.951089)
			(xy 6.59225 -497.03064) (xy 6.6002 -497.111359) (xy 6.600698 -497.151914) (xy 6.6002 -497.192469)
			(xy 7.48918 -497.192469) (xy 7.48918 -497.111359) (xy 7.49713 -497.03064) (xy 7.512953 -496.951089)
			(xy 7.536498 -496.873473) (xy 7.567537 -496.798537) (xy 7.605772 -496.727005) (xy 7.650834 -496.659565)
			(xy 7.702289 -496.596866) (xy 7.759642 -496.539513) (xy 7.822341 -496.488058) (xy 7.889781 -496.442996)
			(xy 7.961313 -496.404761) (xy 8.036249 -496.373722) (xy 8.113865 -496.350177) (xy 8.193416 -496.334354)
			(xy 8.274135 -496.326404) (xy 8.355245 -496.326404) (xy 8.435964 -496.334354) (xy 8.515515 -496.350177)
			(xy 8.593131 -496.373722) (xy 8.668067 -496.404761) (xy 8.739599 -496.442996) (xy 8.807039 -496.488058)
			(xy 8.869738 -496.539513) (xy 8.927091 -496.596866) (xy 8.978546 -496.659565) (xy 9.023608 -496.727005)
			(xy 9.061843 -496.798537) (xy 9.092882 -496.873473) (xy 9.116427 -496.951089) (xy 9.13225 -497.03064)
			(xy 9.1402 -497.111359) (xy 9.140698 -497.151914) (xy 9.1402 -497.192469) (xy 10.02918 -497.192469)
			(xy 10.02918 -497.111359) (xy 10.03713 -497.03064) (xy 10.052953 -496.951089) (xy 10.076498 -496.873473)
			(xy 10.107537 -496.798537) (xy 10.145772 -496.727005) (xy 10.190834 -496.659565) (xy 10.242289 -496.596866)
			(xy 10.299642 -496.539513) (xy 10.362341 -496.488058) (xy 10.429781 -496.442996) (xy 10.501313 -496.404761)
			(xy 10.576249 -496.373722) (xy 10.653865 -496.350177) (xy 10.733416 -496.334354) (xy 10.814135 -496.326404)
			(xy 10.895245 -496.326404) (xy 10.975964 -496.334354) (xy 11.055515 -496.350177) (xy 11.133131 -496.373722)
			(xy 11.208067 -496.404761) (xy 11.279599 -496.442996) (xy 11.347039 -496.488058) (xy 11.409738 -496.539513)
			(xy 11.467091 -496.596866) (xy 11.518546 -496.659565) (xy 11.563608 -496.727005) (xy 11.601843 -496.798537)
			(xy 11.632882 -496.873473) (xy 11.656427 -496.951089) (xy 11.67225 -497.03064) (xy 11.6802 -497.111359)
			(xy 11.680698 -497.151914) (xy 11.6802 -497.192469) (xy 12.56918 -497.192469) (xy 12.56918 -497.111359)
			(xy 12.57713 -497.03064) (xy 12.592953 -496.951089) (xy 12.616498 -496.873473) (xy 12.647537 -496.798537)
			(xy 12.685772 -496.727005) (xy 12.730834 -496.659565) (xy 12.782289 -496.596866) (xy 12.839642 -496.539513)
			(xy 12.902341 -496.488058) (xy 12.969781 -496.442996) (xy 13.041313 -496.404761) (xy 13.116249 -496.373722)
			(xy 13.193865 -496.350177) (xy 13.273416 -496.334354) (xy 13.354135 -496.326404) (xy 13.435245 -496.326404)
			(xy 13.515964 -496.334354) (xy 13.595515 -496.350177) (xy 13.673131 -496.373722) (xy 13.748067 -496.404761)
			(xy 13.819599 -496.442996) (xy 13.887039 -496.488058) (xy 13.949738 -496.539513) (xy 14.007091 -496.596866)
			(xy 14.058546 -496.659565) (xy 14.103608 -496.727005) (xy 14.141843 -496.798537) (xy 14.172882 -496.873473)
			(xy 14.196427 -496.951089) (xy 14.21225 -497.03064) (xy 14.2202 -497.111359) (xy 14.220698 -497.151914)
			(xy 14.2202 -497.192469) (xy 14.21225 -497.273188) (xy 14.196427 -497.352739) (xy 14.172882 -497.430355)
			(xy 14.141843 -497.505291) (xy 14.103608 -497.576823) (xy 14.058546 -497.644263) (xy 14.007091 -497.706962)
			(xy 13.949738 -497.764315) (xy 13.887039 -497.81577) (xy 13.819599 -497.860832) (xy 13.748067 -497.899067)
			(xy 13.673131 -497.930106) (xy 13.595515 -497.953651) (xy 13.515964 -497.969474) (xy 13.435245 -497.977424)
			(xy 13.354135 -497.977424) (xy 13.273416 -497.969474) (xy 13.193865 -497.953651) (xy 13.116249 -497.930106)
			(xy 13.041313 -497.899067) (xy 12.969781 -497.860832) (xy 12.902341 -497.81577) (xy 12.839642 -497.764315)
			(xy 12.782289 -497.706962) (xy 12.730834 -497.644263) (xy 12.685772 -497.576823) (xy 12.647537 -497.505291)
			(xy 12.616498 -497.430355) (xy 12.592953 -497.352739) (xy 12.57713 -497.273188) (xy 12.56918 -497.192469)
			(xy 11.6802 -497.192469) (xy 11.67225 -497.273188) (xy 11.656427 -497.352739) (xy 11.632882 -497.430355)
			(xy 11.601843 -497.505291) (xy 11.563608 -497.576823) (xy 11.518546 -497.644263) (xy 11.467091 -497.706962)
			(xy 11.409738 -497.764315) (xy 11.347039 -497.81577) (xy 11.279599 -497.860832) (xy 11.208067 -497.899067)
			(xy 11.133131 -497.930106) (xy 11.055515 -497.953651) (xy 10.975964 -497.969474) (xy 10.895245 -497.977424)
			(xy 10.814135 -497.977424) (xy 10.733416 -497.969474) (xy 10.653865 -497.953651) (xy 10.576249 -497.930106)
			(xy 10.501313 -497.899067) (xy 10.429781 -497.860832) (xy 10.362341 -497.81577) (xy 10.299642 -497.764315)
			(xy 10.242289 -497.706962) (xy 10.190834 -497.644263) (xy 10.145772 -497.576823) (xy 10.107537 -497.505291)
			(xy 10.076498 -497.430355) (xy 10.052953 -497.352739) (xy 10.03713 -497.273188) (xy 10.02918 -497.192469)
			(xy 9.1402 -497.192469) (xy 9.13225 -497.273188) (xy 9.116427 -497.352739) (xy 9.092882 -497.430355)
			(xy 9.061843 -497.505291) (xy 9.023608 -497.576823) (xy 8.978546 -497.644263) (xy 8.927091 -497.706962)
			(xy 8.869738 -497.764315) (xy 8.807039 -497.81577) (xy 8.739599 -497.860832) (xy 8.668067 -497.899067)
			(xy 8.593131 -497.930106) (xy 8.515515 -497.953651) (xy 8.435964 -497.969474) (xy 8.355245 -497.977424)
			(xy 8.274135 -497.977424) (xy 8.193416 -497.969474) (xy 8.113865 -497.953651) (xy 8.036249 -497.930106)
			(xy 7.961313 -497.899067) (xy 7.889781 -497.860832) (xy 7.822341 -497.81577) (xy 7.759642 -497.764315)
			(xy 7.702289 -497.706962) (xy 7.650834 -497.644263) (xy 7.605772 -497.576823) (xy 7.567537 -497.505291)
			(xy 7.536498 -497.430355) (xy 7.512953 -497.352739) (xy 7.49713 -497.273188) (xy 7.48918 -497.192469)
			(xy 6.6002 -497.192469) (xy 6.59225 -497.273188) (xy 6.576427 -497.352739) (xy 6.552882 -497.430355)
			(xy 6.521843 -497.505291) (xy 6.483608 -497.576823) (xy 6.438546 -497.644263) (xy 6.387091 -497.706962)
			(xy 6.329738 -497.764315) (xy 6.267039 -497.81577) (xy 6.199599 -497.860832) (xy 6.128067 -497.899067)
			(xy 6.053131 -497.930106) (xy 5.975515 -497.953651) (xy 5.895964 -497.969474) (xy 5.815245 -497.977424)
			(xy 5.734135 -497.977424) (xy 5.653416 -497.969474) (xy 5.573865 -497.953651) (xy 5.496249 -497.930106)
			(xy 5.421313 -497.899067) (xy 5.349781 -497.860832) (xy 5.282341 -497.81577) (xy 5.219642 -497.764315)
			(xy 5.162289 -497.706962) (xy 5.110834 -497.644263) (xy 5.065772 -497.576823) (xy 5.027537 -497.505291)
			(xy 4.996498 -497.430355) (xy 4.972953 -497.352739) (xy 4.95713 -497.273188) (xy 4.94918 -497.192469)
			(xy 1.27 -497.192469) (xy 1.27 -505.51461) (xy 80.909412 -505.51461) (xy 80.913483 -505.458988) (xy 80.925609 -505.404551)
			(xy 80.945532 -505.35246) (xy 80.972828 -505.303825) (xy 81.006914 -505.259682) (xy 81.047063 -505.220973)
			(xy 81.092421 -505.188522) (xy 81.142021 -505.163021) (xy 81.194805 -505.145014) (xy 81.249648 -505.134884)
			(xy 81.305382 -505.132847) (xy 81.360819 -505.138947) (xy 81.414776 -505.153053) (xy 81.466105 -505.174865)
			(xy 81.513711 -505.203919) (xy 81.556579 -505.239594) (xy 81.593796 -505.281131) (xy 81.624569 -505.327644)
			(xy 81.648241 -505.378141) (xy 81.664309 -505.431548) (xy 81.672429 -505.486724) (xy 81.672938 -505.51461)
			(xy 81.672674 -505.529088) (xy 82.117944 -505.529088) (xy 82.122015 -505.473466) (xy 82.134141 -505.419029)
			(xy 82.154064 -505.366938) (xy 82.18136 -505.318303) (xy 82.215446 -505.27416) (xy 82.255595 -505.235451)
			(xy 82.300953 -505.203) (xy 82.350553 -505.177499) (xy 82.403337 -505.159492) (xy 82.45818 -505.149362)
			(xy 82.513914 -505.147325) (xy 82.569351 -505.153425) (xy 82.623308 -505.167531) (xy 82.674637 -505.189343)
			(xy 82.722243 -505.218397) (xy 82.765111 -505.254072) (xy 82.802328 -505.295609) (xy 82.833101 -505.342122)
			(xy 82.856773 -505.392619) (xy 82.872841 -505.446026) (xy 82.880961 -505.501202) (xy 82.88147 -505.529088)
			(xy 82.880961 -505.556974) (xy 82.872841 -505.61215) (xy 82.856773 -505.665557) (xy 82.833101 -505.716054)
			(xy 82.802328 -505.762567) (xy 82.765111 -505.804104) (xy 82.722243 -505.839779) (xy 82.674637 -505.868833)
			(xy 82.623308 -505.890645) (xy 82.569351 -505.904751) (xy 82.513914 -505.910851) (xy 82.45818 -505.908814)
			(xy 82.403337 -505.898684) (xy 82.350553 -505.880677) (xy 82.300953 -505.855176) (xy 82.255595 -505.822725)
			(xy 82.215446 -505.784016) (xy 82.18136 -505.739873) (xy 82.154064 -505.691238) (xy 82.134141 -505.639147)
			(xy 82.122015 -505.58471) (xy 82.117944 -505.529088) (xy 81.672674 -505.529088) (xy 81.672429 -505.542496)
			(xy 81.664309 -505.597672) (xy 81.648241 -505.651079) (xy 81.624569 -505.701576) (xy 81.593796 -505.748089)
			(xy 81.556579 -505.789626) (xy 81.513711 -505.825301) (xy 81.466105 -505.854355) (xy 81.414776 -505.876167)
			(xy 81.360819 -505.890273) (xy 81.305382 -505.896373) (xy 81.249648 -505.894336) (xy 81.194805 -505.884206)
			(xy 81.142021 -505.866199) (xy 81.092421 -505.840698) (xy 81.047063 -505.808247) (xy 81.006914 -505.769538)
			(xy 80.972828 -505.725395) (xy 80.945532 -505.67676) (xy 80.925609 -505.624669) (xy 80.913483 -505.570232)
			(xy 80.909412 -505.51461) (xy 1.27 -505.51461) (xy 1.27 -506.498098) (xy 79.51673 -506.498098) (xy 79.520801 -506.442476)
			(xy 79.532927 -506.388039) (xy 79.55285 -506.335948) (xy 79.580146 -506.287313) (xy 79.614232 -506.24317)
			(xy 79.654381 -506.204461) (xy 79.699739 -506.17201) (xy 79.749339 -506.146509) (xy 79.802123 -506.128502)
			(xy 79.856966 -506.118372) (xy 79.9127 -506.116335) (xy 79.968137 -506.122435) (xy 80.022094 -506.136541)
			(xy 80.073423 -506.158353) (xy 80.121029 -506.187407) (xy 80.163897 -506.223082) (xy 80.201114 -506.264619)
			(xy 80.231887 -506.311132) (xy 80.255559 -506.361629) (xy 80.271627 -506.415036) (xy 80.279747 -506.470212)
			(xy 80.280256 -506.498098) (xy 80.279747 -506.525984) (xy 80.271627 -506.58116) (xy 80.255559 -506.634567)
			(xy 80.231887 -506.685064) (xy 80.201114 -506.731577) (xy 80.163897 -506.773114) (xy 80.121029 -506.808789)
			(xy 80.073423 -506.837843) (xy 80.022094 -506.859655) (xy 79.968137 -506.873761) (xy 79.9127 -506.879861)
			(xy 79.856966 -506.877824) (xy 79.802123 -506.867694) (xy 79.749339 -506.849687) (xy 79.699739 -506.824186)
			(xy 79.654381 -506.791735) (xy 79.614232 -506.753026) (xy 79.580146 -506.708883) (xy 79.55285 -506.660248)
			(xy 79.532927 -506.608157) (xy 79.520801 -506.55372) (xy 79.51673 -506.498098) (xy 1.27 -506.498098)
			(xy 1.27 -507.717975) (xy 47.97424 -507.717975) (xy 47.97424 -507.636865) (xy 47.98219 -507.556146)
			(xy 47.998013 -507.476595) (xy 48.021558 -507.398979) (xy 48.052597 -507.324043) (xy 48.090832 -507.252511)
			(xy 48.135894 -507.185071) (xy 48.187349 -507.122372) (xy 48.244702 -507.065019) (xy 48.307401 -507.013564)
			(xy 48.374841 -506.968502) (xy 48.446373 -506.930267) (xy 48.521309 -506.899228) (xy 48.598925 -506.875683)
			(xy 48.678476 -506.85986) (xy 48.759195 -506.85191) (xy 48.840305 -506.85191) (xy 48.921024 -506.85986)
			(xy 49.000575 -506.875683) (xy 49.078191 -506.899228) (xy 49.153127 -506.930267) (xy 49.224659 -506.968502)
			(xy 49.292099 -507.013564) (xy 49.354798 -507.065019) (xy 49.412151 -507.122372) (xy 49.463606 -507.185071)
			(xy 49.508668 -507.252511) (xy 49.546903 -507.324043) (xy 49.577942 -507.398979) (xy 49.601487 -507.476595)
			(xy 49.61731 -507.556146) (xy 49.62526 -507.636865) (xy 49.625758 -507.67742) (xy 49.62526 -507.717975)
			(xy 49.61731 -507.798694) (xy 49.601487 -507.878245) (xy 49.577942 -507.955861) (xy 49.546903 -508.030797)
			(xy 49.508668 -508.102329) (xy 49.463606 -508.169769) (xy 49.412151 -508.232468) (xy 49.354798 -508.289821)
			(xy 49.292099 -508.341276) (xy 49.224659 -508.386338) (xy 49.153127 -508.424573) (xy 49.078191 -508.455612)
			(xy 49.000575 -508.479157) (xy 48.921024 -508.49498) (xy 48.840305 -508.50293) (xy 48.759195 -508.50293)
			(xy 48.678476 -508.49498) (xy 48.598925 -508.479157) (xy 48.521309 -508.455612) (xy 48.446373 -508.424573)
			(xy 48.374841 -508.386338) (xy 48.307401 -508.341276) (xy 48.244702 -508.289821) (xy 48.187349 -508.232468)
			(xy 48.135894 -508.169769) (xy 48.090832 -508.102329) (xy 48.052597 -508.030797) (xy 48.021558 -507.955861)
			(xy 47.998013 -507.878245) (xy 47.98219 -507.798694) (xy 47.97424 -507.717975) (xy 1.27 -507.717975)
			(xy 1.27 -508.96012) (xy 86.877404 -508.96012) (xy 86.881424 -508.769469) (xy 86.893478 -508.579156)
			(xy 86.913544 -508.389521) (xy 86.941587 -508.2009) (xy 86.977556 -508.01363) (xy 87.021388 -507.828042)
			(xy 87.073005 -507.644467) (xy 87.132315 -507.463231) (xy 87.199213 -507.284656) (xy 87.273579 -507.109061)
			(xy 87.355281 -506.936756) (xy 87.444175 -506.768049) (xy 87.540101 -506.603239) (xy 87.64289 -506.44262)
			(xy 87.752359 -506.286477) (xy 87.868313 -506.135088) (xy 87.990547 -505.988721) (xy 88.118841 -505.847637)
			(xy 88.252969 -505.712088) (xy 88.392693 -505.582313) (xy 88.537763 -505.458543) (xy 88.687921 -505.341)
			(xy 88.842902 -505.229891) (xy 89.002429 -505.125414) (xy 89.166218 -505.027755) (xy 89.333978 -504.937088)
			(xy 89.505412 -504.853574) (xy 89.680214 -504.777361) (xy 89.858073 -504.708585) (xy 90.038674 -504.647367)
			(xy 90.221694 -504.593818) (xy 90.40681 -504.548032) (xy 90.593691 -504.51009) (xy 90.782006 -504.480061)
			(xy 90.971419 -504.457996) (xy 91.161593 -504.443937) (xy 91.352192 -504.437907) (xy 91.542875 -504.439917)
			(xy 91.733304 -504.449964) (xy 91.92314 -504.46803) (xy 92.112046 -504.494083) (xy 92.299685 -504.528076)
			(xy 92.485725 -504.569949) (xy 92.669834 -504.619628) (xy 92.851685 -504.677024) (xy 93.030955 -504.742035)
			(xy 93.207325 -504.814546) (xy 93.380481 -504.894427) (xy 93.550116 -504.981537) (xy 93.715928 -505.075721)
			(xy 93.877622 -505.176812) (xy 94.03491 -505.284628) (xy 94.187513 -505.39898) (xy 94.335161 -505.519663)
			(xy 94.477589 -505.646464) (xy 94.614545 -505.779155) (xy 94.745786 -505.917503) (xy 94.871078 -506.06126)
			(xy 94.990198 -506.210171) (xy 95.102934 -506.363972) (xy 95.209087 -506.522388) (xy 95.308467 -506.685139)
			(xy 95.400897 -506.851934) (xy 95.486214 -507.022478) (xy 95.564266 -507.196466) (xy 95.634913 -507.373591)
			(xy 95.698031 -507.553536) (xy 95.753507 -507.735982) (xy 95.801242 -507.920605) (xy 95.841152 -508.107075)
			(xy 95.873165 -508.295063) (xy 95.897225 -508.484233) (xy 95.913288 -508.674249) (xy 95.921327 -508.864773)
			(xy 95.92183 -508.96012) (xy 95.921327 -509.055467) (xy 95.913288 -509.245991) (xy 95.897225 -509.436007)
			(xy 95.873165 -509.625177) (xy 95.841152 -509.813165) (xy 95.801242 -509.999635) (xy 95.753507 -510.184258)
			(xy 95.698031 -510.366704) (xy 95.634913 -510.546649) (xy 95.564266 -510.723774) (xy 95.486214 -510.897762)
			(xy 95.400897 -511.068306) (xy 95.308467 -511.235101) (xy 95.209087 -511.397852) (xy 95.102934 -511.556268)
			(xy 94.990198 -511.710069) (xy 94.871078 -511.85898) (xy 94.745786 -512.002737) (xy 94.614545 -512.141085)
			(xy 94.477589 -512.273776) (xy 94.335161 -512.400577) (xy 94.187513 -512.52126) (xy 94.03491 -512.635612)
			(xy 93.877622 -512.743428) (xy 93.715928 -512.844519) (xy 93.550116 -512.938703) (xy 93.380481 -513.025813)
			(xy 93.207325 -513.105694) (xy 93.030955 -513.178205) (xy 92.851685 -513.243216) (xy 92.669834 -513.300612)
			(xy 92.485725 -513.350291) (xy 92.299685 -513.392164) (xy 92.112046 -513.426157) (xy 91.92314 -513.45221)
			(xy 91.733304 -513.470276) (xy 91.542875 -513.480323) (xy 91.352192 -513.482333) (xy 91.161593 -513.476303)
			(xy 90.971419 -513.462244) (xy 90.782006 -513.440179) (xy 90.593691 -513.41015) (xy 90.40681 -513.372208)
			(xy 90.221694 -513.326422) (xy 90.038674 -513.272873) (xy 89.858073 -513.211655) (xy 89.680214 -513.142879)
			(xy 89.505412 -513.066666) (xy 89.333978 -512.983152) (xy 89.166218 -512.892485) (xy 89.002429 -512.794826)
			(xy 88.842902 -512.690349) (xy 88.687921 -512.57924) (xy 88.537763 -512.461697) (xy 88.392693 -512.337927)
			(xy 88.252969 -512.208152) (xy 88.118841 -512.072603) (xy 87.990547 -511.931519) (xy 87.868313 -511.785152)
			(xy 87.752359 -511.633763) (xy 87.64289 -511.47762) (xy 87.540101 -511.317001) (xy 87.444175 -511.152191)
			(xy 87.355281 -510.983484) (xy 87.273579 -510.811179) (xy 87.199213 -510.635584) (xy 87.132315 -510.457009)
			(xy 87.073005 -510.275773) (xy 87.021388 -510.092198) (xy 86.977556 -509.90661) (xy 86.941587 -509.71934)
			(xy 86.913544 -509.530719) (xy 86.893478 -509.341084) (xy 86.881424 -509.150771) (xy 86.877404 -508.96012)
			(xy 1.27 -508.96012) (xy 1.27 -513.179314) (xy 1.270551 -513.202676) (xy 1.279134 -513.248607) (xy 1.29597 -513.292194)
			(xy 1.320492 -513.331969) (xy 1.351871 -513.36659) (xy 1.389052 -513.39489) (xy 1.430779 -513.415916)
			(xy 1.475648 -513.428958) (xy 1.522145 -513.433578) (xy 1.568703 -513.429618) (xy 1.613752 -513.417214)
			(xy 1.655774 -513.396782) (xy 1.693352 -513.369012) (xy 1.709674 -513.352288) (xy 1.754144 -513.305252)
			(xy 1.848064 -513.216155) (xy 1.947334 -513.133062) (xy 2.051571 -513.056293) (xy 2.160374 -512.986144)
			(xy 2.273323 -512.922886) (xy 2.389982 -512.866763) (xy 2.5099 -512.817992) (xy 2.632615 -512.77676)
			(xy 2.757653 -512.743227) (xy 2.884532 -512.717522) (xy 3.012762 -512.699745) (xy 3.141848 -512.689963)
			(xy 3.271293 -512.688216) (xy 3.400597 -512.694509) (xy 3.52926 -512.708818) (xy 3.656786 -512.731088)
			(xy 3.782684 -512.761233) (xy 3.906468 -512.799137) (xy 4.027658 -512.844653) (xy 4.14579 -512.897607)
			(xy 4.260405 -512.957792) (xy 4.371062 -513.024979) (xy 4.477334 -513.098906) (xy 4.578812 -513.179288)
			(xy 4.675102 -513.265817) (xy 4.765834 -513.358157) (xy 4.850658 -513.455952) (xy 4.929246 -513.558825)
			(xy 5.001295 -513.66638) (xy 5.066527 -513.7782) (xy 5.124691 -513.893855) (xy 5.175561 -514.012898)
			(xy 5.218942 -514.134869) (xy 5.254666 -514.259299) (xy 5.282595 -514.385707) (xy 5.302622 -514.513605)
			(xy 5.314669 -514.6425) (xy 5.31869 -514.771894) (xy 12.580624 -514.771894) (xy 12.584655 -514.642328)
			(xy 12.596734 -514.513264) (xy 12.616813 -514.3852) (xy 12.644815 -514.258633) (xy 12.680632 -514.13405)
			(xy 12.724124 -514.011936) (xy 12.775124 -513.892762) (xy 12.833435 -513.776989) (xy 12.89883 -513.665065)
			(xy 12.971057 -513.557423) (xy 13.049837 -513.45448) (xy 13.134864 -513.356634) (xy 13.225809 -513.264262)
			(xy 13.322321 -513.177724) (xy 13.424027 -513.097353) (xy 13.530533 -513.023461) (xy 13.641426 -512.956333)
			(xy 13.756278 -512.896229) (xy 13.874645 -512.843382) (xy 13.996068 -512.797995) (xy 14.120078 -512.760246)
			(xy 14.246195 -512.730279) (xy 14.373931 -512.70821) (xy 14.502792 -512.694126) (xy 14.632279 -512.68808)
			(xy 14.761892 -512.690096) (xy 14.891128 -512.700166) (xy 15.019489 -512.718251) (xy 15.146477 -512.744281)
			(xy 15.271601 -512.778156) (xy 15.394377 -512.819744) (xy 15.51433 -512.868885) (xy 15.630995 -512.925388)
			(xy 15.743923 -512.989035) (xy 15.852675 -513.059579) (xy 15.956831 -513.136748) (xy 16.055988 -513.220243)
			(xy 16.149762 -513.309741) (xy 16.237791 -513.404896) (xy 16.319734 -513.505339) (xy 16.395273 -513.610682)
			(xy 16.464118 -513.720518) (xy 16.526001 -513.834422) (xy 16.580682 -513.951952) (xy 16.627952 -514.072655)
			(xy 16.667625 -514.196063) (xy 16.69955 -514.321699) (xy 16.723602 -514.449076) (xy 16.739689 -514.577702)
			(xy 16.747748 -514.70708) (xy 16.748252 -514.771894) (xy 16.747748 -514.836708) (xy 16.739689 -514.966086)
			(xy 16.723602 -515.094712) (xy 16.69955 -515.222089) (xy 16.667625 -515.347725) (xy 16.627952 -515.471133)
			(xy 16.580682 -515.591836) (xy 16.526001 -515.709366) (xy 16.464118 -515.82327) (xy 16.395273 -515.933106)
			(xy 16.319734 -516.038449) (xy 16.237791 -516.138892) (xy 16.149762 -516.234047) (xy 16.055988 -516.323545)
			(xy 15.956831 -516.40704) (xy 15.852675 -516.484209) (xy 15.743923 -516.554753) (xy 15.630995 -516.6184)
			(xy 15.51433 -516.674903) (xy 15.394377 -516.724044) (xy 15.271601 -516.765632) (xy 15.146477 -516.799507)
			(xy 15.019489 -516.825537) (xy 14.891128 -516.843622) (xy 14.761892 -516.853692) (xy 14.632279 -516.855708)
			(xy 14.502792 -516.849662) (xy 14.373931 -516.835578) (xy 14.246195 -516.813509) (xy 14.120078 -516.783542)
			(xy 13.996068 -516.745793) (xy 13.874645 -516.700406) (xy 13.756278 -516.647559) (xy 13.641426 -516.587455)
			(xy 13.530533 -516.520327) (xy 13.424027 -516.446435) (xy 13.322321 -516.366064) (xy 13.225809 -516.279526)
			(xy 13.134864 -516.187154) (xy 13.049837 -516.089308) (xy 12.971057 -515.986365) (xy 12.89883 -515.878723)
			(xy 12.833435 -515.766799) (xy 12.775124 -515.651026) (xy 12.724124 -515.531852) (xy 12.680632 -515.409738)
			(xy 12.644815 -515.285155) (xy 12.616813 -515.158588) (xy 12.596734 -515.030524) (xy 12.584655 -514.90146)
			(xy 12.580624 -514.771894) (xy 5.31869 -514.771894) (xy 5.314669 -514.901288) (xy 5.302622 -515.030183)
			(xy 5.282595 -515.158081) (xy 5.254666 -515.284489) (xy 5.218942 -515.408919) (xy 5.175561 -515.53089)
			(xy 5.124691 -515.649933) (xy 5.066527 -515.765588) (xy 5.001295 -515.877408) (xy 4.929246 -515.984963)
			(xy 4.850658 -516.087836) (xy 4.765834 -516.185631) (xy 4.675102 -516.277971) (xy 4.578812 -516.3645)
			(xy 4.477334 -516.444882) (xy 4.371062 -516.518809) (xy 4.260405 -516.585996) (xy 4.14579 -516.646181)
			(xy 4.027658 -516.699135) (xy 3.906468 -516.744651) (xy 3.782684 -516.782555) (xy 3.656786 -516.8127)
			(xy 3.52926 -516.83497) (xy 3.400597 -516.849279) (xy 3.271293 -516.855572) (xy 3.141848 -516.853825)
			(xy 3.012762 -516.844043) (xy 2.884532 -516.826266) (xy 2.757653 -516.800561) (xy 2.632615 -516.767028)
			(xy 2.5099 -516.725796) (xy 2.389982 -516.677025) (xy 2.273323 -516.620902) (xy 2.160374 -516.557644)
			(xy 2.051571 -516.487495) (xy 1.947334 -516.410726) (xy 1.848064 -516.327633) (xy 1.754144 -516.238536)
			(xy 1.709674 -516.1915) (xy 1.693349 -516.174784) (xy 1.655769 -516.147031) (xy 1.613749 -516.126614)
			(xy 1.568705 -516.11422) (xy 1.522155 -516.110268) (xy 1.475666 -516.114891) (xy 1.430806 -516.127933)
			(xy 1.389085 -516.148954) (xy 1.351908 -516.177247) (xy 1.320529 -516.211857) (xy 1.296005 -516.25162)
			(xy 1.279161 -516.295196) (xy 1.270565 -516.341116) (xy 1.27 -516.364474) (xy 1.27 -519.061107) (xy 47.82311 -519.061107)
			(xy 47.82311 -518.979997) (xy 47.83106 -518.899278) (xy 47.846883 -518.819727) (xy 47.870428 -518.742111)
			(xy 47.901467 -518.667175) (xy 47.939702 -518.595643) (xy 47.984764 -518.528203) (xy 48.036219 -518.465504)
			(xy 48.093572 -518.408151) (xy 48.156271 -518.356696) (xy 48.223711 -518.311634) (xy 48.295243 -518.273399)
			(xy 48.370179 -518.24236) (xy 48.447795 -518.218815) (xy 48.527346 -518.202992) (xy 48.608065 -518.195042)
			(xy 48.689175 -518.195042) (xy 48.769894 -518.202992) (xy 48.849445 -518.218815) (xy 48.927061 -518.24236)
			(xy 49.001997 -518.273399) (xy 49.073529 -518.311634) (xy 49.140969 -518.356696) (xy 49.203668 -518.408151)
			(xy 49.261021 -518.465504) (xy 49.312476 -518.528203) (xy 49.357538 -518.595643) (xy 49.395773 -518.667175)
			(xy 49.426812 -518.742111) (xy 49.450357 -518.819727) (xy 49.46618 -518.899278) (xy 49.47413 -518.979997)
			(xy 49.474628 -519.020552) (xy 49.474269 -519.049762) (xy 72.868035 -519.049762) (xy 72.872042 -518.847012)
			(xy 72.884055 -518.644578) (xy 72.904056 -518.442777) (xy 72.932015 -518.241923) (xy 72.967886 -518.042331)
			(xy 73.011615 -517.844312) (xy 73.063133 -517.648175) (xy 73.122359 -517.454227) (xy 73.189201 -517.262769)
			(xy 73.263555 -517.074102) (xy 73.345304 -516.88852) (xy 73.434322 -516.706312) (xy 73.530468 -516.527763)
			(xy 73.633593 -516.353152) (xy 73.743536 -516.182752) (xy 73.860125 -516.016828) (xy 73.983178 -515.855639)
			(xy 74.112503 -515.699438) (xy 74.247898 -515.548468) (xy 74.389151 -515.402964) (xy 74.536043 -515.263155)
			(xy 74.688343 -515.129258) (xy 74.845814 -515.001483) (xy 75.008211 -514.880028) (xy 75.175278 -514.765084)
			(xy 75.346757 -514.65683) (xy 75.522378 -514.555435) (xy 75.701868 -514.461057) (xy 75.884946 -514.373845)
			(xy 76.071327 -514.293933) (xy 76.26072 -514.221446) (xy 76.452828 -514.156499) (xy 76.647352 -514.099191)
			(xy 76.843988 -514.049614) (xy 77.04243 -514.007843) (xy 77.242367 -513.973945) (xy 77.443486 -513.947973)
			(xy 77.645475 -513.929966) (xy 77.848018 -513.919953) (xy 78.050798 -513.917949) (xy 78.253499 -513.923959)
			(xy 78.455804 -513.937971) (xy 78.657398 -513.959966) (xy 78.857965 -513.989907) (xy 79.057193 -514.027748)
			(xy 79.254771 -514.073431) (xy 79.450389 -514.126884) (xy 79.643743 -514.188023) (xy 79.834531 -514.256754)
			(xy 80.022454 -514.332968) (xy 80.20722 -514.416547) (xy 80.388539 -514.50736) (xy 80.56613 -514.605265)
			(xy 80.739713 -514.71011) (xy 80.909019 -514.821731) (xy 81.073784 -514.939953) (xy 81.233749 -515.064593)
			(xy 81.388665 -515.195454) (xy 81.53829 -515.332334) (xy 81.68239 -515.475018) (xy 81.820742 -515.623284)
			(xy 81.953127 -515.7769) (xy 82.079341 -515.935625) (xy 82.199185 -516.099214) (xy 82.312473 -516.267409)
			(xy 82.419028 -516.439948) (xy 82.518683 -516.616563) (xy 82.611283 -516.796976) (xy 82.696683 -516.980907)
			(xy 82.77475 -517.168068) (xy 82.845362 -517.358168) (xy 82.908408 -517.550908) (xy 82.963791 -517.745989)
			(xy 83.011423 -517.943106) (xy 83.051231 -518.14195) (xy 83.083153 -518.342212) (xy 83.107137 -518.543578)
			(xy 83.123148 -518.745735) (xy 83.131159 -518.948367) (xy 83.13166 -519.049762) (xy 83.131159 -519.151157)
			(xy 83.123148 -519.353789) (xy 83.107137 -519.555946) (xy 83.083153 -519.757312) (xy 83.051231 -519.957574)
			(xy 83.011423 -520.156418) (xy 82.963791 -520.353535) (xy 82.908408 -520.548616) (xy 82.845362 -520.741356)
			(xy 82.77475 -520.931456) (xy 82.696683 -521.118617) (xy 82.611283 -521.302548) (xy 82.518683 -521.482961)
			(xy 82.419028 -521.659576) (xy 82.312473 -521.832115) (xy 82.199185 -522.00031) (xy 82.079341 -522.163899)
			(xy 81.953127 -522.322624) (xy 81.820742 -522.47624) (xy 81.68239 -522.624506) (xy 81.53829 -522.76719)
			(xy 81.388665 -522.90407) (xy 81.233749 -523.034931) (xy 81.073784 -523.159571) (xy 80.909019 -523.277793)
			(xy 80.739713 -523.389414) (xy 80.56613 -523.494259) (xy 80.388539 -523.592164) (xy 80.20722 -523.682977)
			(xy 80.022454 -523.766556) (xy 79.834531 -523.84277) (xy 79.643743 -523.911501) (xy 79.450389 -523.97264)
			(xy 79.254771 -524.026093) (xy 79.057193 -524.071776) (xy 78.857965 -524.109617) (xy 78.657398 -524.139558)
			(xy 78.455804 -524.161553) (xy 78.253499 -524.175565) (xy 78.050798 -524.181575) (xy 77.848018 -524.179571)
			(xy 77.645475 -524.169558) (xy 77.443486 -524.151551) (xy 77.242367 -524.125579) (xy 77.04243 -524.091681)
			(xy 76.843988 -524.04991) (xy 76.647352 -524.000333) (xy 76.452828 -523.943025) (xy 76.26072 -523.878078)
			(xy 76.071327 -523.805591) (xy 75.884946 -523.725679) (xy 75.701868 -523.638467) (xy 75.522378 -523.544089)
			(xy 75.346757 -523.442694) (xy 75.175278 -523.33444) (xy 75.008211 -523.219496) (xy 74.845814 -523.098041)
			(xy 74.688343 -522.970266) (xy 74.536043 -522.836369) (xy 74.389151 -522.69656) (xy 74.247898 -522.551056)
			(xy 74.112503 -522.400086) (xy 73.983178 -522.243885) (xy 73.860125 -522.082696) (xy 73.743536 -521.916772)
			(xy 73.633593 -521.746372) (xy 73.530468 -521.571761) (xy 73.434322 -521.393212) (xy 73.345304 -521.211004)
			(xy 73.263555 -521.025422) (xy 73.189201 -520.836755) (xy 73.122359 -520.645297) (xy 73.063133 -520.451349)
			(xy 73.011615 -520.255212) (xy 72.967886 -520.057193) (xy 72.932015 -519.857601) (xy 72.904056 -519.656747)
			(xy 72.884055 -519.454946) (xy 72.872042 -519.252512) (xy 72.868035 -519.049762) (xy 49.474269 -519.049762)
			(xy 49.47413 -519.061107) (xy 49.46618 -519.141826) (xy 49.450357 -519.221377) (xy 49.426812 -519.298993)
			(xy 49.395773 -519.373929) (xy 49.357538 -519.445461) (xy 49.312476 -519.512901) (xy 49.261021 -519.5756)
			(xy 49.203668 -519.632953) (xy 49.140969 -519.684408) (xy 49.073529 -519.72947) (xy 49.001997 -519.767705)
			(xy 48.927061 -519.798744) (xy 48.849445 -519.822289) (xy 48.769894 -519.838112) (xy 48.689175 -519.846062)
			(xy 48.608065 -519.846062) (xy 48.527346 -519.838112) (xy 48.447795 -519.822289) (xy 48.370179 -519.798744)
			(xy 48.295243 -519.767705) (xy 48.223711 -519.72947) (xy 48.156271 -519.684408) (xy 48.093572 -519.632953)
			(xy 48.036219 -519.5756) (xy 47.984764 -519.512901) (xy 47.939702 -519.445461) (xy 47.901467 -519.373929)
			(xy 47.870428 -519.298993) (xy 47.846883 -519.221377) (xy 47.83106 -519.141826) (xy 47.82311 -519.061107)
			(xy 1.27 -519.061107) (xy 1.27 -521.162449) (xy 3.67918 -521.162449) (xy 3.67918 -521.081339) (xy 3.68713 -521.00062)
			(xy 3.702953 -520.921069) (xy 3.726498 -520.843453) (xy 3.757537 -520.768517) (xy 3.795772 -520.696985)
			(xy 3.840834 -520.629545) (xy 3.892289 -520.566846) (xy 3.949642 -520.509493) (xy 4.012341 -520.458038)
			(xy 4.079781 -520.412976) (xy 4.151313 -520.374741) (xy 4.226249 -520.343702) (xy 4.303865 -520.320157)
			(xy 4.383416 -520.304334) (xy 4.464135 -520.296384) (xy 4.545245 -520.296384) (xy 4.625964 -520.304334)
			(xy 4.705515 -520.320157) (xy 4.783131 -520.343702) (xy 4.858067 -520.374741) (xy 4.929599 -520.412976)
			(xy 4.997039 -520.458038) (xy 5.059738 -520.509493) (xy 5.117091 -520.566846) (xy 5.168546 -520.629545)
			(xy 5.213608 -520.696985) (xy 5.251843 -520.768517) (xy 5.282882 -520.843453) (xy 5.306427 -520.921069)
			(xy 5.32225 -521.00062) (xy 5.3302 -521.081339) (xy 5.330698 -521.121894) (xy 5.3302 -521.162449)
			(xy 6.21918 -521.162449) (xy 6.21918 -521.081339) (xy 6.22713 -521.00062) (xy 6.242953 -520.921069)
			(xy 6.266498 -520.843453) (xy 6.297537 -520.768517) (xy 6.335772 -520.696985) (xy 6.380834 -520.629545)
			(xy 6.432289 -520.566846) (xy 6.489642 -520.509493) (xy 6.552341 -520.458038) (xy 6.619781 -520.412976)
			(xy 6.691313 -520.374741) (xy 6.766249 -520.343702) (xy 6.843865 -520.320157) (xy 6.923416 -520.304334)
			(xy 7.004135 -520.296384) (xy 7.085245 -520.296384) (xy 7.165964 -520.304334) (xy 7.245515 -520.320157)
			(xy 7.323131 -520.343702) (xy 7.398067 -520.374741) (xy 7.469599 -520.412976) (xy 7.537039 -520.458038)
			(xy 7.599738 -520.509493) (xy 7.657091 -520.566846) (xy 7.708546 -520.629545) (xy 7.753608 -520.696985)
			(xy 7.791843 -520.768517) (xy 7.822882 -520.843453) (xy 7.846427 -520.921069) (xy 7.86225 -521.00062)
			(xy 7.8702 -521.081339) (xy 7.870698 -521.121894) (xy 7.8702 -521.162449) (xy 8.75918 -521.162449)
			(xy 8.75918 -521.081339) (xy 8.76713 -521.00062) (xy 8.782953 -520.921069) (xy 8.806498 -520.843453)
			(xy 8.837537 -520.768517) (xy 8.875772 -520.696985) (xy 8.920834 -520.629545) (xy 8.972289 -520.566846)
			(xy 9.029642 -520.509493) (xy 9.092341 -520.458038) (xy 9.159781 -520.412976) (xy 9.231313 -520.374741)
			(xy 9.306249 -520.343702) (xy 9.383865 -520.320157) (xy 9.463416 -520.304334) (xy 9.544135 -520.296384)
			(xy 9.625245 -520.296384) (xy 9.705964 -520.304334) (xy 9.785515 -520.320157) (xy 9.863131 -520.343702)
			(xy 9.938067 -520.374741) (xy 10.009599 -520.412976) (xy 10.077039 -520.458038) (xy 10.139738 -520.509493)
			(xy 10.197091 -520.566846) (xy 10.248546 -520.629545) (xy 10.293608 -520.696985) (xy 10.331843 -520.768517)
			(xy 10.362882 -520.843453) (xy 10.386427 -520.921069) (xy 10.40225 -521.00062) (xy 10.4102 -521.081339)
			(xy 10.410698 -521.121894) (xy 10.4102 -521.162449) (xy 11.29918 -521.162449) (xy 11.29918 -521.081339)
			(xy 11.30713 -521.00062) (xy 11.322953 -520.921069) (xy 11.346498 -520.843453) (xy 11.377537 -520.768517)
			(xy 11.415772 -520.696985) (xy 11.460834 -520.629545) (xy 11.512289 -520.566846) (xy 11.569642 -520.509493)
			(xy 11.632341 -520.458038) (xy 11.699781 -520.412976) (xy 11.771313 -520.374741) (xy 11.846249 -520.343702)
			(xy 11.923865 -520.320157) (xy 12.003416 -520.304334) (xy 12.084135 -520.296384) (xy 12.165245 -520.296384)
			(xy 12.245964 -520.304334) (xy 12.325515 -520.320157) (xy 12.403131 -520.343702) (xy 12.478067 -520.374741)
			(xy 12.549599 -520.412976) (xy 12.617039 -520.458038) (xy 12.679738 -520.509493) (xy 12.737091 -520.566846)
			(xy 12.788546 -520.629545) (xy 12.833608 -520.696985) (xy 12.871843 -520.768517) (xy 12.902882 -520.843453)
			(xy 12.926427 -520.921069) (xy 12.94225 -521.00062) (xy 12.9502 -521.081339) (xy 12.950698 -521.121894)
			(xy 12.9502 -521.162449) (xy 12.94225 -521.243168) (xy 12.926427 -521.322719) (xy 12.902882 -521.400335)
			(xy 12.871843 -521.475271) (xy 12.833608 -521.546803) (xy 12.788546 -521.614243) (xy 12.737091 -521.676942)
			(xy 12.679738 -521.734295) (xy 12.617039 -521.78575) (xy 12.549599 -521.830812) (xy 12.478067 -521.869047)
			(xy 12.403131 -521.900086) (xy 12.325515 -521.923631) (xy 12.245964 -521.939454) (xy 12.165245 -521.947404)
			(xy 12.084135 -521.947404) (xy 12.003416 -521.939454) (xy 11.923865 -521.923631) (xy 11.846249 -521.900086)
			(xy 11.771313 -521.869047) (xy 11.699781 -521.830812) (xy 11.632341 -521.78575) (xy 11.569642 -521.734295)
			(xy 11.512289 -521.676942) (xy 11.460834 -521.614243) (xy 11.415772 -521.546803) (xy 11.377537 -521.475271)
			(xy 11.346498 -521.400335) (xy 11.322953 -521.322719) (xy 11.30713 -521.243168) (xy 11.29918 -521.162449)
			(xy 10.4102 -521.162449) (xy 10.40225 -521.243168) (xy 10.386427 -521.322719) (xy 10.362882 -521.400335)
			(xy 10.331843 -521.475271) (xy 10.293608 -521.546803) (xy 10.248546 -521.614243) (xy 10.197091 -521.676942)
			(xy 10.139738 -521.734295) (xy 10.077039 -521.78575) (xy 10.009599 -521.830812) (xy 9.938067 -521.869047)
			(xy 9.863131 -521.900086) (xy 9.785515 -521.923631) (xy 9.705964 -521.939454) (xy 9.625245 -521.947404)
			(xy 9.544135 -521.947404) (xy 9.463416 -521.939454) (xy 9.383865 -521.923631) (xy 9.306249 -521.900086)
			(xy 9.231313 -521.869047) (xy 9.159781 -521.830812) (xy 9.092341 -521.78575) (xy 9.029642 -521.734295)
			(xy 8.972289 -521.676942) (xy 8.920834 -521.614243) (xy 8.875772 -521.546803) (xy 8.837537 -521.475271)
			(xy 8.806498 -521.400335) (xy 8.782953 -521.322719) (xy 8.76713 -521.243168) (xy 8.75918 -521.162449)
			(xy 7.8702 -521.162449) (xy 7.86225 -521.243168) (xy 7.846427 -521.322719) (xy 7.822882 -521.400335)
			(xy 7.791843 -521.475271) (xy 7.753608 -521.546803) (xy 7.708546 -521.614243) (xy 7.657091 -521.676942)
			(xy 7.599738 -521.734295) (xy 7.537039 -521.78575) (xy 7.469599 -521.830812) (xy 7.398067 -521.869047)
			(xy 7.323131 -521.900086) (xy 7.245515 -521.923631) (xy 7.165964 -521.939454) (xy 7.085245 -521.947404)
			(xy 7.004135 -521.947404) (xy 6.923416 -521.939454) (xy 6.843865 -521.923631) (xy 6.766249 -521.900086)
			(xy 6.691313 -521.869047) (xy 6.619781 -521.830812) (xy 6.552341 -521.78575) (xy 6.489642 -521.734295)
			(xy 6.432289 -521.676942) (xy 6.380834 -521.614243) (xy 6.335772 -521.546803) (xy 6.297537 -521.475271)
			(xy 6.266498 -521.400335) (xy 6.242953 -521.322719) (xy 6.22713 -521.243168) (xy 6.21918 -521.162449)
			(xy 5.3302 -521.162449) (xy 5.32225 -521.243168) (xy 5.306427 -521.322719) (xy 5.282882 -521.400335)
			(xy 5.251843 -521.475271) (xy 5.213608 -521.546803) (xy 5.168546 -521.614243) (xy 5.117091 -521.676942)
			(xy 5.059738 -521.734295) (xy 4.997039 -521.78575) (xy 4.929599 -521.830812) (xy 4.858067 -521.869047)
			(xy 4.783131 -521.900086) (xy 4.705515 -521.923631) (xy 4.625964 -521.939454) (xy 4.545245 -521.947404)
			(xy 4.464135 -521.947404) (xy 4.383416 -521.939454) (xy 4.303865 -521.923631) (xy 4.226249 -521.900086)
			(xy 4.151313 -521.869047) (xy 4.079781 -521.830812) (xy 4.012341 -521.78575) (xy 3.949642 -521.734295)
			(xy 3.892289 -521.676942) (xy 3.840834 -521.614243) (xy 3.795772 -521.546803) (xy 3.757537 -521.475271)
			(xy 3.726498 -521.400335) (xy 3.702953 -521.322719) (xy 3.68713 -521.243168) (xy 3.67918 -521.162449)
			(xy 1.27 -521.162449) (xy 1.27 -524.500094) (xy 1.270418 -524.520529) (xy 1.277593 -524.560764) (xy 1.291771 -524.599096)
			(xy 1.30175 -524.616934) (xy 1.309267 -524.629378) (xy 1.326973 -524.652435) (xy 1.337056 -524.662908)
			(xy 1.354085 -524.679138) (xy 1.393394 -524.704967) (xy 1.437124 -524.722289) (xy 1.483458 -524.730384)
			(xy 1.506982 -524.730218) (xy 1.509268 -524.730218) (xy 1.512316 -524.729964) (xy 5.065014 -524.729964)
			(xy 5.087016 -524.729503) (xy 5.130364 -524.721933) (xy 5.171759 -524.707005) (xy 5.209961 -524.685166)
			(xy 5.243827 -524.65707) (xy 5.272344 -524.623556) (xy 5.294658 -524.585629) (xy 5.310101 -524.544424)
			(xy 5.31821 -524.501174) (xy 5.318744 -524.457173) (xy 5.311686 -524.413739) (xy 5.297247 -524.372171)
			(xy 5.27586 -524.333714) (xy 5.248164 -524.299519) (xy 5.231892 -524.284702) (xy 5.201393 -524.257461)
			(xy 5.145352 -524.197901) (xy 5.095471 -524.133095) (xy 5.052237 -524.063678) (xy 5.016073 -523.990328)
			(xy 4.987333 -523.913764) (xy 4.9663 -523.834735) (xy 4.953177 -523.754015) (xy 4.948095 -523.672393)
			(xy 4.951103 -523.590668) (xy 4.962171 -523.50964) (xy 4.98119 -523.430103) (xy 5.007976 -523.352833)
			(xy 5.042265 -523.278589) (xy 5.083722 -523.208096) (xy 5.131942 -523.142044) (xy 5.186452 -523.08108)
			(xy 5.246719 -523.0258) (xy 5.312153 -522.976745) (xy 5.382114 -522.934396) (xy 5.455917 -522.899167)
			(xy 5.53284 -522.871402) (xy 5.612129 -522.851374) (xy 5.69301 -522.839278) (xy 5.77469 -522.835233)
			(xy 5.85637 -522.839278) (xy 5.937251 -522.851374) (xy 6.01654 -522.871402) (xy 6.093463 -522.899167)
			(xy 6.167266 -522.934396) (xy 6.237227 -522.976745) (xy 6.302661 -523.0258) (xy 6.362928 -523.08108)
			(xy 6.417438 -523.142044) (xy 6.465658 -523.208096) (xy 6.507115 -523.278589) (xy 6.541404 -523.352833)
			(xy 6.56819 -523.430103) (xy 6.587209 -523.50964) (xy 6.598277 -523.590668) (xy 6.601285 -523.672393)
			(xy 6.596203 -523.754015) (xy 6.58308 -523.834735) (xy 6.562047 -523.913764) (xy 6.533307 -523.990328)
			(xy 6.497143 -524.063678) (xy 6.453909 -524.133095) (xy 6.404028 -524.197901) (xy 6.347987 -524.257461)
			(xy 6.317488 -524.284702) (xy 6.301228 -524.299518) (xy 6.273571 -524.333721) (xy 6.252218 -524.372176)
			(xy 6.237807 -524.413734) (xy 6.230769 -524.457153) (xy 6.231315 -524.501136) (xy 6.239428 -524.544367)
			(xy 6.254865 -524.585555) (xy 6.277165 -524.623468) (xy 6.305663 -524.656974) (xy 6.339505 -524.685072)
			(xy 6.377681 -524.70692) (xy 6.419049 -524.721867) (xy 6.462373 -524.729466) (xy 6.484366 -524.729964)
			(xy 7.605014 -524.729964) (xy 7.627016 -524.729503) (xy 7.670364 -524.721933) (xy 7.711759 -524.707005)
			(xy 7.749961 -524.685166) (xy 7.783827 -524.65707) (xy 7.812344 -524.623556) (xy 7.834658 -524.585629)
			(xy 7.850101 -524.544424) (xy 7.85821 -524.501174) (xy 7.858744 -524.457173) (xy 7.851686 -524.413739)
			(xy 7.837247 -524.372171) (xy 7.81586 -524.333714) (xy 7.788164 -524.299519) (xy 7.771892 -524.284702)
			(xy 7.741393 -524.257461) (xy 7.685352 -524.197901) (xy 7.635471 -524.133095) (xy 7.592237 -524.063678)
			(xy 7.556073 -523.990328) (xy 7.527333 -523.913764) (xy 7.5063 -523.834735) (xy 7.493177 -523.754015)
			(xy 7.488095 -523.672393) (xy 7.491103 -523.590668) (xy 7.502171 -523.50964) (xy 7.52119 -523.430103)
			(xy 7.547976 -523.352833) (xy 7.582265 -523.278589) (xy 7.623722 -523.208096) (xy 7.671942 -523.142044)
			(xy 7.726452 -523.08108) (xy 7.786719 -523.0258) (xy 7.852153 -522.976745) (xy 7.922114 -522.934396)
			(xy 7.995917 -522.899167) (xy 8.07284 -522.871402) (xy 8.152129 -522.851374) (xy 8.23301 -522.839278)
			(xy 8.31469 -522.835233) (xy 8.39637 -522.839278) (xy 8.477251 -522.851374) (xy 8.55654 -522.871402)
			(xy 8.633463 -522.899167) (xy 8.707266 -522.934396) (xy 8.777227 -522.976745) (xy 8.842661 -523.0258)
			(xy 8.902928 -523.08108) (xy 8.957438 -523.142044) (xy 9.005658 -523.208096) (xy 9.047115 -523.278589)
			(xy 9.081404 -523.352833) (xy 9.10819 -523.430103) (xy 9.127209 -523.50964) (xy 9.138277 -523.590668)
			(xy 9.141285 -523.672393) (xy 9.136203 -523.754015) (xy 9.12308 -523.834735) (xy 9.102047 -523.913764)
			(xy 9.073307 -523.990328) (xy 9.037143 -524.063678) (xy 8.993909 -524.133095) (xy 8.944028 -524.197901)
			(xy 8.887987 -524.257461) (xy 8.857488 -524.284702) (xy 8.841228 -524.299518) (xy 8.813571 -524.333721)
			(xy 8.792218 -524.372176) (xy 8.777807 -524.413734) (xy 8.770769 -524.457153) (xy 8.771315 -524.501136)
			(xy 8.779428 -524.544367) (xy 8.794865 -524.585555) (xy 8.817165 -524.623468) (xy 8.845663 -524.656974)
			(xy 8.879505 -524.685072) (xy 8.917681 -524.70692) (xy 8.959049 -524.721867) (xy 9.002373 -524.729466)
			(xy 9.024366 -524.729964) (xy 10.145014 -524.729964) (xy 10.167016 -524.729503) (xy 10.210364 -524.721933)
			(xy 10.251759 -524.707005) (xy 10.289961 -524.685166) (xy 10.323827 -524.65707) (xy 10.352344 -524.623556)
			(xy 10.374658 -524.585629) (xy 10.390101 -524.544424) (xy 10.39821 -524.501174) (xy 10.398744 -524.457173)
			(xy 10.391686 -524.413739) (xy 10.377247 -524.372171) (xy 10.35586 -524.333714) (xy 10.328164 -524.299519)
			(xy 10.311892 -524.284702) (xy 10.281393 -524.257461) (xy 10.225352 -524.197901) (xy 10.175471 -524.133095)
			(xy 10.132237 -524.063678) (xy 10.096073 -523.990328) (xy 10.067333 -523.913764) (xy 10.0463 -523.834735)
			(xy 10.033177 -523.754015) (xy 10.028095 -523.672393) (xy 10.031103 -523.590668) (xy 10.042171 -523.50964)
			(xy 10.06119 -523.430103) (xy 10.087976 -523.352833) (xy 10.122265 -523.278589) (xy 10.163722 -523.208096)
			(xy 10.211942 -523.142044) (xy 10.266452 -523.08108) (xy 10.326719 -523.0258) (xy 10.392153 -522.976745)
			(xy 10.462114 -522.934396) (xy 10.535917 -522.899167) (xy 10.61284 -522.871402) (xy 10.692129 -522.851374)
			(xy 10.77301 -522.839278) (xy 10.85469 -522.835233) (xy 10.93637 -522.839278) (xy 11.017251 -522.851374)
			(xy 11.09654 -522.871402) (xy 11.173463 -522.899167) (xy 11.247266 -522.934396) (xy 11.317227 -522.976745)
			(xy 11.382661 -523.0258) (xy 11.442928 -523.08108) (xy 11.497438 -523.142044) (xy 11.545658 -523.208096)
			(xy 11.587115 -523.278589) (xy 11.621404 -523.352833) (xy 11.64819 -523.430103) (xy 11.667209 -523.50964)
			(xy 11.678277 -523.590668) (xy 11.681285 -523.672393) (xy 11.676203 -523.754015) (xy 11.66308 -523.834735)
			(xy 11.642047 -523.913764) (xy 11.613307 -523.990328) (xy 11.577143 -524.063678) (xy 11.533909 -524.133095)
			(xy 11.484028 -524.197901) (xy 11.427987 -524.257461) (xy 11.397488 -524.284702) (xy 11.381228 -524.299518)
			(xy 11.353571 -524.333721) (xy 11.332218 -524.372176) (xy 11.317807 -524.413734) (xy 11.310769 -524.457153)
			(xy 11.311315 -524.501136) (xy 11.319428 -524.544367) (xy 11.334865 -524.585555) (xy 11.357165 -524.623468)
			(xy 11.385663 -524.656974) (xy 11.419505 -524.685072) (xy 11.457681 -524.70692) (xy 11.499049 -524.721867)
			(xy 11.542373 -524.729466) (xy 11.564366 -524.729964) (xy 12.685014 -524.729964) (xy 12.707016 -524.729503)
			(xy 12.750364 -524.721933) (xy 12.791759 -524.707005) (xy 12.829961 -524.685166) (xy 12.863827 -524.65707)
			(xy 12.892344 -524.623556) (xy 12.914658 -524.585629) (xy 12.930101 -524.544424) (xy 12.93821 -524.501174)
			(xy 12.938744 -524.457173) (xy 12.931686 -524.413739) (xy 12.917247 -524.372171) (xy 12.89586 -524.333714)
			(xy 12.868164 -524.299519) (xy 12.851892 -524.284702) (xy 12.821393 -524.257461) (xy 12.765352 -524.197901)
			(xy 12.715471 -524.133095) (xy 12.672237 -524.063678) (xy 12.636073 -523.990328) (xy 12.607333 -523.913764)
			(xy 12.5863 -523.834735) (xy 12.573177 -523.754015) (xy 12.568095 -523.672393) (xy 12.571103 -523.590668)
			(xy 12.582171 -523.50964) (xy 12.60119 -523.430103) (xy 12.627976 -523.352833) (xy 12.662265 -523.278589)
			(xy 12.703722 -523.208096) (xy 12.751942 -523.142044) (xy 12.806452 -523.08108) (xy 12.866719 -523.0258)
			(xy 12.932153 -522.976745) (xy 13.002114 -522.934396) (xy 13.075917 -522.899167) (xy 13.15284 -522.871402)
			(xy 13.232129 -522.851374) (xy 13.31301 -522.839278) (xy 13.39469 -522.835233) (xy 13.47637 -522.839278)
			(xy 13.557251 -522.851374) (xy 13.63654 -522.871402) (xy 13.713463 -522.899167) (xy 13.787266 -522.934396)
			(xy 13.857227 -522.976745) (xy 13.922661 -523.0258) (xy 13.982928 -523.08108) (xy 14.037438 -523.142044)
			(xy 14.085658 -523.208096) (xy 14.127115 -523.278589) (xy 14.161404 -523.352833) (xy 14.18819 -523.430103)
			(xy 14.207209 -523.50964) (xy 14.218277 -523.590668) (xy 14.221285 -523.672393) (xy 14.216203 -523.754015)
			(xy 14.20308 -523.834735) (xy 14.182047 -523.913764) (xy 14.153307 -523.990328) (xy 14.117143 -524.063678)
			(xy 14.073909 -524.133095) (xy 14.024028 -524.197901) (xy 13.967987 -524.257461) (xy 13.937488 -524.284702)
			(xy 13.921228 -524.299518) (xy 13.893571 -524.333721) (xy 13.872218 -524.372176) (xy 13.857807 -524.413734)
			(xy 13.850769 -524.457153) (xy 13.851315 -524.501136) (xy 13.859428 -524.544367) (xy 13.874865 -524.585555)
			(xy 13.897165 -524.623468) (xy 13.925663 -524.656974) (xy 13.959505 -524.685072) (xy 13.997681 -524.70692)
			(xy 14.039049 -524.721867) (xy 14.082373 -524.729466) (xy 14.104366 -524.729964) (xy 23.50008 -524.729964)
			(xy 23.573919 -524.730454) (xy 23.721386 -524.738334) (xy 23.868223 -524.754063) (xy 24.014014 -524.777595)
			(xy 24.158343 -524.808865) (xy 24.3008 -524.847782) (xy 24.440981 -524.894237) (xy 24.578486 -524.948096)
			(xy 24.712926 -525.009208) (xy 24.843917 -525.077399) (xy 24.907748 -525.11452) (xy 24.967688 -525.150425)
			(xy 25.084276 -525.22746) (xy 25.196832 -525.310276) (xy 25.305068 -525.398662) (xy 25.408709 -525.492394)
			(xy 25.45842 -525.541494) (xy 25.507533 -525.591221) (xy 25.601267 -525.694915) (xy 25.689652 -525.803204)
			(xy 25.772464 -525.915813) (xy 25.849491 -526.032455) (xy 25.885394 -526.09242) (xy 25.922502 -526.156255)
			(xy 25.990667 -526.287252) (xy 26.051754 -526.421695) (xy 26.105588 -526.559203) (xy 26.152017 -526.699385)
			(xy 26.190908 -526.841842) (xy 26.222152 -526.98617) (xy 26.245659 -527.131958) (xy 26.261362 -527.278791)
			(xy 26.269217 -527.426253) (xy 26.269696 -527.500088) (xy 26.269696 -528.500086) (xy 26.270243 -528.52202)
			(xy 26.278593 -528.565086) (xy 26.294935 -528.605797) (xy 26.318682 -528.642682) (xy 26.348976 -528.674412)
			(xy 26.384723 -528.69984) (xy 26.424634 -528.718049) (xy 26.467268 -528.728382) (xy 26.489152 -528.729956)
		)
		(stroke
			(width 0)
			(type solid)
		)
		(fill yes)
		(layer "In2.Cu")
		(net "P12V")
	)
	(gr_line
		(start 0 -524.500094)
		(end 0 -5.500116)
		(stroke
			(width 2.032)
			(type default)
		)
		(layer "In3.Cu")
	)
	(gr_arc
		(start 0 -524.500094)
		(mid 0.439393 -525.560749)
		(end 1.500124 -525.999964)
		(stroke
			(width 2.032)
			(type default)
		)
		(layer "In3.Cu")
	)
	(gr_poly
		(pts
			(xy 27.681936 -528.95246) (xy 27.697684 -528.939506) (xy 27.720452 -528.921766) (xy 27.770278 -528.892634)
			(xy 27.823922 -528.871337) (xy 27.880162 -528.858362) (xy 27.937714 -528.854003) (xy 27.995266 -528.858362)
			(xy 28.051506 -528.871337) (xy 28.10515 -528.892634) (xy 28.154976 -528.921766) (xy 28.177744 -528.939506)
			(xy 28.193492 -528.95246) (xy 28.27655 -528.983956) (xy 40.298878 -528.983956) (xy 40.381936 -528.95246)
			(xy 40.397684 -528.939506) (xy 40.420452 -528.921766) (xy 40.470278 -528.892634) (xy 40.523922 -528.871337)
			(xy 40.580162 -528.858362) (xy 40.637714 -528.854003) (xy 40.695266 -528.858362) (xy 40.751506 -528.871337)
			(xy 40.80515 -528.892634) (xy 40.854976 -528.921766) (xy 40.877744 -528.939506) (xy 40.893492 -528.95246)
			(xy 40.97655 -528.983956) (xy 52.998878 -528.983956) (xy 53.081936 -528.95246) (xy 53.097684 -528.939506)
			(xy 53.120452 -528.921766) (xy 53.170278 -528.892634) (xy 53.223922 -528.871337) (xy 53.280162 -528.858362)
			(xy 53.337714 -528.854003) (xy 53.395266 -528.858362) (xy 53.451506 -528.871337) (xy 53.50515 -528.892634)
			(xy 53.554976 -528.921766) (xy 53.577744 -528.939506) (xy 53.593492 -528.95246) (xy 53.67655 -528.983956)
			(xy 65.698878 -528.983956) (xy 65.781936 -528.95246) (xy 65.797684 -528.939506) (xy 65.820452 -528.921766)
			(xy 65.870278 -528.892634) (xy 65.923922 -528.871337) (xy 65.980162 -528.858362) (xy 66.037714 -528.854003)
			(xy 66.095266 -528.858362) (xy 66.151506 -528.871337) (xy 66.20515 -528.892634) (xy 66.254976 -528.921766)
			(xy 66.277744 -528.939506) (xy 66.293492 -528.95246) (xy 66.37655 -528.983956) (xy 78.398878 -528.983956)
			(xy 78.481936 -528.95246) (xy 78.497684 -528.939506) (xy 78.520452 -528.921766) (xy 78.570278 -528.892634)
			(xy 78.623922 -528.871337) (xy 78.680162 -528.858362) (xy 78.737714 -528.854003) (xy 78.795266 -528.858362)
			(xy 78.851506 -528.871337) (xy 78.90515 -528.892634) (xy 78.954976 -528.921766) (xy 78.977744 -528.939506)
			(xy 78.993492 -528.95246) (xy 79.07655 -528.983956) (xy 91.098878 -528.983956) (xy 91.181936 -528.95246)
			(xy 91.197684 -528.939506) (xy 91.220452 -528.921766) (xy 91.270278 -528.892634) (xy 91.323922 -528.871337)
			(xy 91.380162 -528.858362) (xy 91.437714 -528.854003) (xy 91.495266 -528.858362) (xy 91.551506 -528.871337)
			(xy 91.60515 -528.892634) (xy 91.654976 -528.921766) (xy 91.677744 -528.939506) (xy 91.693492 -528.95246)
			(xy 91.77655 -528.983956) (xy 101.000052 -528.983956) (xy 101.045522 -528.983449) (xy 101.136075 -528.975062)
			(xy 101.225467 -528.958355) (xy 101.312937 -528.933471) (xy 101.397737 -528.900622) (xy 101.479144 -528.860089)
			(xy 101.556464 -528.812216) (xy 101.629036 -528.757413) (xy 101.696242 -528.696148) (xy 101.757508 -528.628942)
			(xy 101.812312 -528.55637) (xy 101.860185 -528.479051) (xy 101.900719 -528.397644) (xy 101.933569 -528.312844)
			(xy 101.958454 -528.225375) (xy 101.975161 -528.135983) (xy 101.983549 -528.04543) (xy 101.984048 -527.99996)
			(xy 101.984048 -525.382236) (xy 101.983586 -525.366909) (xy 101.976272 -525.337141) (xy 101.962081 -525.30997)
			(xy 101.952298 -525.298162) (xy 101.934352 -525.277135) (xy 101.904082 -525.230879) (xy 101.880807 -525.180739)
			(xy 101.865012 -525.127764) (xy 101.85703 -525.073064) (xy 101.857026 -525.017784) (xy 101.865002 -524.963083)
			(xy 101.88079 -524.910106) (xy 101.904059 -524.859963) (xy 101.934322 -524.813703) (xy 101.952298 -524.792702)
			(xy 101.962138 -524.780931) (xy 101.976362 -524.753756) (xy 101.983666 -524.723965) (xy 101.984048 -524.708628)
			(xy 101.984048 -512.682236) (xy 101.983586 -512.666909) (xy 101.976272 -512.637141) (xy 101.962081 -512.60997)
			(xy 101.952298 -512.598162) (xy 101.934352 -512.577135) (xy 101.904082 -512.530879) (xy 101.880807 -512.480739)
			(xy 101.865012 -512.427764) (xy 101.85703 -512.373064) (xy 101.857026 -512.317784) (xy 101.865002 -512.263083)
			(xy 101.88079 -512.210106) (xy 101.904059 -512.159963) (xy 101.934322 -512.113703) (xy 101.952298 -512.092702)
			(xy 101.962138 -512.080931) (xy 101.976362 -512.053756) (xy 101.983666 -512.023965) (xy 101.984048 -512.008628)
			(xy 101.984048 -499.982236) (xy 101.983586 -499.966909) (xy 101.976272 -499.937141) (xy 101.962081 -499.90997)
			(xy 101.952298 -499.898162) (xy 101.934352 -499.877135) (xy 101.904082 -499.830879) (xy 101.880807 -499.780739)
			(xy 101.865012 -499.727764) (xy 101.85703 -499.673064) (xy 101.857026 -499.617784) (xy 101.865002 -499.563083)
			(xy 101.88079 -499.510106) (xy 101.904059 -499.459963) (xy 101.934322 -499.413703) (xy 101.952298 -499.392702)
			(xy 101.962138 -499.380931) (xy 101.976362 -499.353756) (xy 101.983666 -499.323965) (xy 101.984048 -499.308628)
			(xy 101.984048 -487.282236) (xy 101.983586 -487.266909) (xy 101.976272 -487.237141) (xy 101.962081 -487.20997)
			(xy 101.952298 -487.198162) (xy 101.934352 -487.177135) (xy 101.904082 -487.130879) (xy 101.880807 -487.080739)
			(xy 101.865012 -487.027764) (xy 101.85703 -486.973064) (xy 101.857026 -486.917784) (xy 101.865002 -486.863083)
			(xy 101.88079 -486.810106) (xy 101.904059 -486.759963) (xy 101.934322 -486.713703) (xy 101.952298 -486.692702)
			(xy 101.962138 -486.680931) (xy 101.976362 -486.653756) (xy 101.983666 -486.623965) (xy 101.984048 -486.608628)
			(xy 101.984048 -474.582236) (xy 101.983586 -474.566909) (xy 101.976272 -474.537141) (xy 101.962081 -474.50997)
			(xy 101.952298 -474.498162) (xy 101.934352 -474.477135) (xy 101.904082 -474.430879) (xy 101.880807 -474.380739)
			(xy 101.865012 -474.327764) (xy 101.85703 -474.273064) (xy 101.857026 -474.217784) (xy 101.865002 -474.163083)
			(xy 101.88079 -474.110106) (xy 101.904059 -474.059963) (xy 101.934322 -474.013703) (xy 101.952298 -473.992702)
			(xy 101.962138 -473.980931) (xy 101.976362 -473.953756) (xy 101.983666 -473.923965) (xy 101.984048 -473.908628)
			(xy 101.984048 -461.882236) (xy 101.983586 -461.866909) (xy 101.976272 -461.837141) (xy 101.962081 -461.80997)
			(xy 101.952298 -461.798162) (xy 101.934352 -461.777135) (xy 101.904082 -461.730879) (xy 101.880807 -461.680739)
			(xy 101.865012 -461.627764) (xy 101.85703 -461.573064) (xy 101.857026 -461.517784) (xy 101.865002 -461.463083)
			(xy 101.88079 -461.410106) (xy 101.904059 -461.359963) (xy 101.934322 -461.313703) (xy 101.952298 -461.292702)
			(xy 101.962138 -461.280931) (xy 101.976362 -461.253756) (xy 101.983666 -461.223965) (xy 101.984048 -461.208628)
			(xy 101.984048 -449.182236) (xy 101.983586 -449.166909) (xy 101.976272 -449.137141) (xy 101.962081 -449.10997)
			(xy 101.952298 -449.098162) (xy 101.934352 -449.077135) (xy 101.904082 -449.030879) (xy 101.880807 -448.980739)
			(xy 101.865012 -448.927764) (xy 101.85703 -448.873064) (xy 101.857026 -448.817784) (xy 101.865002 -448.763083)
			(xy 101.88079 -448.710106) (xy 101.904059 -448.659963) (xy 101.934322 -448.613703) (xy 101.952298 -448.592702)
			(xy 101.962138 -448.580931) (xy 101.976362 -448.553756) (xy 101.983666 -448.523965) (xy 101.984048 -448.508628)
			(xy 101.984048 -436.482236) (xy 101.983586 -436.466909) (xy 101.976272 -436.437141) (xy 101.962081 -436.40997)
			(xy 101.952298 -436.398162) (xy 101.934352 -436.377135) (xy 101.904082 -436.330879) (xy 101.880807 -436.280739)
			(xy 101.865012 -436.227764) (xy 101.85703 -436.173064) (xy 101.857026 -436.117784) (xy 101.865002 -436.063083)
			(xy 101.88079 -436.010106) (xy 101.904059 -435.959963) (xy 101.934322 -435.913703) (xy 101.952298 -435.892702)
			(xy 101.962138 -435.880931) (xy 101.976362 -435.853756) (xy 101.983666 -435.823965) (xy 101.984048 -435.808628)
			(xy 101.984048 -423.782236) (xy 101.983586 -423.766909) (xy 101.976272 -423.737141) (xy 101.962081 -423.70997)
			(xy 101.952298 -423.698162) (xy 101.934352 -423.677135) (xy 101.904082 -423.630879) (xy 101.880807 -423.580739)
			(xy 101.865012 -423.527764) (xy 101.85703 -423.473064) (xy 101.857026 -423.417784) (xy 101.865002 -423.363083)
			(xy 101.88079 -423.310106) (xy 101.904059 -423.259963) (xy 101.934322 -423.213703) (xy 101.952298 -423.192702)
			(xy 101.962138 -423.180931) (xy 101.976362 -423.153756) (xy 101.983666 -423.123965) (xy 101.984048 -423.108628)
			(xy 101.984048 -411.082236) (xy 101.983586 -411.066909) (xy 101.976272 -411.037141) (xy 101.962081 -411.00997)
			(xy 101.952298 -410.998162) (xy 101.934352 -410.977135) (xy 101.904082 -410.930879) (xy 101.880807 -410.880739)
			(xy 101.865012 -410.827764) (xy 101.85703 -410.773064) (xy 101.857026 -410.717784) (xy 101.865002 -410.663083)
			(xy 101.88079 -410.610106) (xy 101.904059 -410.559963) (xy 101.934322 -410.513703) (xy 101.952298 -410.492702)
			(xy 101.962138 -410.480931) (xy 101.976362 -410.453756) (xy 101.983666 -410.423965) (xy 101.984048 -410.408628)
			(xy 101.984048 -398.382236) (xy 101.983586 -398.366909) (xy 101.976272 -398.337141) (xy 101.962081 -398.30997)
			(xy 101.952298 -398.298162) (xy 101.934352 -398.277135) (xy 101.904082 -398.230879) (xy 101.880807 -398.180739)
			(xy 101.865012 -398.127764) (xy 101.85703 -398.073064) (xy 101.857026 -398.017784) (xy 101.865002 -397.963083)
			(xy 101.88079 -397.910106) (xy 101.904059 -397.859963) (xy 101.934322 -397.813703) (xy 101.952298 -397.792702)
			(xy 101.962138 -397.780931) (xy 101.976362 -397.753756) (xy 101.983666 -397.723965) (xy 101.984048 -397.708628)
			(xy 101.984048 -385.682236) (xy 101.983586 -385.666909) (xy 101.976272 -385.637141) (xy 101.962081 -385.60997)
			(xy 101.952298 -385.598162) (xy 101.934352 -385.577135) (xy 101.904082 -385.530879) (xy 101.880807 -385.480739)
			(xy 101.865012 -385.427764) (xy 101.85703 -385.373064) (xy 101.857026 -385.317784) (xy 101.865002 -385.263083)
			(xy 101.88079 -385.210106) (xy 101.904059 -385.159963) (xy 101.934322 -385.113703) (xy 101.952298 -385.092702)
			(xy 101.962138 -385.080931) (xy 101.976362 -385.053756) (xy 101.983666 -385.023965) (xy 101.984048 -385.008628)
			(xy 101.984048 -372.982236) (xy 101.983586 -372.966909) (xy 101.976272 -372.937141) (xy 101.962081 -372.90997)
			(xy 101.952298 -372.898162) (xy 101.934352 -372.877135) (xy 101.904082 -372.830879) (xy 101.880807 -372.780739)
			(xy 101.865012 -372.727764) (xy 101.85703 -372.673064) (xy 101.857026 -372.617784) (xy 101.865002 -372.563083)
			(xy 101.88079 -372.510106) (xy 101.904059 -372.459963) (xy 101.934322 -372.413703) (xy 101.952298 -372.392702)
			(xy 101.962138 -372.380931) (xy 101.976362 -372.353756) (xy 101.983666 -372.323965) (xy 101.984048 -372.308628)
			(xy 101.984048 -360.282236) (xy 101.983586 -360.266909) (xy 101.976272 -360.237141) (xy 101.962081 -360.20997)
			(xy 101.952298 -360.198162) (xy 101.934352 -360.177135) (xy 101.904082 -360.130879) (xy 101.880807 -360.080739)
			(xy 101.865012 -360.027764) (xy 101.85703 -359.973064) (xy 101.857026 -359.917784) (xy 101.865002 -359.863083)
			(xy 101.88079 -359.810106) (xy 101.904059 -359.759963) (xy 101.934322 -359.713703) (xy 101.952298 -359.692702)
			(xy 101.962138 -359.680931) (xy 101.976362 -359.653756) (xy 101.983666 -359.623965) (xy 101.984048 -359.608628)
			(xy 101.984048 -347.582236) (xy 101.983586 -347.566909) (xy 101.976272 -347.537141) (xy 101.962081 -347.50997)
			(xy 101.952298 -347.498162) (xy 101.934352 -347.477135) (xy 101.904082 -347.430879) (xy 101.880807 -347.380739)
			(xy 101.865012 -347.327764) (xy 101.85703 -347.273064) (xy 101.857026 -347.217784) (xy 101.865002 -347.163083)
			(xy 101.88079 -347.110106) (xy 101.904059 -347.059963) (xy 101.934322 -347.013703) (xy 101.952298 -346.992702)
			(xy 101.962138 -346.980931) (xy 101.976362 -346.953756) (xy 101.983666 -346.923965) (xy 101.984048 -346.908628)
			(xy 101.984048 -334.882236) (xy 101.983586 -334.866909) (xy 101.976272 -334.837141) (xy 101.962081 -334.80997)
			(xy 101.952298 -334.798162) (xy 101.934352 -334.777135) (xy 101.904082 -334.730879) (xy 101.880807 -334.680739)
			(xy 101.865012 -334.627764) (xy 101.85703 -334.573064) (xy 101.857026 -334.517784) (xy 101.865002 -334.463083)
			(xy 101.88079 -334.410106) (xy 101.904059 -334.359963) (xy 101.934322 -334.313703) (xy 101.952298 -334.292702)
			(xy 101.962138 -334.280931) (xy 101.976362 -334.253756) (xy 101.983666 -334.223965) (xy 101.984048 -334.208628)
			(xy 101.984048 -322.182236) (xy 101.983586 -322.166909) (xy 101.976272 -322.137141) (xy 101.962081 -322.10997)
			(xy 101.952298 -322.098162) (xy 101.934352 -322.077135) (xy 101.904082 -322.030879) (xy 101.880807 -321.980739)
			(xy 101.865012 -321.927764) (xy 101.85703 -321.873064) (xy 101.857026 -321.817784) (xy 101.865002 -321.763083)
			(xy 101.88079 -321.710106) (xy 101.904059 -321.659963) (xy 101.934322 -321.613703) (xy 101.952298 -321.592702)
			(xy 101.962138 -321.580931) (xy 101.976362 -321.553756) (xy 101.983666 -321.523965) (xy 101.984048 -321.508628)
			(xy 101.984048 -309.482236) (xy 101.983586 -309.466909) (xy 101.976272 -309.437141) (xy 101.962081 -309.40997)
			(xy 101.952298 -309.398162) (xy 101.934352 -309.377135) (xy 101.904082 -309.330879) (xy 101.880807 -309.280739)
			(xy 101.865012 -309.227764) (xy 101.85703 -309.173064) (xy 101.857026 -309.117784) (xy 101.865002 -309.063083)
			(xy 101.88079 -309.010106) (xy 101.904059 -308.959963) (xy 101.934322 -308.913703) (xy 101.952298 -308.892702)
			(xy 101.962138 -308.880931) (xy 101.976362 -308.853756) (xy 101.983666 -308.823965) (xy 101.984048 -308.808628)
			(xy 101.984048 -296.782236) (xy 101.983586 -296.766909) (xy 101.976272 -296.737141) (xy 101.962081 -296.70997)
			(xy 101.952298 -296.698162) (xy 101.934352 -296.677135) (xy 101.904082 -296.630879) (xy 101.880807 -296.580739)
			(xy 101.865012 -296.527764) (xy 101.85703 -296.473064) (xy 101.857026 -296.417784) (xy 101.865002 -296.363083)
			(xy 101.88079 -296.310106) (xy 101.904059 -296.259963) (xy 101.934322 -296.213703) (xy 101.952298 -296.192702)
			(xy 101.962138 -296.180931) (xy 101.976362 -296.153756) (xy 101.983666 -296.123965) (xy 101.984048 -296.108628)
			(xy 101.984048 -284.082236) (xy 101.983586 -284.066909) (xy 101.976272 -284.037141) (xy 101.962081 -284.00997)
			(xy 101.952298 -283.998162) (xy 101.934352 -283.977135) (xy 101.904082 -283.930879) (xy 101.880807 -283.880739)
			(xy 101.865012 -283.827764) (xy 101.85703 -283.773064) (xy 101.857026 -283.717784) (xy 101.865002 -283.663083)
			(xy 101.88079 -283.610106) (xy 101.904059 -283.559963) (xy 101.934322 -283.513703) (xy 101.952298 -283.492702)
			(xy 101.962138 -283.480931) (xy 101.976362 -283.453756) (xy 101.983666 -283.423965) (xy 101.984048 -283.408628)
			(xy 101.984048 -271.382236) (xy 101.983586 -271.366909) (xy 101.976272 -271.337141) (xy 101.962081 -271.30997)
			(xy 101.952298 -271.298162) (xy 101.934352 -271.277135) (xy 101.904082 -271.230879) (xy 101.880807 -271.180739)
			(xy 101.865012 -271.127764) (xy 101.85703 -271.073064) (xy 101.857026 -271.017784) (xy 101.865002 -270.963083)
			(xy 101.88079 -270.910106) (xy 101.904059 -270.859963) (xy 101.934322 -270.813703) (xy 101.952298 -270.792702)
			(xy 101.962138 -270.780931) (xy 101.976362 -270.753756) (xy 101.983666 -270.723965) (xy 101.984048 -270.708628)
			(xy 101.984048 -258.682236) (xy 101.983586 -258.666909) (xy 101.976272 -258.637141) (xy 101.962081 -258.60997)
			(xy 101.952298 -258.598162) (xy 101.934352 -258.577135) (xy 101.904082 -258.530879) (xy 101.880807 -258.480739)
			(xy 101.865012 -258.427764) (xy 101.85703 -258.373064) (xy 101.857026 -258.317784) (xy 101.865002 -258.263083)
			(xy 101.88079 -258.210106) (xy 101.904059 -258.159963) (xy 101.934322 -258.113703) (xy 101.952298 -258.092702)
			(xy 101.962138 -258.080931) (xy 101.976362 -258.053756) (xy 101.983666 -258.023965) (xy 101.984048 -258.008628)
			(xy 101.984048 -245.982236) (xy 101.983586 -245.966909) (xy 101.976272 -245.937141) (xy 101.962081 -245.90997)
			(xy 101.952298 -245.898162) (xy 101.934352 -245.877135) (xy 101.904082 -245.830879) (xy 101.880807 -245.780739)
			(xy 101.865012 -245.727764) (xy 101.85703 -245.673064) (xy 101.857026 -245.617784) (xy 101.865002 -245.563083)
			(xy 101.88079 -245.510106) (xy 101.904059 -245.459963) (xy 101.934322 -245.413703) (xy 101.952298 -245.392702)
			(xy 101.962138 -245.380931) (xy 101.976362 -245.353756) (xy 101.983666 -245.323965) (xy 101.984048 -245.308628)
			(xy 101.984048 -233.282236) (xy 101.983586 -233.266909) (xy 101.976272 -233.237141) (xy 101.962081 -233.20997)
			(xy 101.952298 -233.198162) (xy 101.934352 -233.177135) (xy 101.904082 -233.130879) (xy 101.880807 -233.080739)
			(xy 101.865012 -233.027764) (xy 101.85703 -232.973064) (xy 101.857026 -232.917784) (xy 101.865002 -232.863083)
			(xy 101.88079 -232.810106) (xy 101.904059 -232.759963) (xy 101.934322 -232.713703) (xy 101.952298 -232.692702)
			(xy 101.962138 -232.680931) (xy 101.976362 -232.653756) (xy 101.983666 -232.623965) (xy 101.984048 -232.608628)
			(xy 101.984048 -220.582236) (xy 101.983586 -220.566909) (xy 101.976272 -220.537141) (xy 101.962081 -220.50997)
			(xy 101.952298 -220.498162) (xy 101.934352 -220.477135) (xy 101.904082 -220.430879) (xy 101.880807 -220.380739)
			(xy 101.865012 -220.327764) (xy 101.85703 -220.273064) (xy 101.857026 -220.217784) (xy 101.865002 -220.163083)
			(xy 101.88079 -220.110106) (xy 101.904059 -220.059963) (xy 101.934322 -220.013703) (xy 101.952298 -219.992702)
			(xy 101.962138 -219.980931) (xy 101.976362 -219.953756) (xy 101.983666 -219.923965) (xy 101.984048 -219.908628)
			(xy 101.984048 -207.882236) (xy 101.983586 -207.866909) (xy 101.976272 -207.837141) (xy 101.962081 -207.80997)
			(xy 101.952298 -207.798162) (xy 101.934352 -207.777135) (xy 101.904082 -207.730879) (xy 101.880807 -207.680739)
			(xy 101.865012 -207.627764) (xy 101.85703 -207.573064) (xy 101.857026 -207.517784) (xy 101.865002 -207.463083)
			(xy 101.88079 -207.410106) (xy 101.904059 -207.359963) (xy 101.934322 -207.313703) (xy 101.952298 -207.292702)
			(xy 101.962138 -207.280931) (xy 101.976362 -207.253756) (xy 101.983666 -207.223965) (xy 101.984048 -207.208628)
			(xy 101.984048 -195.182236) (xy 101.983586 -195.166909) (xy 101.976272 -195.137141) (xy 101.962081 -195.10997)
			(xy 101.952298 -195.098162) (xy 101.934352 -195.077135) (xy 101.904082 -195.030879) (xy 101.880807 -194.980739)
			(xy 101.865012 -194.927764) (xy 101.85703 -194.873064) (xy 101.857026 -194.817784) (xy 101.865002 -194.763083)
			(xy 101.88079 -194.710106) (xy 101.904059 -194.659963) (xy 101.934322 -194.613703) (xy 101.952298 -194.592702)
			(xy 101.962138 -194.580931) (xy 101.976362 -194.553756) (xy 101.983666 -194.523965) (xy 101.984048 -194.508628)
			(xy 101.984048 -182.482236) (xy 101.983586 -182.466909) (xy 101.976272 -182.437141) (xy 101.962081 -182.40997)
			(xy 101.952298 -182.398162) (xy 101.934352 -182.377135) (xy 101.904082 -182.330879) (xy 101.880807 -182.280739)
			(xy 101.865012 -182.227764) (xy 101.85703 -182.173064) (xy 101.857026 -182.117784) (xy 101.865002 -182.063083)
			(xy 101.88079 -182.010106) (xy 101.904059 -181.959963) (xy 101.934322 -181.913703) (xy 101.952298 -181.892702)
			(xy 101.962138 -181.880931) (xy 101.976362 -181.853756) (xy 101.983666 -181.823965) (xy 101.984048 -181.808628)
			(xy 101.984048 -169.782236) (xy 101.983586 -169.766909) (xy 101.976272 -169.737141) (xy 101.962081 -169.70997)
			(xy 101.952298 -169.698162) (xy 101.934352 -169.677135) (xy 101.904082 -169.630879) (xy 101.880807 -169.580739)
			(xy 101.865012 -169.527764) (xy 101.85703 -169.473064) (xy 101.857026 -169.417784) (xy 101.865002 -169.363083)
			(xy 101.88079 -169.310106) (xy 101.904059 -169.259963) (xy 101.934322 -169.213703) (xy 101.952298 -169.192702)
			(xy 101.962138 -169.180931) (xy 101.976362 -169.153756) (xy 101.983666 -169.123965) (xy 101.984048 -169.108628)
			(xy 101.984048 -157.082236) (xy 101.983586 -157.066909) (xy 101.976272 -157.037141) (xy 101.962081 -157.00997)
			(xy 101.952298 -156.998162) (xy 101.934352 -156.977135) (xy 101.904082 -156.930879) (xy 101.880807 -156.880739)
			(xy 101.865012 -156.827764) (xy 101.85703 -156.773064) (xy 101.857026 -156.717784) (xy 101.865002 -156.663083)
			(xy 101.88079 -156.610106) (xy 101.904059 -156.559963) (xy 101.934322 -156.513703) (xy 101.952298 -156.492702)
			(xy 101.962138 -156.480931) (xy 101.976362 -156.453756) (xy 101.983666 -156.423965) (xy 101.984048 -156.408628)
			(xy 101.984048 -144.382236) (xy 101.983586 -144.366909) (xy 101.976272 -144.337141) (xy 101.962081 -144.30997)
			(xy 101.952298 -144.298162) (xy 101.934352 -144.277135) (xy 101.904082 -144.230879) (xy 101.880807 -144.180739)
			(xy 101.865012 -144.127764) (xy 101.85703 -144.073064) (xy 101.857026 -144.017784) (xy 101.865002 -143.963083)
			(xy 101.88079 -143.910106) (xy 101.904059 -143.859963) (xy 101.934322 -143.813703) (xy 101.952298 -143.792702)
			(xy 101.962138 -143.780931) (xy 101.976362 -143.753756) (xy 101.983666 -143.723965) (xy 101.984048 -143.708628)
			(xy 101.984048 -131.682236) (xy 101.983586 -131.666909) (xy 101.976272 -131.637141) (xy 101.962081 -131.60997)
			(xy 101.952298 -131.598162) (xy 101.934352 -131.577135) (xy 101.904082 -131.530879) (xy 101.880807 -131.480739)
			(xy 101.865012 -131.427764) (xy 101.85703 -131.373064) (xy 101.857026 -131.317784) (xy 101.865002 -131.263083)
			(xy 101.88079 -131.210106) (xy 101.904059 -131.159963) (xy 101.934322 -131.113703) (xy 101.952298 -131.092702)
			(xy 101.962138 -131.080931) (xy 101.976362 -131.053756) (xy 101.983666 -131.023965) (xy 101.984048 -131.008628)
			(xy 101.984048 -118.982236) (xy 101.983586 -118.966909) (xy 101.976272 -118.937141) (xy 101.962081 -118.90997)
			(xy 101.952298 -118.898162) (xy 101.934352 -118.877135) (xy 101.904082 -118.830879) (xy 101.880807 -118.780739)
			(xy 101.865012 -118.727764) (xy 101.85703 -118.673064) (xy 101.857026 -118.617784) (xy 101.865002 -118.563083)
			(xy 101.88079 -118.510106) (xy 101.904059 -118.459963) (xy 101.934322 -118.413703) (xy 101.952298 -118.392702)
			(xy 101.962138 -118.380931) (xy 101.976362 -118.353756) (xy 101.983666 -118.323965) (xy 101.984048 -118.308628)
			(xy 101.984048 -106.282236) (xy 101.983586 -106.266909) (xy 101.976272 -106.237141) (xy 101.962081 -106.20997)
			(xy 101.952298 -106.198162) (xy 101.934352 -106.177135) (xy 101.904082 -106.130879) (xy 101.880807 -106.080739)
			(xy 101.865012 -106.027764) (xy 101.85703 -105.973064) (xy 101.857026 -105.917784) (xy 101.865002 -105.863083)
			(xy 101.88079 -105.810106) (xy 101.904059 -105.759963) (xy 101.934322 -105.713703) (xy 101.952298 -105.692702)
			(xy 101.962138 -105.680931) (xy 101.976362 -105.653756) (xy 101.983666 -105.623965) (xy 101.984048 -105.608628)
			(xy 101.984048 -93.582236) (xy 101.983586 -93.566909) (xy 101.976272 -93.537141) (xy 101.962081 -93.50997)
			(xy 101.952298 -93.498162) (xy 101.934352 -93.477135) (xy 101.904082 -93.430879) (xy 101.880807 -93.380739)
			(xy 101.865012 -93.327764) (xy 101.85703 -93.273064) (xy 101.857026 -93.217784) (xy 101.865002 -93.163083)
			(xy 101.88079 -93.110106) (xy 101.904059 -93.059963) (xy 101.934322 -93.013703) (xy 101.952298 -92.992702)
			(xy 101.962138 -92.980931) (xy 101.976362 -92.953756) (xy 101.983666 -92.923965) (xy 101.984048 -92.908628)
			(xy 101.984048 -80.882236) (xy 101.983586 -80.866909) (xy 101.976272 -80.837141) (xy 101.962081 -80.80997)
			(xy 101.952298 -80.798162) (xy 101.934352 -80.777135) (xy 101.904082 -80.730879) (xy 101.880807 -80.680739)
			(xy 101.865012 -80.627764) (xy 101.85703 -80.573064) (xy 101.857026 -80.517784) (xy 101.865002 -80.463083)
			(xy 101.88079 -80.410106) (xy 101.904059 -80.359963) (xy 101.934322 -80.313703) (xy 101.952298 -80.292702)
			(xy 101.962138 -80.280931) (xy 101.976362 -80.253756) (xy 101.983666 -80.223965) (xy 101.984048 -80.208628)
			(xy 101.984048 -68.182236) (xy 101.983586 -68.166909) (xy 101.976272 -68.137141) (xy 101.962081 -68.10997)
			(xy 101.952298 -68.098162) (xy 101.934352 -68.077135) (xy 101.904082 -68.030879) (xy 101.880807 -67.980739)
			(xy 101.865012 -67.927764) (xy 101.85703 -67.873064) (xy 101.857026 -67.817784) (xy 101.865002 -67.763083)
			(xy 101.88079 -67.710106) (xy 101.904059 -67.659963) (xy 101.934322 -67.613703) (xy 101.952298 -67.592702)
			(xy 101.962138 -67.580931) (xy 101.976362 -67.553756) (xy 101.983666 -67.523965) (xy 101.984048 -67.508628)
			(xy 101.984048 -55.482236) (xy 101.983586 -55.466909) (xy 101.976272 -55.437141) (xy 101.962081 -55.40997)
			(xy 101.952298 -55.398162) (xy 101.934352 -55.377135) (xy 101.904082 -55.330879) (xy 101.880807 -55.280739)
			(xy 101.865012 -55.227764) (xy 101.85703 -55.173064) (xy 101.857026 -55.117784) (xy 101.865002 -55.063083)
			(xy 101.88079 -55.010106) (xy 101.904059 -54.959963) (xy 101.934322 -54.913703) (xy 101.952298 -54.892702)
			(xy 101.962138 -54.880931) (xy 101.976362 -54.853756) (xy 101.983666 -54.823965) (xy 101.984048 -54.808628)
			(xy 101.984048 -42.782236) (xy 101.983586 -42.766909) (xy 101.976272 -42.737141) (xy 101.962081 -42.70997)
			(xy 101.952298 -42.698162) (xy 101.934352 -42.677135) (xy 101.904082 -42.630879) (xy 101.880807 -42.580739)
			(xy 101.865012 -42.527764) (xy 101.85703 -42.473064) (xy 101.857026 -42.417784) (xy 101.865002 -42.363083)
			(xy 101.88079 -42.310106) (xy 101.904059 -42.259963) (xy 101.934322 -42.213703) (xy 101.952298 -42.192702)
			(xy 101.962138 -42.180931) (xy 101.976362 -42.153756) (xy 101.983666 -42.123965) (xy 101.984048 -42.108628)
			(xy 101.984048 -30.082236) (xy 101.983586 -30.066909) (xy 101.976272 -30.037141) (xy 101.962081 -30.00997)
			(xy 101.952298 -29.998162) (xy 101.934352 -29.977135) (xy 101.904082 -29.930879) (xy 101.880807 -29.880739)
			(xy 101.865012 -29.827764) (xy 101.85703 -29.773064) (xy 101.857026 -29.717784) (xy 101.865002 -29.663083)
			(xy 101.88079 -29.610106) (xy 101.904059 -29.559963) (xy 101.934322 -29.513703) (xy 101.952298 -29.492702)
			(xy 101.962138 -29.480931) (xy 101.976362 -29.453756) (xy 101.983666 -29.423965) (xy 101.984048 -29.408628)
			(xy 101.984048 -17.382236) (xy 101.983586 -17.366909) (xy 101.976272 -17.337141) (xy 101.962081 -17.30997)
			(xy 101.952298 -17.298162) (xy 101.934352 -17.277135) (xy 101.904082 -17.230879) (xy 101.880807 -17.180739)
			(xy 101.865012 -17.127764) (xy 101.85703 -17.073064) (xy 101.857026 -17.017784) (xy 101.865002 -16.963083)
			(xy 101.88079 -16.910106) (xy 101.904059 -16.859963) (xy 101.934322 -16.813703) (xy 101.952298 -16.792702)
			(xy 101.962138 -16.780931) (xy 101.976362 -16.753756) (xy 101.983666 -16.723965) (xy 101.984048 -16.708628)
			(xy 101.984048 -4.682236) (xy 101.983586 -4.666909) (xy 101.976272 -4.637141) (xy 101.962081 -4.60997)
			(xy 101.952298 -4.598162) (xy 101.934352 -4.577135) (xy 101.904082 -4.530879) (xy 101.880807 -4.480739)
			(xy 101.865012 -4.427764) (xy 101.85703 -4.373064) (xy 101.857026 -4.317784) (xy 101.865002 -4.263083)
			(xy 101.88079 -4.210106) (xy 101.904059 -4.159963) (xy 101.934322 -4.113703) (xy 101.952298 -4.092702)
			(xy 101.962138 -4.080931) (xy 101.976362 -4.053756) (xy 101.983666 -4.023965) (xy 101.984048 -4.008628)
			(xy 101.984048 -1.999996) (xy 101.983539 -1.954528) (xy 101.975148 -1.863979) (xy 101.958437 -1.77459)
			(xy 101.93355 -1.687125) (xy 101.900699 -1.60233) (xy 101.860163 -1.520927) (xy 101.81229 -1.443612)
			(xy 101.757486 -1.371044) (xy 101.696221 -1.303842) (xy 101.629016 -1.242581) (xy 101.556445 -1.187781)
			(xy 101.479127 -1.139911) (xy 101.397723 -1.09938) (xy 101.312925 -1.066533) (xy 101.225459 -1.041651)
			(xy 101.13607 -1.024945) (xy 101.04552 -1.016559) (xy 101.000052 -1.016) (xy 95.642938 -1.016) (xy 95.55988 -1.047496)
			(xy 95.544386 -1.059942) (xy 95.521696 -1.077492) (xy 95.472092 -1.106297) (xy 95.418734 -1.127348)
			(xy 95.362825 -1.140172) (xy 95.305626 -1.144479) (xy 95.248427 -1.140172) (xy 95.192518 -1.127348)
			(xy 95.13916 -1.106297) (xy 95.089556 -1.077492) (xy 95.066866 -1.059942) (xy 95.051372 -1.047496)
			(xy 94.968314 -1.016) (xy 82.942938 -1.016) (xy 82.85988 -1.047496) (xy 82.844386 -1.059942) (xy 82.821696 -1.077492)
			(xy 82.772092 -1.106297) (xy 82.718734 -1.127348) (xy 82.662825 -1.140172) (xy 82.605626 -1.144479)
			(xy 82.548427 -1.140172) (xy 82.492518 -1.127348) (xy 82.43916 -1.106297) (xy 82.389556 -1.077492)
			(xy 82.366866 -1.059942) (xy 82.351372 -1.047496) (xy 82.268314 -1.016) (xy 70.242938 -1.016) (xy 70.15988 -1.047496)
			(xy 70.144386 -1.059942) (xy 70.121696 -1.077492) (xy 70.072092 -1.106297) (xy 70.018734 -1.127348)
			(xy 69.962825 -1.140172) (xy 69.905626 -1.144479) (xy 69.848427 -1.140172) (xy 69.792518 -1.127348)
			(xy 69.73916 -1.106297) (xy 69.689556 -1.077492) (xy 69.666866 -1.059942) (xy 69.651372 -1.047496)
			(xy 69.568314 -1.016) (xy 57.542938 -1.016) (xy 57.45988 -1.047496) (xy 57.444386 -1.059942) (xy 57.421696 -1.077492)
			(xy 57.372092 -1.106297) (xy 57.318734 -1.127348) (xy 57.262825 -1.140172) (xy 57.205626 -1.144479)
			(xy 57.148427 -1.140172) (xy 57.092518 -1.127348) (xy 57.03916 -1.106297) (xy 56.989556 -1.077492)
			(xy 56.966866 -1.059942) (xy 56.951372 -1.047496) (xy 56.868314 -1.016) (xy 44.842938 -1.016) (xy 44.75988 -1.047496)
			(xy 44.744386 -1.059942) (xy 44.721696 -1.077492) (xy 44.672092 -1.106297) (xy 44.618734 -1.127348)
			(xy 44.562825 -1.140172) (xy 44.505626 -1.144479) (xy 44.448427 -1.140172) (xy 44.392518 -1.127348)
			(xy 44.33916 -1.106297) (xy 44.289556 -1.077492) (xy 44.266866 -1.059942) (xy 44.251372 -1.047496)
			(xy 44.168314 -1.016) (xy 32.142938 -1.016) (xy 32.05988 -1.047496) (xy 32.044386 -1.059942) (xy 32.021696 -1.077492)
			(xy 31.972092 -1.106297) (xy 31.918734 -1.127348) (xy 31.862825 -1.140172) (xy 31.805626 -1.144479)
			(xy 31.748427 -1.140172) (xy 31.692518 -1.127348) (xy 31.63916 -1.106297) (xy 31.589556 -1.077492)
			(xy 31.566866 -1.059942) (xy 31.551372 -1.047496) (xy 31.468314 -1.016) (xy 26.500074 -1.016) (xy 26.468378 -1.01652)
			(xy 26.40553 -1.024797) (xy 26.3443 -1.041207) (xy 26.285735 -1.065469) (xy 26.230839 -1.097168)
			(xy 26.180549 -1.13576) (xy 26.135727 -1.180587) (xy 26.09714 -1.23088) (xy 26.065447 -1.28578) (xy 26.041191 -1.344347)
			(xy 26.024788 -1.405579) (xy 26.016517 -1.468428) (xy 26.01595 -1.500124) (xy 26.01595 -2.500122)
			(xy 26.015455 -2.570697) (xy 26.007541 -2.711624) (xy 25.991737 -2.851885) (xy 25.968093 -2.99104)
			(xy 25.936685 -3.12865) (xy 25.897609 -3.264283) (xy 25.850991 -3.397511) (xy 25.796975 -3.527916)
			(xy 25.735733 -3.655087) (xy 25.667456 -3.778624) (xy 25.59236 -3.898139) (xy 25.510681 -4.013254)
			(xy 25.422676 -4.123609) (xy 25.328622 -4.228856) (xy 25.228814 -4.328663) (xy 25.123568 -4.422717)
			(xy 25.013213 -4.510723) (xy 24.898097 -4.592401) (xy 24.778582 -4.667497) (xy 24.655045 -4.735774)
			(xy 24.527874 -4.797016) (xy 24.39747 -4.851032) (xy 24.264241 -4.89765) (xy 24.128608 -4.936725)
			(xy 23.990998 -4.968134) (xy 23.851843 -4.991777) (xy 23.711582 -5.007581) (xy 23.570655 -5.015495)
			(xy 23.50008 -5.015992) (xy 19.68881 -5.015992) (xy 19.674381 -5.048069) (xy 19.639436 -5.109113)
			(xy 19.597965 -5.165927) (xy 19.550477 -5.217815) (xy 19.49755 -5.264144) (xy 19.439833 -5.304347)
			(xy 19.37803 -5.337932) (xy 19.312897 -5.36449) (xy 19.24523 -5.383695) (xy 19.175857 -5.395313)
			(xy 19.105626 -5.399201) (xy 19.035395 -5.395313) (xy 18.966022 -5.383695) (xy 18.898355 -5.36449)
			(xy 18.833222 -5.337932) (xy 18.771419 -5.304347) (xy 18.713702 -5.264144) (xy 18.660775 -5.217815)
			(xy 18.613287 -5.165927) (xy 18.571816 -5.109113) (xy 18.536871 -5.048069) (xy 18.522442 -5.015992)
			(xy 6.743446 -5.015992) (xy 6.728061 -5.016462) (xy 6.698187 -5.023837) (xy 6.670945 -5.038144) (xy 6.659118 -5.047996)
			(xy 6.638059 -5.06606) (xy 6.5917 -5.096538) (xy 6.541414 -5.119978) (xy 6.488262 -5.135885) (xy 6.433366 -5.143923)
			(xy 6.377886 -5.143923) (xy 6.32299 -5.135885) (xy 6.269838 -5.119978) (xy 6.219552 -5.096538) (xy 6.173193 -5.06606)
			(xy 6.152134 -5.047996) (xy 6.140341 -5.038093) (xy 6.113091 -5.023766) (xy 6.0832 -5.016399) (xy 6.067806 -5.015992)
			(xy 1.500124 -5.015992) (xy 1.468427 -5.016511) (xy 1.405575 -5.024786) (xy 1.344341 -5.041194) (xy 1.285773 -5.065454)
			(xy 1.230872 -5.097152) (xy 1.180579 -5.135744) (xy 1.135752 -5.18057) (xy 1.09716 -5.230864) (xy 1.065463 -5.285765)
			(xy 1.041203 -5.344333) (xy 1.024795 -5.405567) (xy 1.01652 -5.468419) (xy 1.016 -5.500116) (xy 1.016 -6.91007)
			(xy 39.818063 -6.91007) (xy 39.82207 -6.794046) (xy 39.834072 -6.678574) (xy 39.854012 -6.564206)
			(xy 39.881795 -6.451486) (xy 39.917289 -6.340952) (xy 39.960324 -6.233129) (xy 40.010695 -6.128532)
			(xy 40.068162 -6.02766) (xy 40.132452 -5.930993) (xy 40.203257 -5.838992) (xy 40.280241 -5.752095)
			(xy 40.363037 -5.670716) (xy 40.45125 -5.595243) (xy 40.54446 -5.526036) (xy 40.642223 -5.463424)
			(xy 40.744072 -5.407707) (xy 40.849522 -5.359149) (xy 40.958071 -5.317981) (xy 41.069202 -5.284401)
			(xy 41.182385 -5.258568) (xy 41.29708 -5.240605) (xy 41.412742 -5.230597) (xy 41.528818 -5.228594)
			(xy 41.644756 -5.234603) (xy 41.760003 -5.248596) (xy 41.874009 -5.270507) (xy 41.986233 -5.300232)
			(xy 42.096139 -5.337628) (xy 42.203202 -5.382517) (xy 42.306914 -5.434686) (xy 42.406779 -5.493886)
			(xy 42.502322 -5.559835) (xy 42.593088 -5.632218) (xy 42.678643 -5.710691) (xy 42.758581 -5.794879)
			(xy 42.83252 -5.884381) (xy 42.900108 -5.978772) (xy 42.961022 -6.0776) (xy 43.014974 -6.180396)
			(xy 43.061704 -6.286669) (xy 43.100992 -6.395913) (xy 43.132649 -6.507606) (xy 43.156525 -6.621218)
			(xy 43.172506 -6.736206) (xy 43.180515 -6.852023) (xy 43.181016 -6.91007) (xy 43.180515 -6.968117)
			(xy 43.172506 -7.083934) (xy 43.156525 -7.198922) (xy 43.132649 -7.312534) (xy 43.100992 -7.424227)
			(xy 43.061704 -7.533471) (xy 43.014974 -7.639744) (xy 42.961022 -7.74254) (xy 42.900108 -7.841368)
			(xy 42.83252 -7.935759) (xy 42.758581 -8.025261) (xy 42.678643 -8.109449) (xy 42.593088 -8.187922)
			(xy 42.502604 -8.26008) (xy 93.154506 -8.26008) (xy 93.158522 -8.14381) (xy 93.170549 -8.028095)
			(xy 93.190531 -7.913485) (xy 93.218373 -7.800526) (xy 93.253942 -7.689758) (xy 93.297068 -7.581707)
			(xy 93.347545 -7.476889) (xy 93.405134 -7.375804) (xy 93.46956 -7.278932) (xy 93.540515 -7.186736)
			(xy 93.617662 -7.099655) (xy 93.700633 -7.018104) (xy 93.789033 -6.942472) (xy 93.88244 -6.873118)
			(xy 93.980409 -6.810375) (xy 94.082473 -6.754539) (xy 94.188147 -6.705878) (xy 94.296926 -6.664624)
			(xy 94.408291 -6.630973) (xy 94.521714 -6.605085) (xy 94.636651 -6.587084) (xy 94.752557 -6.577055)
			(xy 94.868879 -6.575047) (xy 94.985062 -6.581069) (xy 95.100553 -6.595092) (xy 95.214801 -6.61705)
			(xy 95.327262 -6.646837) (xy 95.4374 -6.684312) (xy 95.54469 -6.729297) (xy 95.648621 -6.781576)
			(xy 95.748697 -6.840901) (xy 95.844443 -6.906989) (xy 95.9354 -6.979525) (xy 96.021136 -7.058164)
			(xy 96.101243 -7.14253) (xy 96.175339 -7.232222) (xy 96.243069 -7.326812) (xy 96.304113 -7.42585)
			(xy 96.358178 -7.528863) (xy 96.405008 -7.63536) (xy 96.444379 -7.744835) (xy 96.476103 -7.856765)
			(xy 96.500029 -7.970617) (xy 96.516043 -8.085849) (xy 96.52407 -8.201911) (xy 96.524572 -8.26008)
			(xy 96.52407 -8.318249) (xy 96.516043 -8.434311) (xy 96.500029 -8.549543) (xy 96.476103 -8.663395)
			(xy 96.444379 -8.775325) (xy 96.405008 -8.8848) (xy 96.358178 -8.991297) (xy 96.304113 -9.09431)
			(xy 96.243069 -9.193348) (xy 96.175339 -9.287938) (xy 96.101243 -9.37763) (xy 96.021136 -9.461996)
			(xy 95.9354 -9.540635) (xy 95.844443 -9.613171) (xy 95.748697 -9.679259) (xy 95.648621 -9.738584)
			(xy 95.54469 -9.790863) (xy 95.4374 -9.835848) (xy 95.327262 -9.873323) (xy 95.214801 -9.90311) (xy 95.100553 -9.925068)
			(xy 94.985062 -9.939091) (xy 94.868879 -9.945113) (xy 94.752557 -9.943105) (xy 94.636651 -9.933076)
			(xy 94.521714 -9.915075) (xy 94.408291 -9.889187) (xy 94.296926 -9.855536) (xy 94.188147 -9.814282)
			(xy 94.082473 -9.765621) (xy 93.980409 -9.709785) (xy 93.88244 -9.647042) (xy 93.789033 -9.577688)
			(xy 93.700633 -9.502056) (xy 93.617662 -9.420505) (xy 93.540515 -9.333424) (xy 93.46956 -9.241228)
			(xy 93.405134 -9.144356) (xy 93.347545 -9.043271) (xy 93.297068 -8.938453) (xy 93.253942 -8.830402)
			(xy 93.218373 -8.719634) (xy 93.190531 -8.606675) (xy 93.170549 -8.492065) (xy 93.158522 -8.37635)
			(xy 93.154506 -8.26008) (xy 42.502604 -8.26008) (xy 42.502322 -8.260305) (xy 42.406779 -8.326254)
			(xy 42.306914 -8.385454) (xy 42.203202 -8.437623) (xy 42.096139 -8.482512) (xy 41.986233 -8.519908)
			(xy 41.874009 -8.549633) (xy 41.760003 -8.571544) (xy 41.644756 -8.585537) (xy 41.528818 -8.591546)
			(xy 41.412742 -8.589543) (xy 41.29708 -8.579535) (xy 41.182385 -8.561572) (xy 41.069202 -8.535739)
			(xy 40.958071 -8.502159) (xy 40.849522 -8.460991) (xy 40.744072 -8.412433) (xy 40.642223 -8.356716)
			(xy 40.54446 -8.294104) (xy 40.45125 -8.224897) (xy 40.363037 -8.149424) (xy 40.280241 -8.068045)
			(xy 40.203257 -7.981148) (xy 40.132452 -7.889147) (xy 40.068162 -7.79248) (xy 40.010695 -7.691608)
			(xy 39.960324 -7.587011) (xy 39.917289 -7.479188) (xy 39.881795 -7.368654) (xy 39.854012 -7.255934)
			(xy 39.834072 -7.141566) (xy 39.82207 -7.026094) (xy 39.818063 -6.91007) (xy 1.016 -6.91007) (xy 1.016 -12.879578)
			(xy 1.047496 -12.962382) (xy 1.059942 -12.977876) (xy 1.077482 -13.00057) (xy 1.106268 -13.050179)
			(xy 1.127305 -13.103537) (xy 1.14012 -13.159442) (xy 1.144423 -13.216636) (xy 1.14012 -13.27383)
			(xy 1.127305 -13.329735) (xy 1.106268 -13.383093) (xy 1.077482 -13.432702) (xy 1.059942 -13.455396)
			(xy 1.047496 -13.47089) (xy 1.016 -13.553694) (xy 1.016 -13.961618) (xy 1.016505 -13.984958) (xy 1.024982 -14.03086)
			(xy 1.0417 -14.074443) (xy 1.066095 -14.11424) (xy 1.097347 -14.148912) (xy 1.134405 -14.177295)
			(xy 1.176023 -14.198434) (xy 1.220801 -14.211617) (xy 1.267234 -14.216401) (xy 1.31376 -14.212626)
			(xy 1.358814 -14.200418) (xy 1.400881 -14.180188) (xy 1.438547 -14.152616) (xy 1.470544 -14.11863)
			(xy 1.483614 -14.099286) (xy 1.51897 -14.04535) (xy 1.595424 -13.941474) (xy 1.678157 -13.842526)
			(xy 1.766854 -13.748886) (xy 1.861174 -13.660913) (xy 1.960755 -13.578943) (xy 2.065217 -13.50329)
			(xy 2.174159 -13.434245) (xy 2.287163 -13.372072) (xy 2.403797 -13.317009) (xy 2.523615 -13.269267)
			(xy 2.646156 -13.229029) (xy 2.770952 -13.196448) (xy 2.897525 -13.171651) (xy 3.025389 -13.154731)
			(xy 3.154055 -13.145755) (xy 3.28303 -13.144755) (xy 3.411819 -13.151736) (xy 3.539931 -13.166671)
			(xy 3.666872 -13.189503) (xy 3.792159 -13.220144) (xy 3.915309 -13.258477) (xy 4.035852 -13.304356)
			(xy 4.153326 -13.357604) (xy 4.267281 -13.418018) (xy 4.37728 -13.485365) (xy 4.482903 -13.559389)
			(xy 4.583743 -13.639805) (xy 4.679415 -13.726305) (xy 4.769553 -13.818559) (xy 4.853811 -13.916212)
			(xy 4.931866 -14.01889) (xy 5.00342 -14.126201) (xy 5.068198 -14.237733) (xy 5.125952 -14.353059)
			(xy 5.17646 -14.471736) (xy 5.219531 -14.593311) (xy 5.254997 -14.717318) (xy 5.282724 -14.843281)
			(xy 5.302605 -14.970718) (xy 5.314565 -15.099141) (xy 5.318556 -15.228058) (xy 5.318556 -15.228062)
			(xy 12.580624 -15.228062) (xy 12.584655 -15.098496) (xy 12.596734 -14.969432) (xy 12.616813 -14.841368)
			(xy 12.644815 -14.714801) (xy 12.680632 -14.590218) (xy 12.724124 -14.468104) (xy 12.775124 -14.34893)
			(xy 12.833435 -14.233157) (xy 12.89883 -14.121233) (xy 12.971057 -14.013591) (xy 13.049837 -13.910648)
			(xy 13.134864 -13.812802) (xy 13.225809 -13.72043) (xy 13.322321 -13.633892) (xy 13.424027 -13.553521)
			(xy 13.530533 -13.479629) (xy 13.641426 -13.412501) (xy 13.756278 -13.352397) (xy 13.874645 -13.29955)
			(xy 13.996068 -13.254163) (xy 14.120078 -13.216414) (xy 14.246195 -13.186447) (xy 14.373931 -13.164378)
			(xy 14.502792 -13.150294) (xy 14.632279 -13.144248) (xy 14.761892 -13.146264) (xy 14.891128 -13.156334)
			(xy 15.019489 -13.174419) (xy 15.146477 -13.200449) (xy 15.271601 -13.234324) (xy 15.394377 -13.275912)
			(xy 15.51433 -13.325053) (xy 15.630995 -13.381556) (xy 15.743923 -13.445203) (xy 15.852675 -13.515747)
			(xy 15.956831 -13.592916) (xy 16.055988 -13.676411) (xy 16.149762 -13.765909) (xy 16.237791 -13.861064)
			(xy 16.319734 -13.961507) (xy 16.395273 -14.06685) (xy 16.464118 -14.176686) (xy 16.526001 -14.29059)
			(xy 16.580682 -14.40812) (xy 16.627952 -14.528823) (xy 16.667625 -14.652231) (xy 16.69955 -14.777867)
			(xy 16.723602 -14.905244) (xy 16.739689 -15.03387) (xy 16.747748 -15.163248) (xy 16.748252 -15.228062)
			(xy 16.747748 -15.292876) (xy 16.739689 -15.422254) (xy 16.723602 -15.55088) (xy 16.69955 -15.678257)
			(xy 16.667625 -15.803893) (xy 16.627952 -15.927301) (xy 16.580682 -16.048004) (xy 16.526001 -16.165534)
			(xy 16.464118 -16.279438) (xy 16.395273 -16.389274) (xy 16.319734 -16.494617) (xy 16.237791 -16.59506)
			(xy 16.149762 -16.690215) (xy 16.055988 -16.779713) (xy 15.956831 -16.863208) (xy 15.852675 -16.940377)
			(xy 15.743923 -17.010921) (xy 15.630995 -17.074568) (xy 15.51433 -17.131071) (xy 15.394377 -17.180212)
			(xy 15.271601 -17.2218) (xy 15.146477 -17.255675) (xy 15.019489 -17.281705) (xy 14.891128 -17.29979)
			(xy 14.761892 -17.30986) (xy 14.632279 -17.311876) (xy 14.502792 -17.30583) (xy 14.373931 -17.291746)
			(xy 14.246195 -17.269677) (xy 14.120078 -17.23971) (xy 13.996068 -17.201961) (xy 13.874645 -17.156574)
			(xy 13.756278 -17.103727) (xy 13.641426 -17.043623) (xy 13.530533 -16.976495) (xy 13.424027 -16.902603)
			(xy 13.322321 -16.822232) (xy 13.225809 -16.735694) (xy 13.134864 -16.643322) (xy 13.049837 -16.545476)
			(xy 12.971057 -16.442533) (xy 12.89883 -16.334891) (xy 12.833435 -16.222967) (xy 12.775124 -16.107194)
			(xy 12.724124 -15.98802) (xy 12.680632 -15.865906) (xy 12.644815 -15.741323) (xy 12.616813 -15.614756)
			(xy 12.596734 -15.486692) (xy 12.584655 -15.357628) (xy 12.580624 -15.228062) (xy 5.318556 -15.228062)
			(xy 5.314565 -15.356975) (xy 5.302606 -15.485398) (xy 5.282725 -15.612836) (xy 5.254998 -15.738799)
			(xy 5.219532 -15.862806) (xy 5.176462 -15.984381) (xy 5.125953 -16.103058) (xy 5.068199 -16.218384)
			(xy 5.003422 -16.329916) (xy 4.931868 -16.437227) (xy 4.853813 -16.539906) (xy 4.769555 -16.637559)
			(xy 4.679418 -16.729812) (xy 4.583745 -16.816313) (xy 4.482905 -16.896729) (xy 4.377283 -16.970753)
			(xy 4.267284 -17.038101) (xy 4.153329 -17.098514) (xy 4.035855 -17.151763) (xy 3.915312 -17.197642)
			(xy 3.792162 -17.235975) (xy 3.666876 -17.266617) (xy 3.539934 -17.289449) (xy 3.411823 -17.304384)
			(xy 3.283033 -17.311365) (xy 3.154058 -17.310366) (xy 3.025392 -17.301389) (xy 2.897528 -17.284469)
			(xy 2.770955 -17.259672) (xy 2.646159 -17.227092) (xy 2.523618 -17.186854) (xy 2.4038 -17.139112)
			(xy 2.287166 -17.084049) (xy 2.174161 -17.021876) (xy 2.06522 -16.952832) (xy 1.960758 -16.877179)
			(xy 1.861176 -16.79521) (xy 1.766856 -16.707236) (xy 1.67816 -16.613597) (xy 1.595426 -16.514649)
			(xy 1.518972 -16.410773) (xy 1.483614 -16.356838) (xy 1.470543 -16.337496) (xy 1.438545 -16.303511)
			(xy 1.400879 -16.275941) (xy 1.358813 -16.255713) (xy 1.31376 -16.243506) (xy 1.267235 -16.239732)
			(xy 1.220803 -16.244516) (xy 1.176026 -16.257699) (xy 1.134409 -16.278836) (xy 1.097351 -16.307218)
			(xy 1.066099 -16.34189) (xy 1.041704 -16.381685) (xy 1.024985 -16.425266) (xy 1.016506 -16.471167)
			(xy 1.016 -16.494506) (xy 1.016 -20.01012) (xy 86.877404 -20.01012) (xy 86.881424 -19.819469) (xy 86.893478 -19.629156)
			(xy 86.913544 -19.439521) (xy 86.941587 -19.2509) (xy 86.977556 -19.06363) (xy 87.021388 -18.878042)
			(xy 87.073005 -18.694467) (xy 87.132315 -18.513231) (xy 87.199213 -18.334656) (xy 87.273579 -18.159061)
			(xy 87.355281 -17.986756) (xy 87.444175 -17.818049) (xy 87.540101 -17.653239) (xy 87.64289 -17.49262)
			(xy 87.752359 -17.336477) (xy 87.868313 -17.185088) (xy 87.990547 -17.038721) (xy 88.118841 -16.897637)
			(xy 88.252969 -16.762088) (xy 88.392693 -16.632313) (xy 88.537763 -16.508543) (xy 88.687921 -16.391)
			(xy 88.842902 -16.279891) (xy 89.002429 -16.175414) (xy 89.166218 -16.077755) (xy 89.333978 -15.987088)
			(xy 89.505412 -15.903574) (xy 89.680214 -15.827361) (xy 89.858073 -15.758585) (xy 90.038674 -15.697367)
			(xy 90.221694 -15.643818) (xy 90.40681 -15.598032) (xy 90.593691 -15.56009) (xy 90.782006 -15.530061)
			(xy 90.971419 -15.507996) (xy 91.161593 -15.493937) (xy 91.352192 -15.487907) (xy 91.542875 -15.489917)
			(xy 91.733304 -15.499964) (xy 91.92314 -15.51803) (xy 92.112046 -15.544083) (xy 92.299685 -15.578076)
			(xy 92.485725 -15.619949) (xy 92.669834 -15.669628) (xy 92.851685 -15.727024) (xy 93.030955 -15.792035)
			(xy 93.207325 -15.864546) (xy 93.380481 -15.944427) (xy 93.550116 -16.031537) (xy 93.715928 -16.125721)
			(xy 93.877622 -16.226812) (xy 94.03491 -16.334628) (xy 94.187513 -16.44898) (xy 94.335161 -16.569663)
			(xy 94.477589 -16.696464) (xy 94.614545 -16.829155) (xy 94.745786 -16.967503) (xy 94.871078 -17.11126)
			(xy 94.990198 -17.260171) (xy 95.102934 -17.413972) (xy 95.209087 -17.572388) (xy 95.308467 -17.735139)
			(xy 95.400897 -17.901934) (xy 95.486214 -18.072478) (xy 95.564266 -18.246466) (xy 95.634913 -18.423591)
			(xy 95.698031 -18.603536) (xy 95.753507 -18.785982) (xy 95.801242 -18.970605) (xy 95.841152 -19.157075)
			(xy 95.873165 -19.345063) (xy 95.897225 -19.534233) (xy 95.913288 -19.724249) (xy 95.921327 -19.914773)
			(xy 95.92183 -20.01012) (xy 95.921327 -20.105467) (xy 95.913288 -20.295991) (xy 95.897225 -20.486007)
			(xy 95.873165 -20.675177) (xy 95.841152 -20.863165) (xy 95.801242 -21.049635) (xy 95.753507 -21.234258)
			(xy 95.698031 -21.416704) (xy 95.634913 -21.596649) (xy 95.564266 -21.773774) (xy 95.486214 -21.947762)
			(xy 95.400897 -22.118306) (xy 95.308467 -22.285101) (xy 95.209087 -22.447852) (xy 95.102934 -22.606268)
			(xy 94.990198 -22.760069) (xy 94.871078 -22.90898) (xy 94.745786 -23.052737) (xy 94.614545 -23.191085)
			(xy 94.477589 -23.323776) (xy 94.335161 -23.450577) (xy 94.187513 -23.57126) (xy 94.03491 -23.685612)
			(xy 93.877622 -23.793428) (xy 93.715928 -23.894519) (xy 93.550116 -23.988703) (xy 93.380481 -24.075813)
			(xy 93.207325 -24.155694) (xy 93.030955 -24.228205) (xy 92.851685 -24.293216) (xy 92.669834 -24.350612)
			(xy 92.485725 -24.400291) (xy 92.299685 -24.442164) (xy 92.112046 -24.476157) (xy 91.92314 -24.50221)
			(xy 91.733304 -24.520276) (xy 91.542875 -24.530323) (xy 91.352192 -24.532333) (xy 91.161593 -24.526303)
			(xy 90.971419 -24.512244) (xy 90.782006 -24.490179) (xy 90.593691 -24.46015) (xy 90.40681 -24.422208)
			(xy 90.221694 -24.376422) (xy 90.038674 -24.322873) (xy 89.858073 -24.261655) (xy 89.680214 -24.192879)
			(xy 89.505412 -24.116666) (xy 89.333978 -24.033152) (xy 89.166218 -23.942485) (xy 89.002429 -23.844826)
			(xy 88.842902 -23.740349) (xy 88.687921 -23.62924) (xy 88.537763 -23.511697) (xy 88.392693 -23.387927)
			(xy 88.252969 -23.258152) (xy 88.118841 -23.122603) (xy 87.990547 -22.981519) (xy 87.868313 -22.835152)
			(xy 87.752359 -22.683763) (xy 87.64289 -22.52762) (xy 87.540101 -22.367001) (xy 87.444175 -22.202191)
			(xy 87.355281 -22.033484) (xy 87.273579 -21.861179) (xy 87.199213 -21.685584) (xy 87.132315 -21.507009)
			(xy 87.073005 -21.325773) (xy 87.021388 -21.142198) (xy 86.977556 -20.95661) (xy 86.941587 -20.76934)
			(xy 86.913544 -20.580719) (xy 86.893478 -20.391084) (xy 86.881424 -20.200771) (xy 86.877404 -20.01012)
			(xy 1.016 -20.01012) (xy 1.016 -25.071578) (xy 1.047496 -25.154382) (xy 1.059942 -25.169876) (xy 1.077482 -25.19257)
			(xy 1.106268 -25.242179) (xy 1.127305 -25.295537) (xy 1.14012 -25.351442) (xy 1.144423 -25.408636)
			(xy 1.14012 -25.46583) (xy 1.127305 -25.521735) (xy 1.106268 -25.575093) (xy 1.077482 -25.624702)
			(xy 1.059942 -25.647396) (xy 1.047496 -25.66289) (xy 1.016 -25.745694) (xy 1.016 -29.19984) (xy 11.341362 -29.19984)
			(xy 11.345365 -28.994672) (xy 11.357371 -28.789816) (xy 11.377361 -28.585585) (xy 11.405303 -28.382289)
			(xy 11.441156 -28.180238) (xy 11.484865 -27.979739) (xy 11.536363 -27.781099) (xy 11.595572 -27.584619)
			(xy 11.662402 -27.390599) (xy 11.736751 -27.199334) (xy 11.818506 -27.011116) (xy 11.907542 -26.82623)
			(xy 12.003724 -26.64496) (xy 12.106905 -26.467579) (xy 12.216928 -26.29436) (xy 12.333626 -26.125565)
			(xy 12.456821 -25.961452) (xy 12.586324 -25.802271) (xy 12.72194 -25.648263) (xy 12.863462 -25.499664)
			(xy 13.010673 -25.356699) (xy 13.16335 -25.219587) (xy 13.321261 -25.088537) (xy 13.484164 -24.963747)
			(xy 13.651812 -24.845408) (xy 13.82395 -24.7337) (xy 14.000315 -24.628793) (xy 14.180639 -24.530847)
			(xy 14.364647 -24.440012) (xy 14.552059 -24.356424) (xy 14.742589 -24.280213) (xy 14.935948 -24.211493)
			(xy 15.131841 -24.15037) (xy 15.329969 -24.096936) (xy 15.530031 -24.051273) (xy 15.731723 -24.01345)
			(xy 15.934737 -23.983526) (xy 16.138763 -23.961545) (xy 16.343492 -23.947541) (xy 16.548612 -23.941536)
			(xy 16.753809 -23.943538) (xy 16.958772 -23.953544) (xy 17.163189 -23.97154) (xy 17.366748 -23.997498)
			(xy 17.569139 -24.031378) (xy 17.770054 -24.073128) (xy 17.969188 -24.122686) (xy 18.166236 -24.179976)
			(xy 18.360899 -24.24491) (xy 18.55288 -24.317389) (xy 18.741887 -24.397304) (xy 18.927632 -24.484532)
			(xy 19.109833 -24.57894) (xy 19.288211 -24.680386) (xy 19.462496 -24.788714) (xy 19.632421 -24.903759)
			(xy 19.797728 -25.025347) (xy 19.958166 -25.153292) (xy 20.113489 -25.287398) (xy 20.263462 -25.427463)
			(xy 20.407856 -25.573273) (xy 20.546451 -25.724605) (xy 20.679036 -25.88123) (xy 20.805409 -26.042908)
			(xy 20.925378 -26.209393) (xy 21.03876 -26.380433) (xy 21.145383 -26.555766) (xy 21.245083 -26.735126)
			(xy 21.33771 -26.918239) (xy 21.423122 -27.104826) (xy 21.501188 -27.294604) (xy 21.571791 -27.487283)
			(xy 21.634823 -27.68257) (xy 21.690187 -27.880168) (xy 21.7378 -28.079775) (xy 21.777588 -28.281088)
			(xy 21.809492 -28.4838) (xy 21.833462 -28.687603) (xy 21.849463 -28.892185) (xy 21.857469 -29.097236)
			(xy 21.85797 -29.19984) (xy 21.857469 -29.302444) (xy 21.849463 -29.507495) (xy 21.833462 -29.712077)
			(xy 21.809492 -29.91588) (xy 21.777588 -30.118592) (xy 21.7378 -30.319905) (xy 21.690187 -30.519512)
			(xy 21.634823 -30.71711) (xy 21.571791 -30.912397) (xy 21.501188 -31.105076) (xy 21.423122 -31.294854)
			(xy 21.33771 -31.481441) (xy 21.245083 -31.664554) (xy 21.145383 -31.843914) (xy 21.03876 -32.019247)
			(xy 20.925378 -32.190287) (xy 20.846567 -32.299656) (xy 72.864733 -32.299656) (xy 72.868742 -32.096785)
			(xy 72.880762 -31.894231) (xy 72.900776 -31.69231) (xy 72.928751 -31.491337) (xy 72.964644 -31.291627)
			(xy 73.008398 -31.09349) (xy 73.059947 -30.897237) (xy 73.119208 -30.703173) (xy 73.18609 -30.511602)
			(xy 73.260488 -30.322823) (xy 73.342286 -30.13713) (xy 73.431356 -29.954814) (xy 73.527559 -29.776159)
			(xy 73.630746 -29.601445) (xy 73.740754 -29.430943) (xy 73.857412 -29.26492) (xy 73.980538 -29.103636)
			(xy 74.10994 -28.947342) (xy 74.245415 -28.796282) (xy 74.386752 -28.650692) (xy 74.533731 -28.5108)
			(xy 74.686122 -28.376824) (xy 74.843687 -28.248972) (xy 75.00618 -28.127446) (xy 75.173347 -28.012433)
			(xy 75.344927 -27.904115) (xy 75.520652 -27.80266) (xy 75.700249 -27.708226) (xy 75.883436 -27.620961)
			(xy 76.069928 -27.541002) (xy 76.259433 -27.468473) (xy 76.451655 -27.403487) (xy 76.646295 -27.346145)
			(xy 76.843048 -27.296538) (xy 77.041607 -27.254743) (xy 77.241663 -27.220825) (xy 77.442902 -27.194837)
			(xy 77.645011 -27.176819) (xy 77.847674 -27.1668) (xy 78.050574 -27.164796) (xy 78.253395 -27.170808)
			(xy 78.455821 -27.184829) (xy 78.657534 -27.206837) (xy 78.858221 -27.236796) (xy 79.057567 -27.27466)
			(xy 79.255262 -27.32037) (xy 79.450996 -27.373854) (xy 79.644465 -27.43503) (xy 79.835366 -27.503801)
			(xy 80.023401 -27.580061) (xy 80.208277 -27.663689) (xy 80.389704 -27.754556) (xy 80.5674 -27.852519)
			(xy 80.741086 -27.957427) (xy 80.910493 -28.069114) (xy 81.075355 -28.187406) (xy 81.235415 -28.31212)
			(xy 81.390423 -28.443059) (xy 81.540137 -28.58002) (xy 81.684323 -28.722789) (xy 81.822757 -28.871143)
			(xy 81.955221 -29.02485) (xy 82.08151 -29.18367) (xy 82.201425 -29.347355) (xy 82.314781 -29.51565)
			(xy 82.421399 -29.688292) (xy 82.521113 -29.865012) (xy 82.613768 -30.045532) (xy 82.699218 -30.229572)
			(xy 82.777332 -30.416845) (xy 82.847985 -30.607057) (xy 82.911069 -30.799912) (xy 82.966485 -30.995109)
			(xy 83.014146 -31.192342) (xy 83.053977 -31.391305) (xy 83.085917 -31.591686) (xy 83.109916 -31.793172)
			(xy 83.125936 -31.995449) (xy 83.133953 -32.198201) (xy 83.134454 -32.299656) (xy 83.133953 -32.401111)
			(xy 83.125936 -32.603863) (xy 83.109916 -32.80614) (xy 83.085917 -33.007626) (xy 83.053977 -33.208007)
			(xy 83.014146 -33.40697) (xy 82.966485 -33.604203) (xy 82.911069 -33.7994) (xy 82.847985 -33.992255)
			(xy 82.777332 -34.182467) (xy 82.699218 -34.36974) (xy 82.613768 -34.55378) (xy 82.521113 -34.7343)
			(xy 82.421399 -34.91102) (xy 82.314781 -35.083662) (xy 82.201425 -35.251957) (xy 82.08151 -35.415642)
			(xy 81.955221 -35.574462) (xy 81.822757 -35.728169) (xy 81.684323 -35.876523) (xy 81.540137 -36.019292)
			(xy 81.390423 -36.156253) (xy 81.235415 -36.287192) (xy 81.075355 -36.411906) (xy 80.910493 -36.530198)
			(xy 80.741086 -36.641885) (xy 80.5674 -36.746793) (xy 80.389704 -36.844756) (xy 80.208277 -36.935623)
			(xy 80.023401 -37.019251) (xy 79.835366 -37.095511) (xy 79.644465 -37.164282) (xy 79.450996 -37.225458)
			(xy 79.255262 -37.278942) (xy 79.057567 -37.324652) (xy 78.858221 -37.362516) (xy 78.657534 -37.392475)
			(xy 78.455821 -37.414483) (xy 78.253395 -37.428504) (xy 78.050574 -37.434516) (xy 77.847674 -37.432512)
			(xy 77.645011 -37.422493) (xy 77.442902 -37.404475) (xy 77.241663 -37.378487) (xy 77.041607 -37.344569)
			(xy 76.843048 -37.302774) (xy 76.646295 -37.253167) (xy 76.451655 -37.195825) (xy 76.259433 -37.130839)
			(xy 76.069928 -37.05831) (xy 75.883436 -36.978351) (xy 75.700249 -36.891086) (xy 75.520652 -36.796652)
			(xy 75.344927 -36.695197) (xy 75.173347 -36.586879) (xy 75.00618 -36.471866) (xy 74.843687 -36.35034)
			(xy 74.686122 -36.222488) (xy 74.533731 -36.088512) (xy 74.386752 -35.94862) (xy 74.245415 -35.80303)
			(xy 74.10994 -35.65197) (xy 73.980538 -35.495676) (xy 73.857412 -35.334392) (xy 73.740754 -35.168369)
			(xy 73.630746 -34.997867) (xy 73.527559 -34.823153) (xy 73.431356 -34.644498) (xy 73.342286 -34.462182)
			(xy 73.260488 -34.276489) (xy 73.18609 -34.08771) (xy 73.119208 -33.896139) (xy 73.059947 -33.702075)
			(xy 73.008398 -33.505822) (xy 72.964644 -33.307685) (xy 72.928751 -33.107975) (xy 72.900776 -32.907002)
			(xy 72.880762 -32.705081) (xy 72.868742 -32.502527) (xy 72.864733 -32.299656) (xy 20.846567 -32.299656)
			(xy 20.805409 -32.356772) (xy 20.679036 -32.51845) (xy 20.546451 -32.675075) (xy 20.407856 -32.826407)
			(xy 20.263462 -32.972217) (xy 20.113489 -33.112282) (xy 19.958166 -33.246388) (xy 19.797728 -33.374333)
			(xy 19.632421 -33.495921) (xy 19.462496 -33.610966) (xy 19.288211 -33.719294) (xy 19.109833 -33.82074)
			(xy 18.927632 -33.915148) (xy 18.741887 -34.002376) (xy 18.55288 -34.082291) (xy 18.360899 -34.15477)
			(xy 18.166236 -34.219704) (xy 17.969188 -34.276994) (xy 17.770054 -34.326552) (xy 17.569139 -34.368302)
			(xy 17.366748 -34.402182) (xy 17.163189 -34.42814) (xy 16.958772 -34.446136) (xy 16.753809 -34.456142)
			(xy 16.548612 -34.458144) (xy 16.343492 -34.452139) (xy 16.138763 -34.438135) (xy 15.934737 -34.416154)
			(xy 15.731723 -34.38623) (xy 15.530031 -34.348407) (xy 15.329969 -34.302744) (xy 15.131841 -34.24931)
			(xy 14.935948 -34.188187) (xy 14.742589 -34.119467) (xy 14.552059 -34.043256) (xy 14.364647 -33.959668)
			(xy 14.180639 -33.868833) (xy 14.000315 -33.770887) (xy 13.82395 -33.66598) (xy 13.651812 -33.554272)
			(xy 13.484164 -33.435933) (xy 13.321261 -33.311143) (xy 13.16335 -33.180093) (xy 13.010673 -33.042981)
			(xy 12.863462 -32.900016) (xy 12.72194 -32.751417) (xy 12.586324 -32.597409) (xy 12.456821 -32.438228)
			(xy 12.333626 -32.274115) (xy 12.216928 -32.10532) (xy 12.106905 -31.932101) (xy 12.003724 -31.75472)
			(xy 11.907542 -31.57345) (xy 11.818506 -31.388564) (xy 11.736751 -31.200346) (xy 11.662402 -31.009081)
			(xy 11.595572 -30.815061) (xy 11.536363 -30.618581) (xy 11.484865 -30.419941) (xy 11.441156 -30.219442)
			(xy 11.405303 -30.017391) (xy 11.377361 -29.814095) (xy 11.357371 -29.609864) (xy 11.345365 -29.405008)
			(xy 11.341362 -29.19984) (xy 1.016 -29.19984) (xy 1.016 -37.771578) (xy 1.047496 -37.854382) (xy 1.059942 -37.869876)
			(xy 1.077482 -37.89257) (xy 1.106268 -37.942179) (xy 1.127305 -37.995537) (xy 1.14012 -38.051442)
			(xy 1.144423 -38.108636) (xy 1.14012 -38.16583) (xy 1.127305 -38.221735) (xy 1.106268 -38.275093)
			(xy 1.077482 -38.324702) (xy 1.059942 -38.347396) (xy 1.047496 -38.36289) (xy 1.016 -38.445694) (xy 1.016 -44.95546)
			(xy 1.016504 -44.9788) (xy 1.024982 -45.024704) (xy 1.041699 -45.068287) (xy 1.066094 -45.108085)
			(xy 1.097346 -45.142758) (xy 1.134405 -45.171142) (xy 1.176024 -45.192281) (xy 1.220803 -45.205465)
			(xy 1.267237 -45.210249) (xy 1.313763 -45.206474) (xy 1.358818 -45.194266) (xy 1.400886 -45.174035)
			(xy 1.438552 -45.146463) (xy 1.47055 -45.112476) (xy 1.483614 -45.093128) (xy 1.51897 -45.039192)
			(xy 1.595424 -44.935316) (xy 1.678157 -44.836368) (xy 1.766854 -44.742728) (xy 1.861173 -44.654754)
			(xy 1.960754 -44.572785) (xy 2.065216 -44.497132) (xy 2.174158 -44.428087) (xy 2.287162 -44.365914)
			(xy 2.403796 -44.310851) (xy 2.523614 -44.263109) (xy 2.646155 -44.22287) (xy 2.770951 -44.19029)
			(xy 2.897523 -44.165492) (xy 3.025387 -44.148573) (xy 3.154053 -44.139596) (xy 3.283028 -44.138596)
			(xy 3.411818 -44.145576) (xy 3.539929 -44.160511) (xy 3.66687 -44.183343) (xy 3.792157 -44.213984)
			(xy 3.915307 -44.252318) (xy 4.03585 -44.298196) (xy 4.153324 -44.351444) (xy 4.267279 -44.411858)
			(xy 4.377278 -44.479205) (xy 4.482901 -44.553229) (xy 4.583741 -44.633645) (xy 4.679413 -44.720145)
			(xy 4.769551 -44.812398) (xy 4.853809 -44.910051) (xy 4.931864 -45.01273) (xy 5.003418 -45.12004)
			(xy 5.068196 -45.231572) (xy 5.12595 -45.346897) (xy 5.176459 -45.465575) (xy 5.219529 -45.58715)
			(xy 5.254996 -45.711156) (xy 5.282723 -45.83712) (xy 5.302604 -45.964557) (xy 5.314563 -46.09298)
			(xy 5.318555 -46.221897) (xy 5.318555 -46.221904) (xy 12.580624 -46.221904) (xy 12.584655 -46.092338)
			(xy 12.596734 -45.963274) (xy 12.616813 -45.83521) (xy 12.644815 -45.708643) (xy 12.680632 -45.58406)
			(xy 12.724124 -45.461946) (xy 12.775124 -45.342772) (xy 12.833435 -45.226999) (xy 12.89883 -45.115075)
			(xy 12.971057 -45.007433) (xy 13.049837 -44.90449) (xy 13.134864 -44.806644) (xy 13.225809 -44.714272)
			(xy 13.322321 -44.627734) (xy 13.424027 -44.547363) (xy 13.530533 -44.473471) (xy 13.641426 -44.406343)
			(xy 13.756278 -44.346239) (xy 13.874645 -44.293392) (xy 13.996068 -44.248005) (xy 14.120078 -44.210256)
			(xy 14.246195 -44.180289) (xy 14.373931 -44.15822) (xy 14.502792 -44.144136) (xy 14.632279 -44.13809)
			(xy 14.761892 -44.140106) (xy 14.891128 -44.150176) (xy 15.019489 -44.168261) (xy 15.146477 -44.194291)
			(xy 15.271601 -44.228166) (xy 15.394377 -44.269754) (xy 15.51433 -44.318895) (xy 15.630995 -44.375398)
			(xy 15.743923 -44.439045) (xy 15.852675 -44.509589) (xy 15.956831 -44.586758) (xy 16.055988 -44.670253)
			(xy 16.149762 -44.759751) (xy 16.237791 -44.854906) (xy 16.319734 -44.955349) (xy 16.395273 -45.060692)
			(xy 16.464118 -45.170528) (xy 16.526001 -45.284432) (xy 16.580682 -45.401962) (xy 16.627952 -45.522665)
			(xy 16.667625 -45.646073) (xy 16.69955 -45.771709) (xy 16.723602 -45.899086) (xy 16.739689 -46.027712)
			(xy 16.747748 -46.15709) (xy 16.748252 -46.221904) (xy 16.747748 -46.286718) (xy 16.739689 -46.416096)
			(xy 16.723602 -46.544722) (xy 16.69955 -46.672099) (xy 16.667625 -46.797735) (xy 16.627952 -46.921143)
			(xy 16.580682 -47.041846) (xy 16.526001 -47.159376) (xy 16.464118 -47.27328) (xy 16.395273 -47.383116)
			(xy 16.319734 -47.488459) (xy 16.237791 -47.588902) (xy 16.149762 -47.684057) (xy 16.055988 -47.773555)
			(xy 15.956831 -47.85705) (xy 15.852675 -47.934219) (xy 15.743923 -48.004763) (xy 15.630995 -48.06841)
			(xy 15.51433 -48.124913) (xy 15.394377 -48.174054) (xy 15.271601 -48.215642) (xy 15.146477 -48.249517)
			(xy 15.019489 -48.275547) (xy 14.891128 -48.293632) (xy 14.761892 -48.303702) (xy 14.632279 -48.305718)
			(xy 14.502792 -48.299672) (xy 14.373931 -48.285588) (xy 14.246195 -48.263519) (xy 14.120078 -48.233552)
			(xy 13.996068 -48.195803) (xy 13.874645 -48.150416) (xy 13.756278 -48.097569) (xy 13.641426 -48.037465)
			(xy 13.530533 -47.970337) (xy 13.424027 -47.896445) (xy 13.322321 -47.816074) (xy 13.225809 -47.729536)
			(xy 13.134864 -47.637164) (xy 13.049837 -47.539318) (xy 12.971057 -47.436375) (xy 12.89883 -47.328733)
			(xy 12.833435 -47.216809) (xy 12.775124 -47.101036) (xy 12.724124 -46.981862) (xy 12.680632 -46.859748)
			(xy 12.644815 -46.735165) (xy 12.616813 -46.608598) (xy 12.596734 -46.480534) (xy 12.584655 -46.35147)
			(xy 12.580624 -46.221904) (xy 5.318555 -46.221904) (xy 5.314564 -46.350814) (xy 5.302605 -46.479237)
			(xy 5.282724 -46.606674) (xy 5.254997 -46.732637) (xy 5.219531 -46.856644) (xy 5.176461 -46.978219)
			(xy 5.125953 -47.096896) (xy 5.068199 -47.212222) (xy 5.003422 -47.323754) (xy 4.931868 -47.431065)
			(xy 4.853813 -47.533744) (xy 4.769556 -47.631397) (xy 4.679418 -47.72365) (xy 4.583746 -47.810151)
			(xy 4.482906 -47.890567) (xy 4.377284 -47.964591) (xy 4.267285 -48.031939) (xy 4.15333 -48.092353)
			(xy 4.035857 -48.145601) (xy 3.915313 -48.19148) (xy 3.792163 -48.229814) (xy 3.666877 -48.260455)
			(xy 3.539935 -48.283288) (xy 3.411824 -48.298223) (xy 3.283035 -48.305204) (xy 3.15406 -48.304205)
			(xy 3.025394 -48.295228) (xy 2.89753 -48.278309) (xy 2.770957 -48.253512) (xy 2.646161 -48.220932)
			(xy 2.52362 -48.180694) (xy 2.403802 -48.132952) (xy 2.287168 -48.077889) (xy 2.174163 -48.015716)
			(xy 2.065222 -47.946672) (xy 1.96076 -47.87102) (xy 1.861178 -47.78905) (xy 1.766858 -47.701077)
			(xy 1.678162 -47.607437) (xy 1.595428 -47.50849) (xy 1.518974 -47.404613) (xy 1.483614 -47.35068)
			(xy 1.470543 -47.331338) (xy 1.438545 -47.297353) (xy 1.40088 -47.269783) (xy 1.358813 -47.249554)
			(xy 1.31376 -47.237347) (xy 1.267235 -47.233573) (xy 1.220803 -47.238357) (xy 1.176026 -47.25154)
			(xy 1.134409 -47.272678) (xy 1.097351 -47.301059) (xy 1.066099 -47.335731) (xy 1.041704 -47.375527)
			(xy 1.024986 -47.419108) (xy 1.016507 -47.465009) (xy 1.016 -47.488348) (xy 1.016 -50.471578) (xy 1.047496 -50.554382)
			(xy 1.059942 -50.569876) (xy 1.077482 -50.59257) (xy 1.106268 -50.642179) (xy 1.127305 -50.695537)
			(xy 1.14012 -50.751442) (xy 1.144423 -50.808636) (xy 1.14012 -50.86583) (xy 1.127305 -50.921735)
			(xy 1.106268 -50.975093) (xy 1.077482 -51.024702) (xy 1.059942 -51.047396) (xy 1.047496 -51.06289)
			(xy 1.016 -51.145694) (xy 1.016 -51.36007) (xy 39.818063 -51.36007) (xy 39.82207 -51.244046) (xy 39.834072 -51.128574)
			(xy 39.854012 -51.014206) (xy 39.881795 -50.901486) (xy 39.917289 -50.790952) (xy 39.960324 -50.683129)
			(xy 40.010695 -50.578532) (xy 40.068162 -50.47766) (xy 40.132452 -50.380993) (xy 40.203257 -50.288992)
			(xy 40.280241 -50.202095) (xy 40.363037 -50.120716) (xy 40.45125 -50.045243) (xy 40.54446 -49.976036)
			(xy 40.642223 -49.913424) (xy 40.744072 -49.857707) (xy 40.849522 -49.809149) (xy 40.958071 -49.767981)
			(xy 41.069202 -49.734401) (xy 41.182385 -49.708568) (xy 41.29708 -49.690605) (xy 41.412742 -49.680597)
			(xy 41.528818 -49.678594) (xy 41.644756 -49.684603) (xy 41.760003 -49.698596) (xy 41.874009 -49.720507)
			(xy 41.986233 -49.750232) (xy 42.096139 -49.787628) (xy 42.203202 -49.832517) (xy 42.306914 -49.884686)
			(xy 42.406779 -49.943886) (xy 42.502322 -50.009835) (xy 42.593088 -50.082218) (xy 42.678643 -50.160691)
			(xy 42.758581 -50.244879) (xy 42.83252 -50.334381) (xy 42.900108 -50.428772) (xy 42.961022 -50.5276)
			(xy 43.014974 -50.630396) (xy 43.061704 -50.736669) (xy 43.100992 -50.845913) (xy 43.132649 -50.957606)
			(xy 43.156525 -51.071218) (xy 43.172506 -51.186206) (xy 43.180515 -51.302023) (xy 43.181016 -51.36007)
			(xy 43.180515 -51.418117) (xy 43.172506 -51.533934) (xy 43.156525 -51.648922) (xy 43.132649 -51.762534)
			(xy 43.100992 -51.874227) (xy 43.061704 -51.983471) (xy 43.014974 -52.089744) (xy 42.961022 -52.19254)
			(xy 42.900108 -52.291368) (xy 42.83252 -52.385759) (xy 42.758581 -52.475261) (xy 42.678643 -52.559449)
			(xy 42.593088 -52.637922) (xy 42.502604 -52.71008) (xy 93.154506 -52.71008) (xy 93.158522 -52.59381)
			(xy 93.170549 -52.478095) (xy 93.190531 -52.363485) (xy 93.218373 -52.250526) (xy 93.253942 -52.139758)
			(xy 93.297068 -52.031707) (xy 93.347545 -51.926889) (xy 93.405134 -51.825804) (xy 93.46956 -51.728932)
			(xy 93.540515 -51.636736) (xy 93.617662 -51.549655) (xy 93.700633 -51.468104) (xy 93.789033 -51.392472)
			(xy 93.88244 -51.323118) (xy 93.980409 -51.260375) (xy 94.082473 -51.204539) (xy 94.188147 -51.155878)
			(xy 94.296926 -51.114624) (xy 94.408291 -51.080973) (xy 94.521714 -51.055085) (xy 94.636651 -51.037084)
			(xy 94.752557 -51.027055) (xy 94.868879 -51.025047) (xy 94.985062 -51.031069) (xy 95.100553 -51.045092)
			(xy 95.214801 -51.06705) (xy 95.327262 -51.096837) (xy 95.4374 -51.134312) (xy 95.54469 -51.179297)
			(xy 95.648621 -51.231576) (xy 95.748697 -51.290901) (xy 95.844443 -51.356989) (xy 95.9354 -51.429525)
			(xy 96.021136 -51.508164) (xy 96.101243 -51.59253) (xy 96.175339 -51.682222) (xy 96.243069 -51.776812)
			(xy 96.304113 -51.87585) (xy 96.358178 -51.978863) (xy 96.405008 -52.08536) (xy 96.444379 -52.194835)
			(xy 96.476103 -52.306765) (xy 96.500029 -52.420617) (xy 96.516043 -52.535849) (xy 96.52407 -52.651911)
			(xy 96.524572 -52.71008) (xy 96.52407 -52.768249) (xy 96.516043 -52.884311) (xy 96.500029 -52.999543)
			(xy 96.476103 -53.113395) (xy 96.444379 -53.225325) (xy 96.405008 -53.3348) (xy 96.358178 -53.441297)
			(xy 96.304113 -53.54431) (xy 96.243069 -53.643348) (xy 96.175339 -53.737938) (xy 96.101243 -53.82763)
			(xy 96.021136 -53.911996) (xy 95.9354 -53.990635) (xy 95.844443 -54.063171) (xy 95.748697 -54.129259)
			(xy 95.648621 -54.188584) (xy 95.54469 -54.240863) (xy 95.4374 -54.285848) (xy 95.327262 -54.323323)
			(xy 95.214801 -54.35311) (xy 95.100553 -54.375068) (xy 94.985062 -54.389091) (xy 94.868879 -54.395113)
			(xy 94.752557 -54.393105) (xy 94.636651 -54.383076) (xy 94.521714 -54.365075) (xy 94.408291 -54.339187)
			(xy 94.296926 -54.305536) (xy 94.188147 -54.264282) (xy 94.082473 -54.215621) (xy 93.980409 -54.159785)
			(xy 93.88244 -54.097042) (xy 93.789033 -54.027688) (xy 93.700633 -53.952056) (xy 93.617662 -53.870505)
			(xy 93.540515 -53.783424) (xy 93.46956 -53.691228) (xy 93.405134 -53.594356) (xy 93.347545 -53.493271)
			(xy 93.297068 -53.388453) (xy 93.253942 -53.280402) (xy 93.218373 -53.169634) (xy 93.190531 -53.056675)
			(xy 93.170549 -52.942065) (xy 93.158522 -52.82635) (xy 93.154506 -52.71008) (xy 42.502604 -52.71008)
			(xy 42.502322 -52.710305) (xy 42.406779 -52.776254) (xy 42.306914 -52.835454) (xy 42.203202 -52.887623)
			(xy 42.096139 -52.932512) (xy 41.986233 -52.969908) (xy 41.874009 -52.999633) (xy 41.760003 -53.021544)
			(xy 41.644756 -53.035537) (xy 41.528818 -53.041546) (xy 41.412742 -53.039543) (xy 41.29708 -53.029535)
			(xy 41.182385 -53.011572) (xy 41.069202 -52.985739) (xy 40.958071 -52.952159) (xy 40.849522 -52.910991)
			(xy 40.744072 -52.862433) (xy 40.642223 -52.806716) (xy 40.54446 -52.744104) (xy 40.45125 -52.674897)
			(xy 40.363037 -52.599424) (xy 40.280241 -52.518045) (xy 40.203257 -52.431148) (xy 40.132452 -52.339147)
			(xy 40.068162 -52.24248) (xy 40.010695 -52.141608) (xy 39.960324 -52.037011) (xy 39.917289 -51.929188)
			(xy 39.881795 -51.818654) (xy 39.854012 -51.705934) (xy 39.834072 -51.591566) (xy 39.82207 -51.476094)
			(xy 39.818063 -51.36007) (xy 1.016 -51.36007) (xy 1.016 -63.171578) (xy 1.047496 -63.254382) (xy 1.059942 -63.269876)
			(xy 1.077482 -63.29257) (xy 1.106268 -63.342179) (xy 1.127305 -63.395537) (xy 1.14012 -63.451442)
			(xy 1.144423 -63.508636) (xy 1.14012 -63.56583) (xy 1.127305 -63.621735) (xy 1.106268 -63.675093)
			(xy 1.077482 -63.724702) (xy 1.059942 -63.747396) (xy 1.047496 -63.76289) (xy 1.016 -63.845694) (xy 1.016 -64.46012)
			(xy 86.877404 -64.46012) (xy 86.881424 -64.269469) (xy 86.893478 -64.079156) (xy 86.913544 -63.889521)
			(xy 86.941587 -63.7009) (xy 86.977556 -63.51363) (xy 87.021388 -63.328042) (xy 87.073005 -63.144467)
			(xy 87.132315 -62.963231) (xy 87.199213 -62.784656) (xy 87.273579 -62.609061) (xy 87.355281 -62.436756)
			(xy 87.444175 -62.268049) (xy 87.540101 -62.103239) (xy 87.64289 -61.94262) (xy 87.752359 -61.786477)
			(xy 87.868313 -61.635088) (xy 87.990547 -61.488721) (xy 88.118841 -61.347637) (xy 88.252969 -61.212088)
			(xy 88.392693 -61.082313) (xy 88.537763 -60.958543) (xy 88.687921 -60.841) (xy 88.842902 -60.729891)
			(xy 89.002429 -60.625414) (xy 89.166218 -60.527755) (xy 89.333978 -60.437088) (xy 89.505412 -60.353574)
			(xy 89.680214 -60.277361) (xy 89.858073 -60.208585) (xy 90.038674 -60.147367) (xy 90.221694 -60.093818)
			(xy 90.40681 -60.048032) (xy 90.593691 -60.01009) (xy 90.782006 -59.980061) (xy 90.971419 -59.957996)
			(xy 91.161593 -59.943937) (xy 91.352192 -59.937907) (xy 91.542875 -59.939917) (xy 91.733304 -59.949964)
			(xy 91.92314 -59.96803) (xy 92.112046 -59.994083) (xy 92.299685 -60.028076) (xy 92.485725 -60.069949)
			(xy 92.669834 -60.119628) (xy 92.851685 -60.177024) (xy 93.030955 -60.242035) (xy 93.207325 -60.314546)
			(xy 93.380481 -60.394427) (xy 93.550116 -60.481537) (xy 93.715928 -60.575721) (xy 93.877622 -60.676812)
			(xy 94.03491 -60.784628) (xy 94.187513 -60.89898) (xy 94.335161 -61.019663) (xy 94.477589 -61.146464)
			(xy 94.614545 -61.279155) (xy 94.745786 -61.417503) (xy 94.871078 -61.56126) (xy 94.990198 -61.710171)
			(xy 95.102934 -61.863972) (xy 95.209087 -62.022388) (xy 95.308467 -62.185139) (xy 95.400897 -62.351934)
			(xy 95.486214 -62.522478) (xy 95.564266 -62.696466) (xy 95.634913 -62.873591) (xy 95.698031 -63.053536)
			(xy 95.753507 -63.235982) (xy 95.801242 -63.420605) (xy 95.841152 -63.607075) (xy 95.873165 -63.795063)
			(xy 95.897225 -63.984233) (xy 95.913288 -64.174249) (xy 95.921327 -64.364773) (xy 95.92183 -64.46012)
			(xy 95.921327 -64.555467) (xy 95.913288 -64.745991) (xy 95.897225 -64.936007) (xy 95.873165 -65.125177)
			(xy 95.841152 -65.313165) (xy 95.801242 -65.499635) (xy 95.753507 -65.684258) (xy 95.698031 -65.866704)
			(xy 95.634913 -66.046649) (xy 95.564266 -66.223774) (xy 95.486214 -66.397762) (xy 95.400897 -66.568306)
			(xy 95.308467 -66.735101) (xy 95.209087 -66.897852) (xy 95.102934 -67.056268) (xy 94.990198 -67.210069)
			(xy 94.871078 -67.35898) (xy 94.745786 -67.502737) (xy 94.614545 -67.641085) (xy 94.477589 -67.773776)
			(xy 94.335161 -67.900577) (xy 94.187513 -68.02126) (xy 94.03491 -68.135612) (xy 93.877622 -68.243428)
			(xy 93.715928 -68.344519) (xy 93.550116 -68.438703) (xy 93.380481 -68.525813) (xy 93.207325 -68.605694)
			(xy 93.030955 -68.678205) (xy 92.851685 -68.743216) (xy 92.669834 -68.800612) (xy 92.485725 -68.850291)
			(xy 92.299685 -68.892164) (xy 92.112046 -68.926157) (xy 91.92314 -68.95221) (xy 91.733304 -68.970276)
			(xy 91.542875 -68.980323) (xy 91.352192 -68.982333) (xy 91.161593 -68.976303) (xy 90.971419 -68.962244)
			(xy 90.782006 -68.940179) (xy 90.593691 -68.91015) (xy 90.40681 -68.872208) (xy 90.221694 -68.826422)
			(xy 90.038674 -68.772873) (xy 89.858073 -68.711655) (xy 89.680214 -68.642879) (xy 89.505412 -68.566666)
			(xy 89.333978 -68.483152) (xy 89.166218 -68.392485) (xy 89.002429 -68.294826) (xy 88.842902 -68.190349)
			(xy 88.687921 -68.07924) (xy 88.537763 -67.961697) (xy 88.392693 -67.837927) (xy 88.252969 -67.708152)
			(xy 88.118841 -67.572603) (xy 87.990547 -67.431519) (xy 87.868313 -67.285152) (xy 87.752359 -67.133763)
			(xy 87.64289 -66.97762) (xy 87.540101 -66.817001) (xy 87.444175 -66.652191) (xy 87.355281 -66.483484)
			(xy 87.273579 -66.311179) (xy 87.199213 -66.135584) (xy 87.132315 -65.957009) (xy 87.073005 -65.775773)
			(xy 87.021388 -65.592198) (xy 86.977556 -65.40661) (xy 86.941587 -65.21934) (xy 86.913544 -65.030719)
			(xy 86.893478 -64.841084) (xy 86.881424 -64.650771) (xy 86.877404 -64.46012) (xy 1.016 -64.46012)
			(xy 1.016 -67.01155) (xy 1.016504 -67.03489) (xy 1.024982 -67.080794) (xy 1.041699 -67.124377) (xy 1.066094 -67.164175)
			(xy 1.097346 -67.198848) (xy 1.134405 -67.227232) (xy 1.176024 -67.248371) (xy 1.220803 -67.261555)
			(xy 1.267237 -67.266339) (xy 1.313763 -67.262564) (xy 1.358818 -67.250356) (xy 1.400886 -67.230125)
			(xy 1.438552 -67.202553) (xy 1.47055 -67.168566) (xy 1.483614 -67.149218) (xy 1.51897 -67.095282)
			(xy 1.595424 -66.991406) (xy 1.678157 -66.892458) (xy 1.766854 -66.798818) (xy 1.861173 -66.710844)
			(xy 1.960754 -66.628875) (xy 2.065216 -66.553222) (xy 2.174158 -66.484177) (xy 2.287162 -66.422004)
			(xy 2.403796 -66.366941) (xy 2.523614 -66.319199) (xy 2.646155 -66.27896) (xy 2.770951 -66.24638)
			(xy 2.897523 -66.221582) (xy 3.025387 -66.204663) (xy 3.154053 -66.195686) (xy 3.283028 -66.194686)
			(xy 3.411818 -66.201666) (xy 3.539929 -66.216601) (xy 3.66687 -66.239433) (xy 3.792157 -66.270074)
			(xy 3.915307 -66.308408) (xy 4.03585 -66.354286) (xy 4.153324 -66.407534) (xy 4.267279 -66.467948)
			(xy 4.377278 -66.535295) (xy 4.482901 -66.609319) (xy 4.583741 -66.689735) (xy 4.679413 -66.776235)
			(xy 4.769551 -66.868488) (xy 4.853809 -66.966141) (xy 4.931864 -67.06882) (xy 5.003418 -67.17613)
			(xy 5.068196 -67.287662) (xy 5.12595 -67.402987) (xy 5.176459 -67.521665) (xy 5.219529 -67.64324)
			(xy 5.254996 -67.767246) (xy 5.282723 -67.89321) (xy 5.302604 -68.020647) (xy 5.314563 -68.14907)
			(xy 5.318555 -68.277987) (xy 5.318555 -68.277994) (xy 12.580624 -68.277994) (xy 12.584655 -68.148428)
			(xy 12.596734 -68.019364) (xy 12.616813 -67.8913) (xy 12.644815 -67.764733) (xy 12.680632 -67.64015)
			(xy 12.724124 -67.518036) (xy 12.775124 -67.398862) (xy 12.833435 -67.283089) (xy 12.89883 -67.171165)
			(xy 12.971057 -67.063523) (xy 13.049837 -66.96058) (xy 13.134864 -66.862734) (xy 13.225809 -66.770362)
			(xy 13.322321 -66.683824) (xy 13.424027 -66.603453) (xy 13.530533 -66.529561) (xy 13.641426 -66.462433)
			(xy 13.756278 -66.402329) (xy 13.874645 -66.349482) (xy 13.996068 -66.304095) (xy 14.120078 -66.266346)
			(xy 14.246195 -66.236379) (xy 14.373931 -66.21431) (xy 14.502792 -66.200226) (xy 14.632279 -66.19418)
			(xy 14.761892 -66.196196) (xy 14.891128 -66.206266) (xy 15.019489 -66.224351) (xy 15.146477 -66.250381)
			(xy 15.271601 -66.284256) (xy 15.394377 -66.325844) (xy 15.51433 -66.374985) (xy 15.630995 -66.431488)
			(xy 15.743923 -66.495135) (xy 15.852675 -66.565679) (xy 15.956831 -66.642848) (xy 16.055988 -66.726343)
			(xy 16.149762 -66.815841) (xy 16.237791 -66.910996) (xy 16.319734 -67.011439) (xy 16.395273 -67.116782)
			(xy 16.464118 -67.226618) (xy 16.526001 -67.340522) (xy 16.580682 -67.458052) (xy 16.627952 -67.578755)
			(xy 16.667625 -67.702163) (xy 16.69955 -67.827799) (xy 16.723602 -67.955176) (xy 16.739689 -68.083802)
			(xy 16.747748 -68.21318) (xy 16.748252 -68.277994) (xy 16.747748 -68.342808) (xy 16.739689 -68.472186)
			(xy 16.723602 -68.600812) (xy 16.69955 -68.728189) (xy 16.667625 -68.853825) (xy 16.627952 -68.977233)
			(xy 16.580682 -69.097936) (xy 16.526001 -69.215466) (xy 16.464118 -69.32937) (xy 16.395273 -69.439206)
			(xy 16.319734 -69.544549) (xy 16.237791 -69.644992) (xy 16.149762 -69.740147) (xy 16.055988 -69.829645)
			(xy 15.956831 -69.91314) (xy 15.852675 -69.990309) (xy 15.743923 -70.060853) (xy 15.630995 -70.1245)
			(xy 15.51433 -70.181003) (xy 15.394377 -70.230144) (xy 15.271601 -70.271732) (xy 15.146477 -70.305607)
			(xy 15.019489 -70.331637) (xy 14.891128 -70.349722) (xy 14.761892 -70.359792) (xy 14.632279 -70.361808)
			(xy 14.502792 -70.355762) (xy 14.373931 -70.341678) (xy 14.246195 -70.319609) (xy 14.120078 -70.289642)
			(xy 13.996068 -70.251893) (xy 13.874645 -70.206506) (xy 13.756278 -70.153659) (xy 13.641426 -70.093555)
			(xy 13.530533 -70.026427) (xy 13.424027 -69.952535) (xy 13.322321 -69.872164) (xy 13.225809 -69.785626)
			(xy 13.134864 -69.693254) (xy 13.049837 -69.595408) (xy 12.971057 -69.492465) (xy 12.89883 -69.384823)
			(xy 12.833435 -69.272899) (xy 12.775124 -69.157126) (xy 12.724124 -69.037952) (xy 12.680632 -68.915838)
			(xy 12.644815 -68.791255) (xy 12.616813 -68.664688) (xy 12.596734 -68.536624) (xy 12.584655 -68.40756)
			(xy 12.580624 -68.277994) (xy 5.318555 -68.277994) (xy 5.314564 -68.406904) (xy 5.302605 -68.535327)
			(xy 5.282724 -68.662764) (xy 5.254997 -68.788727) (xy 5.219531 -68.912734) (xy 5.176461 -69.034309)
			(xy 5.125953 -69.152986) (xy 5.068199 -69.268312) (xy 5.003422 -69.379844) (xy 4.931868 -69.487155)
			(xy 4.853813 -69.589834) (xy 4.769556 -69.687487) (xy 4.679418 -69.77974) (xy 4.583746 -69.866241)
			(xy 4.482906 -69.946657) (xy 4.377284 -70.020681) (xy 4.267285 -70.088029) (xy 4.15333 -70.148443)
			(xy 4.035857 -70.201691) (xy 3.915313 -70.24757) (xy 3.792163 -70.285904) (xy 3.666877 -70.316545)
			(xy 3.539935 -70.339378) (xy 3.411824 -70.354313) (xy 3.283035 -70.361294) (xy 3.15406 -70.360295)
			(xy 3.025394 -70.351318) (xy 2.89753 -70.334399) (xy 2.770957 -70.309602) (xy 2.646161 -70.277022)
			(xy 2.52362 -70.236784) (xy 2.403802 -70.189042) (xy 2.287168 -70.133979) (xy 2.174163 -70.071806)
			(xy 2.065222 -70.002762) (xy 1.96076 -69.92711) (xy 1.861178 -69.84514) (xy 1.766858 -69.757167)
			(xy 1.678162 -69.663527) (xy 1.595428 -69.56458) (xy 1.518974 -69.460703) (xy 1.483614 -69.40677)
			(xy 1.470542 -69.387428) (xy 1.438544 -69.353445) (xy 1.400878 -69.325876) (xy 1.358811 -69.305648)
			(xy 1.313758 -69.293442) (xy 1.267234 -69.289667) (xy 1.220802 -69.294452) (xy 1.176025 -69.307634)
			(xy 1.134408 -69.328771) (xy 1.09735 -69.357153) (xy 1.066098 -69.391824) (xy 1.041702 -69.431618)
			(xy 1.024983 -69.475198) (xy 1.016503 -69.521099) (xy 1.016 -69.544438) (xy 1.016 -75.871578) (xy 1.047496 -75.954382)
			(xy 1.059942 -75.969876) (xy 1.077482 -75.99257) (xy 1.106268 -76.042179) (xy 1.127305 -76.095537)
			(xy 1.14012 -76.151442) (xy 1.144423 -76.208636) (xy 1.14012 -76.26583) (xy 1.127305 -76.321735)
			(xy 1.106268 -76.375093) (xy 1.077482 -76.424702) (xy 1.059942 -76.447396) (xy 1.047496 -76.46289)
			(xy 1.016 -76.545694) (xy 1.016 -78.378673) (xy 74.888081 -78.378673) (xy 74.888081 -78.220963) (xy 74.896069 -78.063456)
			(xy 74.912025 -77.906556) (xy 74.935906 -77.750665) (xy 74.967653 -77.596184) (xy 75.007183 -77.443509)
			(xy 75.054395 -77.293033) (xy 75.109169 -77.14514) (xy 75.171362 -77.000212) (xy 75.240817 -76.85862)
			(xy 75.317353 -76.720727) (xy 75.400776 -76.586888) (xy 75.49087 -76.457446) (xy 75.587405 -76.332733)
			(xy 75.690133 -76.21307) (xy 75.798789 -76.098763) (xy 75.913096 -75.990107) (xy 76.032759 -75.887379)
			(xy 76.157472 -75.790844) (xy 76.286914 -75.70075) (xy 76.420753 -75.617327) (xy 76.558646 -75.540791)
			(xy 76.700238 -75.471336) (xy 76.845166 -75.409143) (xy 76.993059 -75.354369) (xy 77.143535 -75.307157)
			(xy 77.29621 -75.267627) (xy 77.450691 -75.23588) (xy 77.606582 -75.211999) (xy 77.763482 -75.196043)
			(xy 77.920989 -75.188055) (xy 78.078699 -75.188055) (xy 78.236206 -75.196043) (xy 78.393106 -75.211999)
			(xy 78.548997 -75.23588) (xy 78.703478 -75.267627) (xy 78.856153 -75.307157) (xy 79.006629 -75.354369)
			(xy 79.154522 -75.409143) (xy 79.29945 -75.471336) (xy 79.441042 -75.540791) (xy 79.578935 -75.617327)
			(xy 79.712774 -75.70075) (xy 79.842216 -75.790844) (xy 79.966929 -75.887379) (xy 80.086592 -75.990107)
			(xy 80.200899 -76.098763) (xy 80.309555 -76.21307) (xy 80.412283 -76.332733) (xy 80.508818 -76.457446)
			(xy 80.598912 -76.586888) (xy 80.682335 -76.720727) (xy 80.758871 -76.85862) (xy 80.828326 -77.000212)
			(xy 80.890519 -77.14514) (xy 80.945293 -77.293033) (xy 80.992505 -77.443509) (xy 81.032035 -77.596184)
			(xy 81.063782 -77.750665) (xy 81.087663 -77.906556) (xy 81.103619 -78.063456) (xy 81.111607 -78.220963)
			(xy 81.112106 -78.299818) (xy 81.111607 -78.378673) (xy 81.103619 -78.53618) (xy 81.087663 -78.69308)
			(xy 81.063782 -78.848971) (xy 81.032035 -79.003452) (xy 80.992505 -79.156127) (xy 80.945293 -79.306603)
			(xy 80.890519 -79.454496) (xy 80.828326 -79.599424) (xy 80.758871 -79.741016) (xy 80.682335 -79.878909)
			(xy 80.598912 -80.012748) (xy 80.508818 -80.14219) (xy 80.412283 -80.266903) (xy 80.309555 -80.386566)
			(xy 80.200899 -80.500873) (xy 80.086592 -80.609529) (xy 79.966929 -80.712257) (xy 79.842216 -80.808792)
			(xy 79.712774 -80.898886) (xy 79.578935 -80.982309) (xy 79.441042 -81.058845) (xy 79.29945 -81.1283)
			(xy 79.154522 -81.190493) (xy 79.006629 -81.245267) (xy 78.856153 -81.292479) (xy 78.703478 -81.332009)
			(xy 78.548997 -81.363756) (xy 78.393106 -81.387637) (xy 78.236206 -81.403593) (xy 78.078699 -81.411581)
			(xy 77.920989 -81.411581) (xy 77.763482 -81.403593) (xy 77.606582 -81.387637) (xy 77.450691 -81.363756)
			(xy 77.29621 -81.332009) (xy 77.143535 -81.292479) (xy 76.993059 -81.245267) (xy 76.845166 -81.190493)
			(xy 76.700238 -81.1283) (xy 76.558646 -81.058845) (xy 76.420753 -80.982309) (xy 76.286914 -80.898886)
			(xy 76.157472 -80.808792) (xy 76.032759 -80.712257) (xy 75.913096 -80.609529) (xy 75.798789 -80.500873)
			(xy 75.690133 -80.386566) (xy 75.587405 -80.266903) (xy 75.49087 -80.14219) (xy 75.400776 -80.012748)
			(xy 75.317353 -79.878909) (xy 75.240817 -79.741016) (xy 75.171362 -79.599424) (xy 75.109169 -79.454496)
			(xy 75.054395 -79.306603) (xy 75.007183 -79.156127) (xy 74.967653 -79.003452) (xy 74.935906 -78.848971)
			(xy 74.912025 -78.69308) (xy 74.896069 -78.53618) (xy 74.888081 -78.378673) (xy 1.016 -78.378673)
			(xy 1.016 -88.571578) (xy 1.047496 -88.654382) (xy 1.059942 -88.669876) (xy 1.077482 -88.69257) (xy 1.106268 -88.742179)
			(xy 1.127305 -88.795537) (xy 1.14012 -88.851442) (xy 1.144423 -88.908636) (xy 1.14012 -88.96583)
			(xy 1.127305 -89.021735) (xy 1.106268 -89.075093) (xy 1.077482 -89.124702) (xy 1.059942 -89.147396)
			(xy 1.047496 -89.16289) (xy 1.016 -89.245694) (xy 1.016 -95.81007) (xy 39.818063 -95.81007) (xy 39.82207 -95.694046)
			(xy 39.834072 -95.578574) (xy 39.854012 -95.464206) (xy 39.881795 -95.351486) (xy 39.917289 -95.240952)
			(xy 39.960324 -95.133129) (xy 40.010695 -95.028532) (xy 40.068162 -94.92766) (xy 40.132452 -94.830993)
			(xy 40.203257 -94.738992) (xy 40.280241 -94.652095) (xy 40.363037 -94.570716) (xy 40.45125 -94.495243)
			(xy 40.54446 -94.426036) (xy 40.642223 -94.363424) (xy 40.744072 -94.307707) (xy 40.849522 -94.259149)
			(xy 40.958071 -94.217981) (xy 41.069202 -94.184401) (xy 41.182385 -94.158568) (xy 41.29708 -94.140605)
			(xy 41.412742 -94.130597) (xy 41.528818 -94.128594) (xy 41.644756 -94.134603) (xy 41.760003 -94.148596)
			(xy 41.874009 -94.170507) (xy 41.986233 -94.200232) (xy 42.096139 -94.237628) (xy 42.203202 -94.282517)
			(xy 42.306914 -94.334686) (xy 42.406779 -94.393886) (xy 42.502322 -94.459835) (xy 42.593088 -94.532218)
			(xy 42.678643 -94.610691) (xy 42.758581 -94.694879) (xy 42.83252 -94.784381) (xy 42.900108 -94.878772)
			(xy 42.961022 -94.9776) (xy 43.014974 -95.080396) (xy 43.061704 -95.186669) (xy 43.100992 -95.295913)
			(xy 43.132649 -95.407606) (xy 43.156525 -95.521218) (xy 43.172506 -95.636206) (xy 43.180515 -95.752023)
			(xy 43.181016 -95.81007) (xy 43.180515 -95.868117) (xy 43.172506 -95.983934) (xy 43.156525 -96.098922)
			(xy 43.132649 -96.212534) (xy 43.100992 -96.324227) (xy 43.061704 -96.433471) (xy 43.014974 -96.539744)
			(xy 42.961022 -96.64254) (xy 42.900108 -96.741368) (xy 42.83252 -96.835759) (xy 42.758581 -96.925261)
			(xy 42.678643 -97.009449) (xy 42.593088 -97.087922) (xy 42.502604 -97.16008) (xy 93.154506 -97.16008)
			(xy 93.158522 -97.04381) (xy 93.170549 -96.928095) (xy 93.190531 -96.813485) (xy 93.218373 -96.700526)
			(xy 93.253942 -96.589758) (xy 93.297068 -96.481707) (xy 93.347545 -96.376889) (xy 93.405134 -96.275804)
			(xy 93.46956 -96.178932) (xy 93.540515 -96.086736) (xy 93.617662 -95.999655) (xy 93.700633 -95.918104)
			(xy 93.789033 -95.842472) (xy 93.88244 -95.773118) (xy 93.980409 -95.710375) (xy 94.082473 -95.654539)
			(xy 94.188147 -95.605878) (xy 94.296926 -95.564624) (xy 94.408291 -95.530973) (xy 94.521714 -95.505085)
			(xy 94.636651 -95.487084) (xy 94.752557 -95.477055) (xy 94.868879 -95.475047) (xy 94.985062 -95.481069)
			(xy 95.100553 -95.495092) (xy 95.214801 -95.51705) (xy 95.327262 -95.546837) (xy 95.4374 -95.584312)
			(xy 95.54469 -95.629297) (xy 95.648621 -95.681576) (xy 95.748697 -95.740901) (xy 95.844443 -95.806989)
			(xy 95.9354 -95.879525) (xy 96.021136 -95.958164) (xy 96.101243 -96.04253) (xy 96.175339 -96.132222)
			(xy 96.243069 -96.226812) (xy 96.304113 -96.32585) (xy 96.358178 -96.428863) (xy 96.405008 -96.53536)
			(xy 96.444379 -96.644835) (xy 96.476103 -96.756765) (xy 96.500029 -96.870617) (xy 96.516043 -96.985849)
			(xy 96.52407 -97.101911) (xy 96.524572 -97.16008) (xy 96.52407 -97.218249) (xy 96.516043 -97.334311)
			(xy 96.500029 -97.449543) (xy 96.476103 -97.563395) (xy 96.444379 -97.675325) (xy 96.405008 -97.7848)
			(xy 96.358178 -97.891297) (xy 96.304113 -97.99431) (xy 96.243069 -98.093348) (xy 96.175339 -98.187938)
			(xy 96.101243 -98.27763) (xy 96.021136 -98.361996) (xy 95.9354 -98.440635) (xy 95.844443 -98.513171)
			(xy 95.748697 -98.579259) (xy 95.648621 -98.638584) (xy 95.54469 -98.690863) (xy 95.4374 -98.735848)
			(xy 95.327262 -98.773323) (xy 95.214801 -98.80311) (xy 95.100553 -98.825068) (xy 94.985062 -98.839091)
			(xy 94.868879 -98.845113) (xy 94.752557 -98.843105) (xy 94.636651 -98.833076) (xy 94.521714 -98.815075)
			(xy 94.408291 -98.789187) (xy 94.296926 -98.755536) (xy 94.188147 -98.714282) (xy 94.082473 -98.665621)
			(xy 93.980409 -98.609785) (xy 93.88244 -98.547042) (xy 93.789033 -98.477688) (xy 93.700633 -98.402056)
			(xy 93.617662 -98.320505) (xy 93.540515 -98.233424) (xy 93.46956 -98.141228) (xy 93.405134 -98.044356)
			(xy 93.347545 -97.943271) (xy 93.297068 -97.838453) (xy 93.253942 -97.730402) (xy 93.218373 -97.619634)
			(xy 93.190531 -97.506675) (xy 93.170549 -97.392065) (xy 93.158522 -97.27635) (xy 93.154506 -97.16008)
			(xy 42.502604 -97.16008) (xy 42.502322 -97.160305) (xy 42.406779 -97.226254) (xy 42.306914 -97.285454)
			(xy 42.203202 -97.337623) (xy 42.096139 -97.382512) (xy 41.986233 -97.419908) (xy 41.874009 -97.449633)
			(xy 41.760003 -97.471544) (xy 41.644756 -97.485537) (xy 41.528818 -97.491546) (xy 41.412742 -97.489543)
			(xy 41.29708 -97.479535) (xy 41.182385 -97.461572) (xy 41.069202 -97.435739) (xy 40.958071 -97.402159)
			(xy 40.849522 -97.360991) (xy 40.744072 -97.312433) (xy 40.642223 -97.256716) (xy 40.54446 -97.194104)
			(xy 40.45125 -97.124897) (xy 40.363037 -97.049424) (xy 40.280241 -96.968045) (xy 40.203257 -96.881148)
			(xy 40.132452 -96.789147) (xy 40.068162 -96.69248) (xy 40.010695 -96.591608) (xy 39.960324 -96.487011)
			(xy 39.917289 -96.379188) (xy 39.881795 -96.268654) (xy 39.854012 -96.155934) (xy 39.834072 -96.041566)
			(xy 39.82207 -95.926094) (xy 39.818063 -95.81007) (xy 1.016 -95.81007) (xy 1.016 -98.005392) (xy 1.016505 -98.028732)
			(xy 1.024982 -98.074635) (xy 1.0417 -98.118218) (xy 1.066095 -98.158016) (xy 1.097347 -98.192689)
			(xy 1.134405 -98.221072) (xy 1.176024 -98.242211) (xy 1.220803 -98.255395) (xy 1.267236 -98.260179)
			(xy 1.313763 -98.256404) (xy 1.358817 -98.244196) (xy 1.400885 -98.223966) (xy 1.438551 -98.196394)
			(xy 1.470549 -98.162407) (xy 1.483614 -98.14306) (xy 1.51897 -98.089124) (xy 1.595424 -97.985248)
			(xy 1.678158 -97.8863) (xy 1.766855 -97.79266) (xy 1.861175 -97.704687) (xy 1.960757 -97.622717)
			(xy 2.065219 -97.547065) (xy 2.174161 -97.47802) (xy 2.287166 -97.415847) (xy 2.403801 -97.360784)
			(xy 2.523618 -97.313042) (xy 2.64616 -97.272804) (xy 2.770956 -97.240224) (xy 2.897529 -97.215427)
			(xy 3.025394 -97.198508) (xy 3.15406 -97.189531) (xy 3.283035 -97.188531) (xy 3.411825 -97.195513)
			(xy 3.539936 -97.210448) (xy 3.666878 -97.23328) (xy 3.792164 -97.263922) (xy 3.915315 -97.302256)
			(xy 4.035858 -97.348135) (xy 4.153332 -97.401383) (xy 4.267287 -97.461797) (xy 4.377286 -97.529145)
			(xy 4.482909 -97.603169) (xy 4.583749 -97.683586) (xy 4.679421 -97.770086) (xy 4.769559 -97.86234)
			(xy 4.853817 -97.959994) (xy 4.931872 -98.062673) (xy 5.003425 -98.169984) (xy 5.068203 -98.281516)
			(xy 5.125957 -98.396842) (xy 5.176465 -98.51552) (xy 5.219535 -98.637095) (xy 5.255001 -98.761102)
			(xy 5.282728 -98.887065) (xy 5.302609 -99.014503) (xy 5.314568 -99.142926) (xy 5.318559 -99.271836)
			(xy 12.580624 -99.271836) (xy 12.584655 -99.14227) (xy 12.596734 -99.013206) (xy 12.616813 -98.885142)
			(xy 12.644815 -98.758575) (xy 12.680632 -98.633992) (xy 12.724124 -98.511878) (xy 12.775124 -98.392704)
			(xy 12.833435 -98.276931) (xy 12.89883 -98.165007) (xy 12.971057 -98.057365) (xy 13.049837 -97.954422)
			(xy 13.134864 -97.856576) (xy 13.225809 -97.764204) (xy 13.322321 -97.677666) (xy 13.424027 -97.597295)
			(xy 13.530533 -97.523403) (xy 13.641426 -97.456275) (xy 13.756278 -97.396171) (xy 13.874645 -97.343324)
			(xy 13.996068 -97.297937) (xy 14.120078 -97.260188) (xy 14.246195 -97.230221) (xy 14.373931 -97.208152)
			(xy 14.502792 -97.194068) (xy 14.632279 -97.188022) (xy 14.761892 -97.190038) (xy 14.891128 -97.200108)
			(xy 15.019489 -97.218193) (xy 15.146477 -97.244223) (xy 15.271601 -97.278098) (xy 15.394377 -97.319686)
			(xy 15.51433 -97.368827) (xy 15.630995 -97.42533) (xy 15.743923 -97.488977) (xy 15.852675 -97.559521)
			(xy 15.956831 -97.63669) (xy 16.055988 -97.720185) (xy 16.149762 -97.809683) (xy 16.237791 -97.904838)
			(xy 16.319734 -98.005281) (xy 16.395273 -98.110624) (xy 16.464118 -98.22046) (xy 16.526001 -98.334364)
			(xy 16.580682 -98.451894) (xy 16.627952 -98.572597) (xy 16.667625 -98.696005) (xy 16.69955 -98.821641)
			(xy 16.723602 -98.949018) (xy 16.739689 -99.077644) (xy 16.747748 -99.207022) (xy 16.748252 -99.271836)
			(xy 16.747748 -99.33665) (xy 16.739689 -99.466028) (xy 16.723602 -99.594654) (xy 16.69955 -99.722031)
			(xy 16.667625 -99.847667) (xy 16.627952 -99.971075) (xy 16.580682 -100.091778) (xy 16.526001 -100.209308)
			(xy 16.464118 -100.323212) (xy 16.395273 -100.433048) (xy 16.319734 -100.538391) (xy 16.237791 -100.638834)
			(xy 16.149762 -100.733989) (xy 16.055988 -100.823487) (xy 15.956831 -100.906982) (xy 15.852675 -100.984151)
			(xy 15.743923 -101.054695) (xy 15.630995 -101.118342) (xy 15.51433 -101.174845) (xy 15.394377 -101.223986)
			(xy 15.271601 -101.265574) (xy 15.146477 -101.299449) (xy 15.019489 -101.325479) (xy 14.891128 -101.343564)
			(xy 14.761892 -101.353634) (xy 14.632279 -101.35565) (xy 14.502792 -101.349604) (xy 14.373931 -101.33552)
			(xy 14.246195 -101.313451) (xy 14.120078 -101.283484) (xy 13.996068 -101.245735) (xy 13.874645 -101.200348)
			(xy 13.756278 -101.147501) (xy 13.641426 -101.087397) (xy 13.530533 -101.020269) (xy 13.424027 -100.946377)
			(xy 13.322321 -100.866006) (xy 13.225809 -100.779468) (xy 13.134864 -100.687096) (xy 13.049837 -100.58925)
			(xy 12.971057 -100.486307) (xy 12.89883 -100.378665) (xy 12.833435 -100.266741) (xy 12.775124 -100.150968)
			(xy 12.724124 -100.031794) (xy 12.680632 -99.90968) (xy 12.644815 -99.785097) (xy 12.616813 -99.65853)
			(xy 12.596734 -99.530466) (xy 12.584655 -99.401402) (xy 12.580624 -99.271836) (xy 5.318559 -99.271836)
			(xy 5.318559 -99.271843) (xy 5.314568 -99.400761) (xy 5.302608 -99.529184) (xy 5.282727 -99.656621)
			(xy 5.255 -99.782585) (xy 5.219533 -99.906591) (xy 5.176463 -100.028167) (xy 5.125954 -100.146844)
			(xy 5.0682 -100.26217) (xy 5.003422 -100.373702) (xy 4.931868 -100.481013) (xy 4.853812 -100.583692)
			(xy 4.769554 -100.681345) (xy 4.679416 -100.773598) (xy 4.583744 -100.860099) (xy 4.482903 -100.940515)
			(xy 4.377281 -101.014538) (xy 4.267281 -101.081886) (xy 4.153326 -101.1423) (xy 4.035852 -101.195548)
			(xy 3.915309 -101.241426) (xy 3.792158 -101.27976) (xy 3.666871 -101.310401) (xy 3.539929 -101.333233)
			(xy 3.411818 -101.348168) (xy 3.283028 -101.355149) (xy 3.154053 -101.354149) (xy 3.025387 -101.345172)
			(xy 2.897523 -101.328252) (xy 2.77095 -101.303454) (xy 2.646154 -101.270874) (xy 2.523612 -101.230636)
			(xy 2.403795 -101.182893) (xy 2.28716 -101.12783) (xy 2.174155 -101.065657) (xy 2.065214 -100.996611)
			(xy 1.960752 -100.920959) (xy 1.86117 -100.838989) (xy 1.766851 -100.751015) (xy 1.678154 -100.657375)
			(xy 1.59542 -100.558427) (xy 1.518966 -100.45455) (xy 1.483614 -100.400612) (xy 1.470543 -100.38127)
			(xy 1.438545 -100.347285) (xy 1.40088 -100.319714) (xy 1.358813 -100.299486) (xy 1.31376 -100.287278)
			(xy 1.267235 -100.283504) (xy 1.220804 -100.288288) (xy 1.176026 -100.301471) (xy 1.134409 -100.322609)
			(xy 1.097351 -100.350991) (xy 1.066099 -100.385663) (xy 1.041704 -100.425458) (xy 1.024987 -100.469039)
			(xy 1.016508 -100.514941) (xy 1.016 -100.53828) (xy 1.016 -101.271578) (xy 1.047496 -101.354382)
			(xy 1.059942 -101.369876) (xy 1.077482 -101.39257) (xy 1.106268 -101.442179) (xy 1.127305 -101.495537)
			(xy 1.14012 -101.551442) (xy 1.144423 -101.608636) (xy 1.14012 -101.66583) (xy 1.127305 -101.721735)
			(xy 1.106268 -101.775093) (xy 1.077482 -101.824702) (xy 1.059942 -101.847396) (xy 1.047496 -101.86289)
			(xy 1.016 -101.945694) (xy 1.016 -108.909866) (xy 86.877404 -108.909866) (xy 86.881424 -108.719215)
			(xy 86.893478 -108.528902) (xy 86.913544 -108.339267) (xy 86.941587 -108.150646) (xy 86.977556 -107.963376)
			(xy 87.021388 -107.777788) (xy 87.073005 -107.594213) (xy 87.132315 -107.412977) (xy 87.199213 -107.234402)
			(xy 87.273579 -107.058807) (xy 87.355281 -106.886502) (xy 87.444175 -106.717795) (xy 87.540101 -106.552985)
			(xy 87.64289 -106.392366) (xy 87.752359 -106.236223) (xy 87.868313 -106.084834) (xy 87.990547 -105.938467)
			(xy 88.118841 -105.797383) (xy 88.252969 -105.661834) (xy 88.392693 -105.532059) (xy 88.537763 -105.408289)
			(xy 88.687921 -105.290746) (xy 88.842902 -105.179637) (xy 89.002429 -105.07516) (xy 89.166218 -104.977501)
			(xy 89.333978 -104.886834) (xy 89.505412 -104.80332) (xy 89.680214 -104.727107) (xy 89.858073 -104.658331)
			(xy 90.038674 -104.597113) (xy 90.221694 -104.543564) (xy 90.40681 -104.497778) (xy 90.593691 -104.459836)
			(xy 90.782006 -104.429807) (xy 90.971419 -104.407742) (xy 91.161593 -104.393683) (xy 91.352192 -104.387653)
			(xy 91.542875 -104.389663) (xy 91.733304 -104.39971) (xy 91.92314 -104.417776) (xy 92.112046 -104.443829)
			(xy 92.299685 -104.477822) (xy 92.485725 -104.519695) (xy 92.669834 -104.569374) (xy 92.851685 -104.62677)
			(xy 93.030955 -104.691781) (xy 93.207325 -104.764292) (xy 93.380481 -104.844173) (xy 93.550116 -104.931283)
			(xy 93.715928 -105.025467) (xy 93.877622 -105.126558) (xy 94.03491 -105.234374) (xy 94.187513 -105.348726)
			(xy 94.335161 -105.469409) (xy 94.477589 -105.59621) (xy 94.614545 -105.728901) (xy 94.745786 -105.867249)
			(xy 94.871078 -106.011006) (xy 94.990198 -106.159917) (xy 95.102934 -106.313718) (xy 95.209087 -106.472134)
			(xy 95.308467 -106.634885) (xy 95.400897 -106.80168) (xy 95.486214 -106.972224) (xy 95.564266 -107.146212)
			(xy 95.634913 -107.323337) (xy 95.698031 -107.503282) (xy 95.753507 -107.685728) (xy 95.801242 -107.870351)
			(xy 95.841152 -108.056821) (xy 95.873165 -108.244809) (xy 95.897225 -108.433979) (xy 95.913288 -108.623995)
			(xy 95.921327 -108.814519) (xy 95.92183 -108.909866) (xy 95.921327 -109.005213) (xy 95.913288 -109.195737)
			(xy 95.897225 -109.385753) (xy 95.873165 -109.574923) (xy 95.841152 -109.762911) (xy 95.801242 -109.949381)
			(xy 95.753507 -110.134004) (xy 95.698031 -110.31645) (xy 95.634913 -110.496395) (xy 95.564266 -110.67352)
			(xy 95.486214 -110.847508) (xy 95.400897 -111.018052) (xy 95.308467 -111.184847) (xy 95.209087 -111.347598)
			(xy 95.102934 -111.506014) (xy 94.990198 -111.659815) (xy 94.871078 -111.808726) (xy 94.745786 -111.952483)
			(xy 94.614545 -112.090831) (xy 94.477589 -112.223522) (xy 94.335161 -112.350323) (xy 94.187513 -112.471006)
			(xy 94.03491 -112.585358) (xy 93.877622 -112.693174) (xy 93.715928 -112.794265) (xy 93.550116 -112.888449)
			(xy 93.380481 -112.975559) (xy 93.207325 -113.05544) (xy 93.030955 -113.127951) (xy 92.851685 -113.192962)
			(xy 92.669834 -113.250358) (xy 92.485725 -113.300037) (xy 92.299685 -113.34191) (xy 92.112046 -113.375903)
			(xy 91.92314 -113.401956) (xy 91.733304 -113.420022) (xy 91.542875 -113.430069) (xy 91.352192 -113.432079)
			(xy 91.161593 -113.426049) (xy 90.971419 -113.41199) (xy 90.782006 -113.389925) (xy 90.593691 -113.359896)
			(xy 90.40681 -113.321954) (xy 90.221694 -113.276168) (xy 90.038674 -113.222619) (xy 89.858073 -113.161401)
			(xy 89.680214 -113.092625) (xy 89.505412 -113.016412) (xy 89.333978 -112.932898) (xy 89.166218 -112.842231)
			(xy 89.002429 -112.744572) (xy 88.842902 -112.640095) (xy 88.687921 -112.528986) (xy 88.537763 -112.411443)
			(xy 88.392693 -112.287673) (xy 88.252969 -112.157898) (xy 88.118841 -112.022349) (xy 87.990547 -111.881265)
			(xy 87.868313 -111.734898) (xy 87.752359 -111.583509) (xy 87.64289 -111.427366) (xy 87.540101 -111.266747)
			(xy 87.444175 -111.101937) (xy 87.355281 -110.93323) (xy 87.273579 -110.760925) (xy 87.199213 -110.58533)
			(xy 87.132315 -110.406755) (xy 87.073005 -110.225519) (xy 87.021388 -110.041944) (xy 86.977556 -109.856356)
			(xy 86.941587 -109.669086) (xy 86.913544 -109.480465) (xy 86.893478 -109.29083) (xy 86.881424 -109.100517)
			(xy 86.877404 -108.909866) (xy 1.016 -108.909866) (xy 1.016 -113.971578) (xy 1.047496 -114.054382)
			(xy 1.059942 -114.069876) (xy 1.077482 -114.09257) (xy 1.106268 -114.142179) (xy 1.127305 -114.195537)
			(xy 1.14012 -114.251442) (xy 1.144423 -114.308636) (xy 1.14012 -114.36583) (xy 1.127305 -114.421735)
			(xy 1.106268 -114.475093) (xy 1.077482 -114.524702) (xy 1.059942 -114.547396) (xy 1.047496 -114.56289)
			(xy 1.016 -114.645694) (xy 1.016 -118.09984) (xy 11.34441 -118.09984) (xy 11.348411 -117.894791)
			(xy 11.36041 -117.690054) (xy 11.380388 -117.485941) (xy 11.408314 -117.282762) (xy 11.444146 -117.080829)
			(xy 11.48783 -116.880446) (xy 11.539298 -116.681921) (xy 11.598473 -116.485555) (xy 11.665264 -116.291648)
			(xy 11.73957 -116.100494) (xy 11.821277 -115.912384) (xy 11.910262 -115.727606) (xy 12.006388 -115.54644)
			(xy 12.109509 -115.369163) (xy 12.219469 -115.196044) (xy 12.336099 -115.027347) (xy 12.459222 -114.863329)
			(xy 12.588651 -114.70424) (xy 12.724188 -114.550322) (xy 12.865627 -114.401808) (xy 13.012754 -114.258927)
			(xy 13.165342 -114.121894) (xy 13.323161 -113.99092) (xy 13.48597 -113.866202) (xy 13.653521 -113.747932)
			(xy 13.825559 -113.636288) (xy 14.001822 -113.531442) (xy 14.182041 -113.433553) (xy 14.365942 -113.34277)
			(xy 14.553246 -113.259232) (xy 14.743666 -113.183064) (xy 14.936912 -113.114384) (xy 15.132692 -113.053296)
			(xy 15.330705 -112.999894) (xy 15.530652 -112.954257) (xy 15.732226 -112.916457) (xy 15.935122 -112.886549)
			(xy 16.139031 -112.864581) (xy 16.343641 -112.850586) (xy 16.548641 -112.844584) (xy 16.75372 -112.846585)
			(xy 16.958564 -112.856585) (xy 17.162863 -112.874571) (xy 17.366304 -112.900513) (xy 17.568577 -112.934374)
			(xy 17.769376 -112.9761) (xy 17.968394 -113.025629) (xy 18.165328 -113.082885) (xy 18.359878 -113.147782)
			(xy 18.551748 -113.220219) (xy 18.740645 -113.300087) (xy 18.926283 -113.387265) (xy 19.108378 -113.481619)
			(xy 19.286653 -113.583006) (xy 19.460836 -113.691271) (xy 19.630663 -113.806249) (xy 19.795875 -113.927767)
			(xy 19.956219 -114.055637) (xy 20.111453 -114.189666) (xy 20.261339 -114.32965) (xy 20.405649 -114.475375)
			(xy 20.544163 -114.62662) (xy 20.676672 -114.783153) (xy 20.802972 -114.944738) (xy 20.922871 -115.111127)
			(xy 21.036188 -115.282067) (xy 21.142748 -115.457299) (xy 21.242391 -115.636554) (xy 21.334964 -115.819561)
			(xy 21.420326 -116.00604) (xy 21.498347 -116.195708) (xy 21.56891 -116.388276) (xy 21.631905 -116.58345)
			(xy 21.687237 -116.780933) (xy 21.734822 -116.980424) (xy 21.774587 -117.181621) (xy 21.806472 -117.384215)
			(xy 21.830429 -117.5879) (xy 21.84642 -117.792364) (xy 21.854422 -117.997296) (xy 21.854922 -118.09984)
			(xy 21.854422 -118.202384) (xy 21.84642 -118.407316) (xy 21.830429 -118.61178) (xy 21.806472 -118.815465)
			(xy 21.774587 -119.018059) (xy 21.734822 -119.219256) (xy 21.687237 -119.418747) (xy 21.631905 -119.61623)
			(xy 21.56891 -119.811404) (xy 21.498347 -120.003972) (xy 21.420326 -120.19364) (xy 21.334964 -120.380119)
			(xy 21.242391 -120.563126) (xy 21.142748 -120.742381) (xy 21.036188 -120.917613) (xy 20.922871 -121.088553)
			(xy 20.842811 -121.199656) (xy 72.865241 -121.199656) (xy 72.86925 -120.996785) (xy 72.88127 -120.794231)
			(xy 72.901284 -120.59231) (xy 72.929259 -120.391337) (xy 72.965152 -120.191627) (xy 73.008906 -119.99349)
			(xy 73.060455 -119.797237) (xy 73.119716 -119.603173) (xy 73.186598 -119.411602) (xy 73.260996 -119.222823)
			(xy 73.342794 -119.03713) (xy 73.431864 -118.854814) (xy 73.528067 -118.676159) (xy 73.631254 -118.501445)
			(xy 73.741262 -118.330943) (xy 73.85792 -118.16492) (xy 73.981046 -118.003636) (xy 74.110448 -117.847342)
			(xy 74.245923 -117.696282) (xy 74.38726 -117.550692) (xy 74.534239 -117.4108) (xy 74.68663 -117.276824)
			(xy 74.844195 -117.148972) (xy 75.006688 -117.027446) (xy 75.173855 -116.912433) (xy 75.345435 -116.804115)
			(xy 75.52116 -116.70266) (xy 75.700757 -116.608226) (xy 75.883944 -116.520961) (xy 76.070436 -116.441002)
			(xy 76.259941 -116.368473) (xy 76.452163 -116.303487) (xy 76.646803 -116.246145) (xy 76.843556 -116.196538)
			(xy 77.042115 -116.154743) (xy 77.242171 -116.120825) (xy 77.44341 -116.094837) (xy 77.645519 -116.076819)
			(xy 77.848182 -116.0668) (xy 78.051082 -116.064796) (xy 78.253903 -116.070808) (xy 78.456329 -116.084829)
			(xy 78.658042 -116.106837) (xy 78.858729 -116.136796) (xy 79.058075 -116.17466) (xy 79.25577 -116.22037)
			(xy 79.451504 -116.273854) (xy 79.644973 -116.33503) (xy 79.835874 -116.403801) (xy 80.023909 -116.480061)
			(xy 80.208785 -116.563689) (xy 80.390212 -116.654556) (xy 80.567908 -116.752519) (xy 80.741594 -116.857427)
			(xy 80.911001 -116.969114) (xy 81.075863 -117.087406) (xy 81.235923 -117.21212) (xy 81.390931 -117.343059)
			(xy 81.540645 -117.48002) (xy 81.684831 -117.622789) (xy 81.823265 -117.771143) (xy 81.955729 -117.92485)
			(xy 82.082018 -118.08367) (xy 82.201933 -118.247355) (xy 82.315289 -118.41565) (xy 82.421907 -118.588292)
			(xy 82.521621 -118.765012) (xy 82.614276 -118.945532) (xy 82.699726 -119.129572) (xy 82.77784 -119.316845)
			(xy 82.848493 -119.507057) (xy 82.911577 -119.699912) (xy 82.966993 -119.895109) (xy 83.014654 -120.092342)
			(xy 83.054485 -120.291305) (xy 83.086425 -120.491686) (xy 83.110424 -120.693172) (xy 83.126444 -120.895449)
			(xy 83.134461 -121.098201) (xy 83.134962 -121.199656) (xy 83.134461 -121.301111) (xy 83.126444 -121.503863)
			(xy 83.110424 -121.70614) (xy 83.086425 -121.907626) (xy 83.054485 -122.108007) (xy 83.014654 -122.30697)
			(xy 82.966993 -122.504203) (xy 82.911577 -122.6994) (xy 82.848493 -122.892255) (xy 82.77784 -123.082467)
			(xy 82.699726 -123.26974) (xy 82.614276 -123.45378) (xy 82.521621 -123.6343) (xy 82.421907 -123.81102)
			(xy 82.315289 -123.983662) (xy 82.201933 -124.151957) (xy 82.082018 -124.315642) (xy 81.955729 -124.474462)
			(xy 81.823265 -124.628169) (xy 81.684831 -124.776523) (xy 81.540645 -124.919292) (xy 81.390931 -125.056253)
			(xy 81.235923 -125.187192) (xy 81.075863 -125.311906) (xy 80.911001 -125.430198) (xy 80.741594 -125.541885)
			(xy 80.567908 -125.646793) (xy 80.390212 -125.744756) (xy 80.208785 -125.835623) (xy 80.023909 -125.919251)
			(xy 79.835874 -125.995511) (xy 79.644973 -126.064282) (xy 79.451504 -126.125458) (xy 79.25577 -126.178942)
			(xy 79.058075 -126.224652) (xy 78.858729 -126.262516) (xy 78.658042 -126.292475) (xy 78.456329 -126.314483)
			(xy 78.253903 -126.328504) (xy 78.051082 -126.334516) (xy 77.848182 -126.332512) (xy 77.645519 -126.322493)
			(xy 77.44341 -126.304475) (xy 77.242171 -126.278487) (xy 77.042115 -126.244569) (xy 76.843556 -126.202774)
			(xy 76.646803 -126.153167) (xy 76.452163 -126.095825) (xy 76.259941 -126.030839) (xy 76.070436 -125.95831)
			(xy 75.883944 -125.878351) (xy 75.700757 -125.791086) (xy 75.52116 -125.696652) (xy 75.345435 -125.595197)
			(xy 75.173855 -125.486879) (xy 75.006688 -125.371866) (xy 74.844195 -125.25034) (xy 74.68663 -125.122488)
			(xy 74.534239 -124.988512) (xy 74.38726 -124.84862) (xy 74.245923 -124.70303) (xy 74.110448 -124.55197)
			(xy 73.981046 -124.395676) (xy 73.85792 -124.234392) (xy 73.741262 -124.068369) (xy 73.631254 -123.897867)
			(xy 73.528067 -123.723153) (xy 73.431864 -123.544498) (xy 73.342794 -123.362182) (xy 73.260996 -123.176489)
			(xy 73.186598 -122.98771) (xy 73.119716 -122.796139) (xy 73.060455 -122.602075) (xy 73.008906 -122.405822)
			(xy 72.965152 -122.207685) (xy 72.929259 -122.007975) (xy 72.901284 -121.807002) (xy 72.88127 -121.605081)
			(xy 72.86925 -121.402527) (xy 72.865241 -121.199656) (xy 20.842811 -121.199656) (xy 20.802972 -121.254942)
			(xy 20.676672 -121.416527) (xy 20.544163 -121.57306) (xy 20.405649 -121.724305) (xy 20.261339 -121.87003)
			(xy 20.111453 -122.010014) (xy 19.956219 -122.144043) (xy 19.795875 -122.271913) (xy 19.630663 -122.393431)
			(xy 19.460836 -122.508409) (xy 19.286653 -122.616674) (xy 19.108378 -122.718061) (xy 18.926283 -122.812415)
			(xy 18.740645 -122.899593) (xy 18.551748 -122.979461) (xy 18.359878 -123.051898) (xy 18.165328 -123.116795)
			(xy 17.968394 -123.174051) (xy 17.769376 -123.22358) (xy 17.568577 -123.265306) (xy 17.366304 -123.299167)
			(xy 17.162863 -123.325109) (xy 16.958564 -123.343095) (xy 16.75372 -123.353095) (xy 16.548641 -123.355096)
			(xy 16.343641 -123.349094) (xy 16.139031 -123.335099) (xy 15.935122 -123.313131) (xy 15.732226 -123.283223)
			(xy 15.530652 -123.245423) (xy 15.330705 -123.199786) (xy 15.132692 -123.146384) (xy 14.936912 -123.085296)
			(xy 14.743666 -123.016616) (xy 14.553246 -122.940448) (xy 14.365942 -122.85691) (xy 14.182041 -122.766127)
			(xy 14.001822 -122.668238) (xy 13.825559 -122.563392) (xy 13.653521 -122.451748) (xy 13.48597 -122.333478)
			(xy 13.323161 -122.20876) (xy 13.165342 -122.077786) (xy 13.012754 -121.940753) (xy 12.865627 -121.797872)
			(xy 12.724188 -121.649358) (xy 12.588651 -121.49544) (xy 12.459222 -121.336351) (xy 12.336099 -121.172333)
			(xy 12.219469 -121.003636) (xy 12.109509 -120.830517) (xy 12.006388 -120.65324) (xy 11.910262 -120.472074)
			(xy 11.821277 -120.287296) (xy 11.73957 -120.099186) (xy 11.665264 -119.908032) (xy 11.598473 -119.714125)
			(xy 11.539298 -119.517759) (xy 11.48783 -119.319234) (xy 11.444146 -119.118851) (xy 11.408314 -118.916918)
			(xy 11.380388 -118.713739) (xy 11.36041 -118.509626) (xy 11.348411 -118.304889) (xy 11.34441 -118.09984)
			(xy 1.016 -118.09984) (xy 1.016 -126.671578) (xy 1.047496 -126.754382) (xy 1.059942 -126.769876)
			(xy 1.077482 -126.79257) (xy 1.106268 -126.842179) (xy 1.127305 -126.895537) (xy 1.14012 -126.951442)
			(xy 1.144423 -127.008636) (xy 1.14012 -127.06583) (xy 1.127305 -127.121735) (xy 1.106268 -127.175093)
			(xy 1.077482 -127.224702) (xy 1.059942 -127.247396) (xy 1.047496 -127.26289) (xy 1.016 -127.345694)
			(xy 1.016 -138.163122) (xy 1.547863 -138.163122) (xy 1.547863 -138.036986) (xy 1.555783 -137.911098)
			(xy 1.571593 -137.785956) (xy 1.595228 -137.662053) (xy 1.626597 -137.53988) (xy 1.665575 -137.419917)
			(xy 1.712009 -137.302638) (xy 1.765716 -137.188506) (xy 1.826483 -137.077971) (xy 1.89407 -136.971471)
			(xy 1.968211 -136.869424) (xy 2.048614 -136.772234) (xy 2.13496 -136.680284) (xy 2.22691 -136.593938)
			(xy 2.3241 -136.513535) (xy 2.426147 -136.439394) (xy 2.532647 -136.371807) (xy 2.643182 -136.31104)
			(xy 2.757314 -136.257333) (xy 2.874593 -136.210899) (xy 2.994556 -136.171921) (xy 3.116729 -136.140552)
			(xy 3.240632 -136.116917) (xy 3.365774 -136.101107) (xy 3.491662 -136.093187) (xy 3.617798 -136.093187)
			(xy 3.743686 -136.101107) (xy 3.868828 -136.116917) (xy 3.992731 -136.140552) (xy 4.114904 -136.171921)
			(xy 4.234867 -136.210899) (xy 4.352146 -136.257333) (xy 4.466278 -136.31104) (xy 4.576813 -136.371807)
			(xy 4.683313 -136.439394) (xy 4.78536 -136.513535) (xy 4.88255 -136.593938) (xy 4.9745 -136.680284)
			(xy 5.060846 -136.772234) (xy 5.141249 -136.869424) (xy 5.21539 -136.971471) (xy 5.282977 -137.077971)
			(xy 5.343744 -137.188506) (xy 5.397451 -137.302638) (xy 5.443885 -137.419917) (xy 5.482863 -137.53988)
			(xy 5.514232 -137.662053) (xy 5.537867 -137.785956) (xy 5.553677 -137.911098) (xy 5.561597 -138.036986)
			(xy 5.562092 -138.100054) (xy 5.561597 -138.163122) (xy 12.977863 -138.163122) (xy 12.977863 -138.036986)
			(xy 12.985783 -137.911098) (xy 13.001593 -137.785956) (xy 13.025228 -137.662053) (xy 13.056597 -137.53988)
			(xy 13.095575 -137.419917) (xy 13.142009 -137.302638) (xy 13.195716 -137.188506) (xy 13.256483 -137.077971)
			(xy 13.32407 -136.971471) (xy 13.398211 -136.869424) (xy 13.478614 -136.772234) (xy 13.56496 -136.680284)
			(xy 13.65691 -136.593938) (xy 13.7541 -136.513535) (xy 13.856147 -136.439394) (xy 13.962647 -136.371807)
			(xy 14.073182 -136.31104) (xy 14.187314 -136.257333) (xy 14.304593 -136.210899) (xy 14.424556 -136.171921)
			(xy 14.546729 -136.140552) (xy 14.670632 -136.116917) (xy 14.795774 -136.101107) (xy 14.921662 -136.093187)
			(xy 15.047798 -136.093187) (xy 15.173686 -136.101107) (xy 15.298828 -136.116917) (xy 15.422731 -136.140552)
			(xy 15.544904 -136.171921) (xy 15.664867 -136.210899) (xy 15.782146 -136.257333) (xy 15.896278 -136.31104)
			(xy 16.006813 -136.371807) (xy 16.113313 -136.439394) (xy 16.21536 -136.513535) (xy 16.31255 -136.593938)
			(xy 16.4045 -136.680284) (xy 16.490846 -136.772234) (xy 16.571249 -136.869424) (xy 16.64539 -136.971471)
			(xy 16.712977 -137.077971) (xy 16.773744 -137.188506) (xy 16.827451 -137.302638) (xy 16.873885 -137.419917)
			(xy 16.912863 -137.53988) (xy 16.944232 -137.662053) (xy 16.967867 -137.785956) (xy 16.983677 -137.911098)
			(xy 16.991597 -138.036986) (xy 16.992092 -138.100054) (xy 16.991597 -138.163122) (xy 16.983677 -138.28901)
			(xy 16.967867 -138.414152) (xy 16.944232 -138.538055) (xy 16.912863 -138.660228) (xy 16.873885 -138.780191)
			(xy 16.827451 -138.89747) (xy 16.773744 -139.011602) (xy 16.712977 -139.122137) (xy 16.64539 -139.228637)
			(xy 16.571249 -139.330684) (xy 16.490846 -139.427874) (xy 16.4045 -139.519824) (xy 16.31255 -139.60617)
			(xy 16.21536 -139.686573) (xy 16.113313 -139.760714) (xy 16.006813 -139.828301) (xy 15.896278 -139.889068)
			(xy 15.782146 -139.942775) (xy 15.664867 -139.989209) (xy 15.544904 -140.028187) (xy 15.422731 -140.059556)
			(xy 15.298828 -140.083191) (xy 15.173686 -140.099001) (xy 15.047798 -140.106921) (xy 14.921662 -140.106921)
			(xy 14.795774 -140.099001) (xy 14.670632 -140.083191) (xy 14.546729 -140.059556) (xy 14.424556 -140.028187)
			(xy 14.304593 -139.989209) (xy 14.187314 -139.942775) (xy 14.073182 -139.889068) (xy 13.962647 -139.828301)
			(xy 13.856147 -139.760714) (xy 13.7541 -139.686573) (xy 13.65691 -139.60617) (xy 13.56496 -139.519824)
			(xy 13.478614 -139.427874) (xy 13.398211 -139.330684) (xy 13.32407 -139.228637) (xy 13.256483 -139.122137)
			(xy 13.195716 -139.011602) (xy 13.142009 -138.89747) (xy 13.095575 -138.780191) (xy 13.056597 -138.660228)
			(xy 13.025228 -138.538055) (xy 13.001593 -138.414152) (xy 12.985783 -138.28901) (xy 12.977863 -138.163122)
			(xy 5.561597 -138.163122) (xy 5.553677 -138.28901) (xy 5.537867 -138.414152) (xy 5.514232 -138.538055)
			(xy 5.482863 -138.660228) (xy 5.443885 -138.780191) (xy 5.397451 -138.89747) (xy 5.343744 -139.011602)
			(xy 5.282977 -139.122137) (xy 5.21539 -139.228637) (xy 5.141249 -139.330684) (xy 5.060846 -139.427874)
			(xy 4.9745 -139.519824) (xy 4.88255 -139.60617) (xy 4.78536 -139.686573) (xy 4.683313 -139.760714)
			(xy 4.576813 -139.828301) (xy 4.466278 -139.889068) (xy 4.352146 -139.942775) (xy 4.234867 -139.989209)
			(xy 4.114904 -140.028187) (xy 3.992731 -140.059556) (xy 3.868828 -140.083191) (xy 3.743686 -140.099001)
			(xy 3.617798 -140.106921) (xy 3.491662 -140.106921) (xy 3.365774 -140.099001) (xy 3.240632 -140.083191)
			(xy 3.116729 -140.059556) (xy 2.994556 -140.028187) (xy 2.874593 -139.989209) (xy 2.757314 -139.942775)
			(xy 2.643182 -139.889068) (xy 2.532647 -139.828301) (xy 2.426147 -139.760714) (xy 2.3241 -139.686573)
			(xy 2.22691 -139.60617) (xy 2.13496 -139.519824) (xy 2.048614 -139.427874) (xy 1.968211 -139.330684)
			(xy 1.89407 -139.228637) (xy 1.826483 -139.122137) (xy 1.765716 -139.011602) (xy 1.712009 -138.89747)
			(xy 1.665575 -138.780191) (xy 1.626597 -138.660228) (xy 1.595228 -138.538055) (xy 1.571593 -138.414152)
			(xy 1.555783 -138.28901) (xy 1.547863 -138.163122) (xy 1.016 -138.163122) (xy 1.016 -139.371578)
			(xy 1.047496 -139.454382) (xy 1.059942 -139.469876) (xy 1.077482 -139.49257) (xy 1.106268 -139.542179)
			(xy 1.127305 -139.595537) (xy 1.14012 -139.651442) (xy 1.144423 -139.708636) (xy 1.14012 -139.76583)
			(xy 1.127305 -139.821735) (xy 1.106268 -139.875093) (xy 1.077482 -139.924702) (xy 1.059942 -139.947396)
			(xy 1.047496 -139.96289) (xy 1.016 -140.045694) (xy 1.016 -140.26007) (xy 39.818317 -140.26007) (xy 39.822324 -140.144046)
			(xy 39.834326 -140.028574) (xy 39.854266 -139.914206) (xy 39.882049 -139.801486) (xy 39.917543 -139.690952)
			(xy 39.960578 -139.583129) (xy 40.010949 -139.478532) (xy 40.068416 -139.37766) (xy 40.132706 -139.280993)
			(xy 40.203511 -139.188992) (xy 40.280495 -139.102095) (xy 40.363291 -139.020716) (xy 40.451504 -138.945243)
			(xy 40.544714 -138.876036) (xy 40.642477 -138.813424) (xy 40.744326 -138.757707) (xy 40.849776 -138.709149)
			(xy 40.958325 -138.667981) (xy 41.069456 -138.634401) (xy 41.182639 -138.608568) (xy 41.297334 -138.590605)
			(xy 41.412996 -138.580597) (xy 41.529072 -138.578594) (xy 41.64501 -138.584603) (xy 41.760257 -138.598596)
			(xy 41.874263 -138.620507) (xy 41.986487 -138.650232) (xy 42.096393 -138.687628) (xy 42.203456 -138.732517)
			(xy 42.307168 -138.784686) (xy 42.407033 -138.843886) (xy 42.502576 -138.909835) (xy 42.593342 -138.982218)
			(xy 42.678897 -139.060691) (xy 42.758835 -139.144879) (xy 42.832774 -139.234381) (xy 42.900362 -139.328772)
			(xy 42.961276 -139.4276) (xy 43.015228 -139.530396) (xy 43.061958 -139.636669) (xy 43.101246 -139.745913)
			(xy 43.132903 -139.857606) (xy 43.156779 -139.971218) (xy 43.17276 -140.086206) (xy 43.180769 -140.202023)
			(xy 43.18127 -140.26007) (xy 43.180769 -140.318117) (xy 43.17276 -140.433934) (xy 43.156779 -140.548922)
			(xy 43.132903 -140.662534) (xy 43.101246 -140.774227) (xy 43.061958 -140.883471) (xy 43.015228 -140.989744)
			(xy 42.961276 -141.09254) (xy 42.900362 -141.191368) (xy 42.832774 -141.285759) (xy 42.758835 -141.375261)
			(xy 42.678897 -141.459449) (xy 42.593342 -141.537922) (xy 42.502858 -141.61008) (xy 93.15476 -141.61008)
			(xy 93.158776 -141.49381) (xy 93.170803 -141.378095) (xy 93.190785 -141.263485) (xy 93.218627 -141.150526)
			(xy 93.254196 -141.039758) (xy 93.297322 -140.931707) (xy 93.347799 -140.826889) (xy 93.405388 -140.725804)
			(xy 93.469814 -140.628932) (xy 93.540769 -140.536736) (xy 93.617916 -140.449655) (xy 93.700887 -140.368104)
			(xy 93.789287 -140.292472) (xy 93.882694 -140.223118) (xy 93.980663 -140.160375) (xy 94.082727 -140.104539)
			(xy 94.188401 -140.055878) (xy 94.29718 -140.014624) (xy 94.408545 -139.980973) (xy 94.521968 -139.955085)
			(xy 94.636905 -139.937084) (xy 94.752811 -139.927055) (xy 94.869133 -139.925047) (xy 94.985316 -139.931069)
			(xy 95.100807 -139.945092) (xy 95.215055 -139.96705) (xy 95.327516 -139.996837) (xy 95.437654 -140.034312)
			(xy 95.544944 -140.079297) (xy 95.648875 -140.131576) (xy 95.748951 -140.190901) (xy 95.844697 -140.256989)
			(xy 95.935654 -140.329525) (xy 96.02139 -140.408164) (xy 96.101497 -140.49253) (xy 96.175593 -140.582222)
			(xy 96.243323 -140.676812) (xy 96.304367 -140.77585) (xy 96.358432 -140.878863) (xy 96.405262 -140.98536)
			(xy 96.444633 -141.094835) (xy 96.476357 -141.206765) (xy 96.500283 -141.320617) (xy 96.516297 -141.435849)
			(xy 96.524324 -141.551911) (xy 96.524826 -141.61008) (xy 96.524324 -141.668249) (xy 96.516297 -141.784311)
			(xy 96.500283 -141.899543) (xy 96.476357 -142.013395) (xy 96.444633 -142.125325) (xy 96.405262 -142.2348)
			(xy 96.358432 -142.341297) (xy 96.304367 -142.44431) (xy 96.243323 -142.543348) (xy 96.175593 -142.637938)
			(xy 96.101497 -142.72763) (xy 96.02139 -142.811996) (xy 95.935654 -142.890635) (xy 95.844697 -142.963171)
			(xy 95.748951 -143.029259) (xy 95.648875 -143.088584) (xy 95.544944 -143.140863) (xy 95.437654 -143.185848)
			(xy 95.327516 -143.223323) (xy 95.215055 -143.25311) (xy 95.100807 -143.275068) (xy 94.985316 -143.289091)
			(xy 94.869133 -143.295113) (xy 94.752811 -143.293105) (xy 94.636905 -143.283076) (xy 94.521968 -143.265075)
			(xy 94.408545 -143.239187) (xy 94.29718 -143.205536) (xy 94.188401 -143.164282) (xy 94.082727 -143.115621)
			(xy 93.980663 -143.059785) (xy 93.882694 -142.997042) (xy 93.789287 -142.927688) (xy 93.700887 -142.852056)
			(xy 93.617916 -142.770505) (xy 93.540769 -142.683424) (xy 93.469814 -142.591228) (xy 93.405388 -142.494356)
			(xy 93.347799 -142.393271) (xy 93.297322 -142.288453) (xy 93.254196 -142.180402) (xy 93.218627 -142.069634)
			(xy 93.190785 -141.956675) (xy 93.170803 -141.842065) (xy 93.158776 -141.72635) (xy 93.15476 -141.61008)
			(xy 42.502858 -141.61008) (xy 42.502576 -141.610305) (xy 42.407033 -141.676254) (xy 42.307168 -141.735454)
			(xy 42.203456 -141.787623) (xy 42.096393 -141.832512) (xy 41.986487 -141.869908) (xy 41.874263 -141.899633)
			(xy 41.760257 -141.921544) (xy 41.64501 -141.935537) (xy 41.529072 -141.941546) (xy 41.412996 -141.939543)
			(xy 41.297334 -141.929535) (xy 41.182639 -141.911572) (xy 41.069456 -141.885739) (xy 40.958325 -141.852159)
			(xy 40.849776 -141.810991) (xy 40.744326 -141.762433) (xy 40.642477 -141.706716) (xy 40.544714 -141.644104)
			(xy 40.451504 -141.574897) (xy 40.363291 -141.499424) (xy 40.280495 -141.418045) (xy 40.203511 -141.331148)
			(xy 40.132706 -141.239147) (xy 40.068416 -141.14248) (xy 40.010949 -141.041608) (xy 39.960578 -140.937011)
			(xy 39.917543 -140.829188) (xy 39.882049 -140.718654) (xy 39.854266 -140.605934) (xy 39.834326 -140.491566)
			(xy 39.822324 -140.376094) (xy 39.818317 -140.26007) (xy 1.016 -140.26007) (xy 1.016 -152.071578)
			(xy 1.047496 -152.154382) (xy 1.059942 -152.169876) (xy 1.077482 -152.19257) (xy 1.106268 -152.242179)
			(xy 1.127305 -152.295537) (xy 1.14012 -152.351442) (xy 1.144423 -152.408636) (xy 1.14012 -152.46583)
			(xy 1.127305 -152.521735) (xy 1.106268 -152.575093) (xy 1.077482 -152.624702) (xy 1.059942 -152.647396)
			(xy 1.047496 -152.66289) (xy 1.016 -152.745694) (xy 1.016 -153.359866) (xy 86.877404 -153.359866)
			(xy 86.881424 -153.169215) (xy 86.893478 -152.978902) (xy 86.913544 -152.789267) (xy 86.941587 -152.600646)
			(xy 86.977556 -152.413376) (xy 87.021388 -152.227788) (xy 87.073005 -152.044213) (xy 87.132315 -151.862977)
			(xy 87.199213 -151.684402) (xy 87.273579 -151.508807) (xy 87.355281 -151.336502) (xy 87.444175 -151.167795)
			(xy 87.540101 -151.002985) (xy 87.64289 -150.842366) (xy 87.752359 -150.686223) (xy 87.868313 -150.534834)
			(xy 87.990547 -150.388467) (xy 88.118841 -150.247383) (xy 88.252969 -150.111834) (xy 88.392693 -149.982059)
			(xy 88.537763 -149.858289) (xy 88.687921 -149.740746) (xy 88.842902 -149.629637) (xy 89.002429 -149.52516)
			(xy 89.166218 -149.427501) (xy 89.333978 -149.336834) (xy 89.505412 -149.25332) (xy 89.680214 -149.177107)
			(xy 89.858073 -149.108331) (xy 90.038674 -149.047113) (xy 90.221694 -148.993564) (xy 90.40681 -148.947778)
			(xy 90.593691 -148.909836) (xy 90.782006 -148.879807) (xy 90.971419 -148.857742) (xy 91.161593 -148.843683)
			(xy 91.352192 -148.837653) (xy 91.542875 -148.839663) (xy 91.733304 -148.84971) (xy 91.92314 -148.867776)
			(xy 92.112046 -148.893829) (xy 92.299685 -148.927822) (xy 92.485725 -148.969695) (xy 92.669834 -149.019374)
			(xy 92.851685 -149.07677) (xy 93.030955 -149.141781) (xy 93.207325 -149.214292) (xy 93.380481 -149.294173)
			(xy 93.550116 -149.381283) (xy 93.715928 -149.475467) (xy 93.877622 -149.576558) (xy 94.03491 -149.684374)
			(xy 94.187513 -149.798726) (xy 94.335161 -149.919409) (xy 94.477589 -150.04621) (xy 94.614545 -150.178901)
			(xy 94.745786 -150.317249) (xy 94.871078 -150.461006) (xy 94.990198 -150.609917) (xy 95.102934 -150.763718)
			(xy 95.209087 -150.922134) (xy 95.308467 -151.084885) (xy 95.400897 -151.25168) (xy 95.486214 -151.422224)
			(xy 95.564266 -151.596212) (xy 95.634913 -151.773337) (xy 95.698031 -151.953282) (xy 95.753507 -152.135728)
			(xy 95.801242 -152.320351) (xy 95.841152 -152.506821) (xy 95.873165 -152.694809) (xy 95.897225 -152.883979)
			(xy 95.913288 -153.073995) (xy 95.921327 -153.264519) (xy 95.92183 -153.359866) (xy 95.921327 -153.455213)
			(xy 95.913288 -153.645737) (xy 95.897225 -153.835753) (xy 95.873165 -154.024923) (xy 95.841152 -154.212911)
			(xy 95.801242 -154.399381) (xy 95.753507 -154.584004) (xy 95.698031 -154.76645) (xy 95.634913 -154.946395)
			(xy 95.564266 -155.12352) (xy 95.486214 -155.297508) (xy 95.400897 -155.468052) (xy 95.308467 -155.634847)
			(xy 95.209087 -155.797598) (xy 95.102934 -155.956014) (xy 94.990198 -156.109815) (xy 94.871078 -156.258726)
			(xy 94.745786 -156.402483) (xy 94.614545 -156.540831) (xy 94.477589 -156.673522) (xy 94.335161 -156.800323)
			(xy 94.187513 -156.921006) (xy 94.03491 -157.035358) (xy 93.877622 -157.143174) (xy 93.715928 -157.244265)
			(xy 93.550116 -157.338449) (xy 93.380481 -157.425559) (xy 93.207325 -157.50544) (xy 93.030955 -157.577951)
			(xy 92.851685 -157.642962) (xy 92.669834 -157.700358) (xy 92.485725 -157.750037) (xy 92.299685 -157.79191)
			(xy 92.112046 -157.825903) (xy 91.92314 -157.851956) (xy 91.733304 -157.870022) (xy 91.542875 -157.880069)
			(xy 91.352192 -157.882079) (xy 91.161593 -157.876049) (xy 90.971419 -157.86199) (xy 90.782006 -157.839925)
			(xy 90.593691 -157.809896) (xy 90.40681 -157.771954) (xy 90.221694 -157.726168) (xy 90.038674 -157.672619)
			(xy 89.858073 -157.611401) (xy 89.680214 -157.542625) (xy 89.505412 -157.466412) (xy 89.333978 -157.382898)
			(xy 89.166218 -157.292231) (xy 89.002429 -157.194572) (xy 88.842902 -157.090095) (xy 88.687921 -156.978986)
			(xy 88.537763 -156.861443) (xy 88.392693 -156.737673) (xy 88.252969 -156.607898) (xy 88.118841 -156.472349)
			(xy 87.990547 -156.331265) (xy 87.868313 -156.184898) (xy 87.752359 -156.033509) (xy 87.64289 -155.877366)
			(xy 87.540101 -155.716747) (xy 87.444175 -155.551937) (xy 87.355281 -155.38323) (xy 87.273579 -155.210925)
			(xy 87.199213 -155.03533) (xy 87.132315 -154.856755) (xy 87.073005 -154.675519) (xy 87.021388 -154.491944)
			(xy 86.977556 -154.306356) (xy 86.941587 -154.119086) (xy 86.913544 -153.930465) (xy 86.893478 -153.74083)
			(xy 86.881424 -153.550517) (xy 86.877404 -153.359866) (xy 1.016 -153.359866) (xy 1.016 -164.771578)
			(xy 1.047496 -164.854382) (xy 1.059942 -164.869876) (xy 1.077482 -164.89257) (xy 1.106268 -164.942179)
			(xy 1.127305 -164.995537) (xy 1.14012 -165.051442) (xy 1.144423 -165.108636) (xy 1.14012 -165.16583)
			(xy 1.127305 -165.221735) (xy 1.106268 -165.275093) (xy 1.077482 -165.324702) (xy 1.059942 -165.347396)
			(xy 1.047496 -165.36289) (xy 1.016 -165.445694) (xy 1.016 -177.471578) (xy 1.047496 -177.554382)
			(xy 1.059942 -177.569876) (xy 1.077482 -177.59257) (xy 1.106268 -177.642179) (xy 1.127305 -177.695537)
			(xy 1.14012 -177.751442) (xy 1.144423 -177.808636) (xy 1.14012 -177.86583) (xy 1.127305 -177.921735)
			(xy 1.106268 -177.975093) (xy 1.077482 -178.024702) (xy 1.059942 -178.047396) (xy 1.047496 -178.06289)
			(xy 1.016 -178.145694) (xy 1.016 -184.71007) (xy 39.818317 -184.71007) (xy 39.822324 -184.594046)
			(xy 39.834326 -184.478574) (xy 39.854266 -184.364206) (xy 39.882049 -184.251486) (xy 39.917543 -184.140952)
			(xy 39.960578 -184.033129) (xy 40.010949 -183.928532) (xy 40.068416 -183.82766) (xy 40.132706 -183.730993)
			(xy 40.203511 -183.638992) (xy 40.280495 -183.552095) (xy 40.363291 -183.470716) (xy 40.451504 -183.395243)
			(xy 40.544714 -183.326036) (xy 40.642477 -183.263424) (xy 40.744326 -183.207707) (xy 40.849776 -183.159149)
			(xy 40.958325 -183.117981) (xy 41.069456 -183.084401) (xy 41.182639 -183.058568) (xy 41.297334 -183.040605)
			(xy 41.412996 -183.030597) (xy 41.529072 -183.028594) (xy 41.64501 -183.034603) (xy 41.760257 -183.048596)
			(xy 41.874263 -183.070507) (xy 41.986487 -183.100232) (xy 42.096393 -183.137628) (xy 42.203456 -183.182517)
			(xy 42.307168 -183.234686) (xy 42.407033 -183.293886) (xy 42.502576 -183.359835) (xy 42.593342 -183.432218)
			(xy 42.678897 -183.510691) (xy 42.758835 -183.594879) (xy 42.832774 -183.684381) (xy 42.900362 -183.778772)
			(xy 42.961276 -183.8776) (xy 43.015228 -183.980396) (xy 43.061958 -184.086669) (xy 43.101246 -184.195913)
			(xy 43.132903 -184.307606) (xy 43.156779 -184.421218) (xy 43.17276 -184.536206) (xy 43.180769 -184.652023)
			(xy 43.18127 -184.71007) (xy 43.180769 -184.768117) (xy 43.17276 -184.883934) (xy 43.156779 -184.998922)
			(xy 43.132903 -185.112534) (xy 43.101246 -185.224227) (xy 43.061958 -185.333471) (xy 43.015228 -185.439744)
			(xy 42.961276 -185.54254) (xy 42.900362 -185.641368) (xy 42.832774 -185.735759) (xy 42.758835 -185.825261)
			(xy 42.678897 -185.909449) (xy 42.593342 -185.987922) (xy 42.502858 -186.06008) (xy 93.15476 -186.06008)
			(xy 93.158776 -185.94381) (xy 93.170803 -185.828095) (xy 93.190785 -185.713485) (xy 93.218627 -185.600526)
			(xy 93.254196 -185.489758) (xy 93.297322 -185.381707) (xy 93.347799 -185.276889) (xy 93.405388 -185.175804)
			(xy 93.469814 -185.078932) (xy 93.540769 -184.986736) (xy 93.617916 -184.899655) (xy 93.700887 -184.818104)
			(xy 93.789287 -184.742472) (xy 93.882694 -184.673118) (xy 93.980663 -184.610375) (xy 94.082727 -184.554539)
			(xy 94.188401 -184.505878) (xy 94.29718 -184.464624) (xy 94.408545 -184.430973) (xy 94.521968 -184.405085)
			(xy 94.636905 -184.387084) (xy 94.752811 -184.377055) (xy 94.869133 -184.375047) (xy 94.985316 -184.381069)
			(xy 95.100807 -184.395092) (xy 95.215055 -184.41705) (xy 95.327516 -184.446837) (xy 95.437654 -184.484312)
			(xy 95.544944 -184.529297) (xy 95.648875 -184.581576) (xy 95.748951 -184.640901) (xy 95.844697 -184.706989)
			(xy 95.935654 -184.779525) (xy 96.02139 -184.858164) (xy 96.101497 -184.94253) (xy 96.175593 -185.032222)
			(xy 96.243323 -185.126812) (xy 96.304367 -185.22585) (xy 96.358432 -185.328863) (xy 96.405262 -185.43536)
			(xy 96.444633 -185.544835) (xy 96.476357 -185.656765) (xy 96.500283 -185.770617) (xy 96.516297 -185.885849)
			(xy 96.524324 -186.001911) (xy 96.524826 -186.06008) (xy 96.524324 -186.118249) (xy 96.516297 -186.234311)
			(xy 96.500283 -186.349543) (xy 96.476357 -186.463395) (xy 96.444633 -186.575325) (xy 96.405262 -186.6848)
			(xy 96.358432 -186.791297) (xy 96.304367 -186.89431) (xy 96.243323 -186.993348) (xy 96.175593 -187.087938)
			(xy 96.101497 -187.17763) (xy 96.02139 -187.261996) (xy 95.935654 -187.340635) (xy 95.844697 -187.413171)
			(xy 95.748951 -187.479259) (xy 95.648875 -187.538584) (xy 95.544944 -187.590863) (xy 95.437654 -187.635848)
			(xy 95.327516 -187.673323) (xy 95.215055 -187.70311) (xy 95.100807 -187.725068) (xy 94.985316 -187.739091)
			(xy 94.869133 -187.745113) (xy 94.752811 -187.743105) (xy 94.636905 -187.733076) (xy 94.521968 -187.715075)
			(xy 94.408545 -187.689187) (xy 94.29718 -187.655536) (xy 94.188401 -187.614282) (xy 94.082727 -187.565621)
			(xy 93.980663 -187.509785) (xy 93.882694 -187.447042) (xy 93.789287 -187.377688) (xy 93.700887 -187.302056)
			(xy 93.617916 -187.220505) (xy 93.540769 -187.133424) (xy 93.469814 -187.041228) (xy 93.405388 -186.944356)
			(xy 93.347799 -186.843271) (xy 93.297322 -186.738453) (xy 93.254196 -186.630402) (xy 93.218627 -186.519634)
			(xy 93.190785 -186.406675) (xy 93.170803 -186.292065) (xy 93.158776 -186.17635) (xy 93.15476 -186.06008)
			(xy 42.502858 -186.06008) (xy 42.502576 -186.060305) (xy 42.407033 -186.126254) (xy 42.307168 -186.185454)
			(xy 42.203456 -186.237623) (xy 42.096393 -186.282512) (xy 41.986487 -186.319908) (xy 41.874263 -186.349633)
			(xy 41.760257 -186.371544) (xy 41.64501 -186.385537) (xy 41.529072 -186.391546) (xy 41.412996 -186.389543)
			(xy 41.297334 -186.379535) (xy 41.182639 -186.361572) (xy 41.069456 -186.335739) (xy 40.958325 -186.302159)
			(xy 40.849776 -186.260991) (xy 40.744326 -186.212433) (xy 40.642477 -186.156716) (xy 40.544714 -186.094104)
			(xy 40.451504 -186.024897) (xy 40.363291 -185.949424) (xy 40.280495 -185.868045) (xy 40.203511 -185.781148)
			(xy 40.132706 -185.689147) (xy 40.068416 -185.59248) (xy 40.010949 -185.491608) (xy 39.960578 -185.387011)
			(xy 39.917543 -185.279188) (xy 39.882049 -185.168654) (xy 39.854266 -185.055934) (xy 39.834326 -184.941566)
			(xy 39.822324 -184.826094) (xy 39.818317 -184.71007) (xy 1.016 -184.71007) (xy 1.016 -190.171578)
			(xy 1.047496 -190.254382) (xy 1.059942 -190.269876) (xy 1.077482 -190.29257) (xy 1.106268 -190.342179)
			(xy 1.127305 -190.395537) (xy 1.14012 -190.451442) (xy 1.144423 -190.508636) (xy 1.14012 -190.56583)
			(xy 1.127305 -190.621735) (xy 1.106268 -190.675093) (xy 1.077482 -190.724702) (xy 1.059942 -190.747396)
			(xy 1.047496 -190.76289) (xy 1.016 -190.845694) (xy 1.016 -197.81012) (xy 86.877404 -197.81012) (xy 86.881424 -197.619469)
			(xy 86.893478 -197.429156) (xy 86.913544 -197.239521) (xy 86.941587 -197.0509) (xy 86.977556 -196.86363)
			(xy 87.021388 -196.678042) (xy 87.073005 -196.494467) (xy 87.132315 -196.313231) (xy 87.199213 -196.134656)
			(xy 87.273579 -195.959061) (xy 87.355281 -195.786756) (xy 87.444175 -195.618049) (xy 87.540101 -195.453239)
			(xy 87.64289 -195.29262) (xy 87.752359 -195.136477) (xy 87.868313 -194.985088) (xy 87.990547 -194.838721)
			(xy 88.118841 -194.697637) (xy 88.252969 -194.562088) (xy 88.392693 -194.432313) (xy 88.537763 -194.308543)
			(xy 88.687921 -194.191) (xy 88.842902 -194.079891) (xy 89.002429 -193.975414) (xy 89.166218 -193.877755)
			(xy 89.333978 -193.787088) (xy 89.505412 -193.703574) (xy 89.680214 -193.627361) (xy 89.858073 -193.558585)
			(xy 90.038674 -193.497367) (xy 90.221694 -193.443818) (xy 90.40681 -193.398032) (xy 90.593691 -193.36009)
			(xy 90.782006 -193.330061) (xy 90.971419 -193.307996) (xy 91.161593 -193.293937) (xy 91.352192 -193.287907)
			(xy 91.542875 -193.289917) (xy 91.733304 -193.299964) (xy 91.92314 -193.31803) (xy 92.112046 -193.344083)
			(xy 92.299685 -193.378076) (xy 92.485725 -193.419949) (xy 92.669834 -193.469628) (xy 92.851685 -193.527024)
			(xy 93.030955 -193.592035) (xy 93.207325 -193.664546) (xy 93.380481 -193.744427) (xy 93.550116 -193.831537)
			(xy 93.715928 -193.925721) (xy 93.877622 -194.026812) (xy 94.03491 -194.134628) (xy 94.187513 -194.24898)
			(xy 94.335161 -194.369663) (xy 94.477589 -194.496464) (xy 94.614545 -194.629155) (xy 94.745786 -194.767503)
			(xy 94.871078 -194.91126) (xy 94.990198 -195.060171) (xy 95.102934 -195.213972) (xy 95.209087 -195.372388)
			(xy 95.308467 -195.535139) (xy 95.400897 -195.701934) (xy 95.486214 -195.872478) (xy 95.564266 -196.046466)
			(xy 95.634913 -196.223591) (xy 95.698031 -196.403536) (xy 95.753507 -196.585982) (xy 95.801242 -196.770605)
			(xy 95.841152 -196.957075) (xy 95.873165 -197.145063) (xy 95.897225 -197.334233) (xy 95.913288 -197.524249)
			(xy 95.921327 -197.714773) (xy 95.92183 -197.81012) (xy 95.921327 -197.905467) (xy 95.913288 -198.095991)
			(xy 95.897225 -198.286007) (xy 95.873165 -198.475177) (xy 95.841152 -198.663165) (xy 95.801242 -198.849635)
			(xy 95.753507 -199.034258) (xy 95.698031 -199.216704) (xy 95.634913 -199.396649) (xy 95.564266 -199.573774)
			(xy 95.486214 -199.747762) (xy 95.400897 -199.918306) (xy 95.308467 -200.085101) (xy 95.209087 -200.247852)
			(xy 95.102934 -200.406268) (xy 94.990198 -200.560069) (xy 94.871078 -200.70898) (xy 94.745786 -200.852737)
			(xy 94.614545 -200.991085) (xy 94.477589 -201.123776) (xy 94.335161 -201.250577) (xy 94.187513 -201.37126)
			(xy 94.03491 -201.485612) (xy 93.877622 -201.593428) (xy 93.715928 -201.694519) (xy 93.550116 -201.788703)
			(xy 93.380481 -201.875813) (xy 93.207325 -201.955694) (xy 93.030955 -202.028205) (xy 92.851685 -202.093216)
			(xy 92.669834 -202.150612) (xy 92.485725 -202.200291) (xy 92.299685 -202.242164) (xy 92.112046 -202.276157)
			(xy 91.92314 -202.30221) (xy 91.733304 -202.320276) (xy 91.542875 -202.330323) (xy 91.352192 -202.332333)
			(xy 91.161593 -202.326303) (xy 90.971419 -202.312244) (xy 90.782006 -202.290179) (xy 90.593691 -202.26015)
			(xy 90.40681 -202.222208) (xy 90.221694 -202.176422) (xy 90.038674 -202.122873) (xy 89.858073 -202.061655)
			(xy 89.680214 -201.992879) (xy 89.505412 -201.916666) (xy 89.333978 -201.833152) (xy 89.166218 -201.742485)
			(xy 89.002429 -201.644826) (xy 88.842902 -201.540349) (xy 88.687921 -201.42924) (xy 88.537763 -201.311697)
			(xy 88.392693 -201.187927) (xy 88.252969 -201.058152) (xy 88.118841 -200.922603) (xy 87.990547 -200.781519)
			(xy 87.868313 -200.635152) (xy 87.752359 -200.483763) (xy 87.64289 -200.32762) (xy 87.540101 -200.167001)
			(xy 87.444175 -200.002191) (xy 87.355281 -199.833484) (xy 87.273579 -199.661179) (xy 87.199213 -199.485584)
			(xy 87.132315 -199.307009) (xy 87.073005 -199.125773) (xy 87.021388 -198.942198) (xy 86.977556 -198.75661)
			(xy 86.941587 -198.56934) (xy 86.913544 -198.380719) (xy 86.893478 -198.191084) (xy 86.881424 -198.000771)
			(xy 86.877404 -197.81012) (xy 1.016 -197.81012) (xy 1.016 -202.871578) (xy 1.047496 -202.954382)
			(xy 1.059942 -202.969876) (xy 1.077482 -202.99257) (xy 1.106268 -203.042179) (xy 1.127305 -203.095537)
			(xy 1.14012 -203.151442) (xy 1.144423 -203.208636) (xy 1.14012 -203.26583) (xy 1.127305 -203.321735)
			(xy 1.106268 -203.375093) (xy 1.077482 -203.424702) (xy 1.059942 -203.447396) (xy 1.047496 -203.46289)
			(xy 1.016 -203.545694) (xy 1.016 -206.99984) (xy 11.34441 -206.99984) (xy 11.348411 -206.794791)
			(xy 11.36041 -206.590054) (xy 11.380388 -206.385941) (xy 11.408314 -206.182762) (xy 11.444146 -205.980829)
			(xy 11.48783 -205.780446) (xy 11.539298 -205.581921) (xy 11.598473 -205.385555) (xy 11.665264 -205.191648)
			(xy 11.73957 -205.000494) (xy 11.821277 -204.812384) (xy 11.910262 -204.627606) (xy 12.006388 -204.44644)
			(xy 12.109509 -204.269163) (xy 12.219469 -204.096044) (xy 12.336099 -203.927347) (xy 12.459222 -203.763329)
			(xy 12.588651 -203.60424) (xy 12.724188 -203.450322) (xy 12.865627 -203.301808) (xy 13.012754 -203.158927)
			(xy 13.165342 -203.021894) (xy 13.323161 -202.89092) (xy 13.48597 -202.766202) (xy 13.653521 -202.647932)
			(xy 13.825559 -202.536288) (xy 14.001822 -202.431442) (xy 14.182041 -202.333553) (xy 14.365942 -202.24277)
			(xy 14.553246 -202.159232) (xy 14.743666 -202.083064) (xy 14.936912 -202.014384) (xy 15.132692 -201.953296)
			(xy 15.330705 -201.899894) (xy 15.530652 -201.854257) (xy 15.732226 -201.816457) (xy 15.935122 -201.786549)
			(xy 16.139031 -201.764581) (xy 16.343641 -201.750586) (xy 16.548641 -201.744584) (xy 16.75372 -201.746585)
			(xy 16.958564 -201.756585) (xy 17.162863 -201.774571) (xy 17.366304 -201.800513) (xy 17.568577 -201.834374)
			(xy 17.769376 -201.8761) (xy 17.968394 -201.925629) (xy 18.165328 -201.982885) (xy 18.359878 -202.047782)
			(xy 18.551748 -202.120219) (xy 18.740645 -202.200087) (xy 18.926283 -202.287265) (xy 19.108378 -202.381619)
			(xy 19.286653 -202.483006) (xy 19.460836 -202.591271) (xy 19.630663 -202.706249) (xy 19.795875 -202.827767)
			(xy 19.956219 -202.955637) (xy 20.111453 -203.089666) (xy 20.261339 -203.22965) (xy 20.405649 -203.375375)
			(xy 20.544163 -203.52662) (xy 20.676672 -203.683153) (xy 20.802972 -203.844738) (xy 20.922871 -204.011127)
			(xy 21.036188 -204.182067) (xy 21.142748 -204.357299) (xy 21.242391 -204.536554) (xy 21.334964 -204.719561)
			(xy 21.420326 -204.90604) (xy 21.498347 -205.095708) (xy 21.56891 -205.288276) (xy 21.631905 -205.48345)
			(xy 21.687237 -205.680933) (xy 21.734822 -205.880424) (xy 21.774587 -206.081621) (xy 21.806472 -206.284215)
			(xy 21.830429 -206.4879) (xy 21.84642 -206.692364) (xy 21.854422 -206.897296) (xy 21.854922 -206.99984)
			(xy 21.854422 -207.102384) (xy 21.84642 -207.307316) (xy 21.830429 -207.51178) (xy 21.806472 -207.715465)
			(xy 21.774587 -207.918059) (xy 21.734822 -208.119256) (xy 21.687237 -208.318747) (xy 21.631905 -208.51623)
			(xy 21.56891 -208.711404) (xy 21.498347 -208.903972) (xy 21.420326 -209.09364) (xy 21.334964 -209.280119)
			(xy 21.242391 -209.463126) (xy 21.142748 -209.642381) (xy 21.036188 -209.817613) (xy 20.922871 -209.988553)
			(xy 20.842811 -210.099656) (xy 72.864987 -210.099656) (xy 72.868996 -209.896785) (xy 72.881016 -209.694231)
			(xy 72.90103 -209.49231) (xy 72.929005 -209.291337) (xy 72.964898 -209.091627) (xy 73.008652 -208.89349)
			(xy 73.060201 -208.697237) (xy 73.119462 -208.503173) (xy 73.186344 -208.311602) (xy 73.260742 -208.122823)
			(xy 73.34254 -207.93713) (xy 73.43161 -207.754814) (xy 73.527813 -207.576159) (xy 73.631 -207.401445)
			(xy 73.741008 -207.230943) (xy 73.857666 -207.06492) (xy 73.980792 -206.903636) (xy 74.110194 -206.747342)
			(xy 74.245669 -206.596282) (xy 74.387006 -206.450692) (xy 74.533985 -206.3108) (xy 74.686376 -206.176824)
			(xy 74.843941 -206.048972) (xy 75.006434 -205.927446) (xy 75.173601 -205.812433) (xy 75.345181 -205.704115)
			(xy 75.520906 -205.60266) (xy 75.700503 -205.508226) (xy 75.88369 -205.420961) (xy 76.070182 -205.341002)
			(xy 76.259687 -205.268473) (xy 76.451909 -205.203487) (xy 76.646549 -205.146145) (xy 76.843302 -205.096538)
			(xy 77.041861 -205.054743) (xy 77.241917 -205.020825) (xy 77.443156 -204.994837) (xy 77.645265 -204.976819)
			(xy 77.847928 -204.9668) (xy 78.050828 -204.964796) (xy 78.253649 -204.970808) (xy 78.456075 -204.984829)
			(xy 78.657788 -205.006837) (xy 78.858475 -205.036796) (xy 79.057821 -205.07466) (xy 79.255516 -205.12037)
			(xy 79.45125 -205.173854) (xy 79.644719 -205.23503) (xy 79.83562 -205.303801) (xy 80.023655 -205.380061)
			(xy 80.208531 -205.463689) (xy 80.389958 -205.554556) (xy 80.567654 -205.652519) (xy 80.74134 -205.757427)
			(xy 80.910747 -205.869114) (xy 81.075609 -205.987406) (xy 81.235669 -206.11212) (xy 81.390677 -206.243059)
			(xy 81.540391 -206.38002) (xy 81.684577 -206.522789) (xy 81.823011 -206.671143) (xy 81.955475 -206.82485)
			(xy 82.081764 -206.98367) (xy 82.201679 -207.147355) (xy 82.315035 -207.31565) (xy 82.421653 -207.488292)
			(xy 82.521367 -207.665012) (xy 82.614022 -207.845532) (xy 82.699472 -208.029572) (xy 82.777586 -208.216845)
			(xy 82.848239 -208.407057) (xy 82.911323 -208.599912) (xy 82.966739 -208.795109) (xy 83.0144 -208.992342)
			(xy 83.054231 -209.191305) (xy 83.086171 -209.391686) (xy 83.11017 -209.593172) (xy 83.12619 -209.795449)
			(xy 83.134207 -209.998201) (xy 83.134708 -210.099656) (xy 83.134207 -210.201111) (xy 83.12619 -210.403863)
			(xy 83.11017 -210.60614) (xy 83.086171 -210.807626) (xy 83.054231 -211.008007) (xy 83.0144 -211.20697)
			(xy 82.966739 -211.404203) (xy 82.911323 -211.5994) (xy 82.848239 -211.792255) (xy 82.777586 -211.982467)
			(xy 82.699472 -212.16974) (xy 82.614022 -212.35378) (xy 82.521367 -212.5343) (xy 82.421653 -212.71102)
			(xy 82.315035 -212.883662) (xy 82.201679 -213.051957) (xy 82.081764 -213.215642) (xy 81.955475 -213.374462)
			(xy 81.823011 -213.528169) (xy 81.684577 -213.676523) (xy 81.540391 -213.819292) (xy 81.390677 -213.956253)
			(xy 81.235669 -214.087192) (xy 81.075609 -214.211906) (xy 80.910747 -214.330198) (xy 80.74134 -214.441885)
			(xy 80.567654 -214.546793) (xy 80.389958 -214.644756) (xy 80.208531 -214.735623) (xy 80.023655 -214.819251)
			(xy 79.83562 -214.895511) (xy 79.644719 -214.964282) (xy 79.45125 -215.025458) (xy 79.255516 -215.078942)
			(xy 79.057821 -215.124652) (xy 78.858475 -215.162516) (xy 78.657788 -215.192475) (xy 78.456075 -215.214483)
			(xy 78.253649 -215.228504) (xy 78.050828 -215.234516) (xy 77.847928 -215.232512) (xy 77.645265 -215.222493)
			(xy 77.443156 -215.204475) (xy 77.241917 -215.178487) (xy 77.041861 -215.144569) (xy 76.843302 -215.102774)
			(xy 76.646549 -215.053167) (xy 76.451909 -214.995825) (xy 76.259687 -214.930839) (xy 76.070182 -214.85831)
			(xy 75.88369 -214.778351) (xy 75.700503 -214.691086) (xy 75.520906 -214.596652) (xy 75.345181 -214.495197)
			(xy 75.173601 -214.386879) (xy 75.006434 -214.271866) (xy 74.843941 -214.15034) (xy 74.686376 -214.022488)
			(xy 74.533985 -213.888512) (xy 74.387006 -213.74862) (xy 74.245669 -213.60303) (xy 74.110194 -213.45197)
			(xy 73.980792 -213.295676) (xy 73.857666 -213.134392) (xy 73.741008 -212.968369) (xy 73.631 -212.797867)
			(xy 73.527813 -212.623153) (xy 73.43161 -212.444498) (xy 73.34254 -212.262182) (xy 73.260742 -212.076489)
			(xy 73.186344 -211.88771) (xy 73.119462 -211.696139) (xy 73.060201 -211.502075) (xy 73.008652 -211.305822)
			(xy 72.964898 -211.107685) (xy 72.929005 -210.907975) (xy 72.90103 -210.707002) (xy 72.881016 -210.505081)
			(xy 72.868996 -210.302527) (xy 72.864987 -210.099656) (xy 20.842811 -210.099656) (xy 20.802972 -210.154942)
			(xy 20.676672 -210.316527) (xy 20.544163 -210.47306) (xy 20.405649 -210.624305) (xy 20.261339 -210.77003)
			(xy 20.111453 -210.910014) (xy 19.956219 -211.044043) (xy 19.795875 -211.171913) (xy 19.630663 -211.293431)
			(xy 19.460836 -211.408409) (xy 19.286653 -211.516674) (xy 19.108378 -211.618061) (xy 18.926283 -211.712415)
			(xy 18.740645 -211.799593) (xy 18.551748 -211.879461) (xy 18.359878 -211.951898) (xy 18.165328 -212.016795)
			(xy 17.968394 -212.074051) (xy 17.769376 -212.12358) (xy 17.568577 -212.165306) (xy 17.366304 -212.199167)
			(xy 17.162863 -212.225109) (xy 16.958564 -212.243095) (xy 16.75372 -212.253095) (xy 16.548641 -212.255096)
			(xy 16.343641 -212.249094) (xy 16.139031 -212.235099) (xy 15.935122 -212.213131) (xy 15.732226 -212.183223)
			(xy 15.530652 -212.145423) (xy 15.330705 -212.099786) (xy 15.132692 -212.046384) (xy 14.936912 -211.985296)
			(xy 14.743666 -211.916616) (xy 14.553246 -211.840448) (xy 14.365942 -211.75691) (xy 14.182041 -211.666127)
			(xy 14.001822 -211.568238) (xy 13.825559 -211.463392) (xy 13.653521 -211.351748) (xy 13.48597 -211.233478)
			(xy 13.323161 -211.10876) (xy 13.165342 -210.977786) (xy 13.012754 -210.840753) (xy 12.865627 -210.697872)
			(xy 12.724188 -210.549358) (xy 12.588651 -210.39544) (xy 12.459222 -210.236351) (xy 12.336099 -210.072333)
			(xy 12.219469 -209.903636) (xy 12.109509 -209.730517) (xy 12.006388 -209.55324) (xy 11.910262 -209.372074)
			(xy 11.821277 -209.187296) (xy 11.73957 -208.999186) (xy 11.665264 -208.808032) (xy 11.598473 -208.614125)
			(xy 11.539298 -208.417759) (xy 11.48783 -208.219234) (xy 11.444146 -208.018851) (xy 11.408314 -207.816918)
			(xy 11.380388 -207.613739) (xy 11.36041 -207.409626) (xy 11.348411 -207.204889) (xy 11.34441 -206.99984)
			(xy 1.016 -206.99984) (xy 1.016 -215.571578) (xy 1.047496 -215.654382) (xy 1.059942 -215.669876)
			(xy 1.077482 -215.69257) (xy 1.106268 -215.742179) (xy 1.127305 -215.795537) (xy 1.14012 -215.851442)
			(xy 1.144423 -215.908636) (xy 1.14012 -215.96583) (xy 1.127305 -216.021735) (xy 1.106268 -216.075093)
			(xy 1.077482 -216.124702) (xy 1.059942 -216.147396) (xy 1.047496 -216.16289) (xy 1.016 -216.245694)
			(xy 1.016 -228.271578) (xy 1.047496 -228.354382) (xy 1.059942 -228.369876) (xy 1.077482 -228.39257)
			(xy 1.106268 -228.442179) (xy 1.127305 -228.495537) (xy 1.14012 -228.551442) (xy 1.144423 -228.608636)
			(xy 1.14012 -228.66583) (xy 1.127305 -228.721735) (xy 1.106268 -228.775093) (xy 1.077482 -228.824702)
			(xy 1.059942 -228.847396) (xy 1.047496 -228.86289) (xy 1.016 -228.945694) (xy 1.016 -229.16007) (xy 39.818063 -229.16007)
			(xy 39.82207 -229.044046) (xy 39.834072 -228.928574) (xy 39.854012 -228.814206) (xy 39.881795 -228.701486)
			(xy 39.917289 -228.590952) (xy 39.960324 -228.483129) (xy 40.010695 -228.378532) (xy 40.068162 -228.27766)
			(xy 40.132452 -228.180993) (xy 40.203257 -228.088992) (xy 40.280241 -228.002095) (xy 40.363037 -227.920716)
			(xy 40.45125 -227.845243) (xy 40.54446 -227.776036) (xy 40.642223 -227.713424) (xy 40.744072 -227.657707)
			(xy 40.849522 -227.609149) (xy 40.958071 -227.567981) (xy 41.069202 -227.534401) (xy 41.182385 -227.508568)
			(xy 41.29708 -227.490605) (xy 41.412742 -227.480597) (xy 41.528818 -227.478594) (xy 41.644756 -227.484603)
			(xy 41.760003 -227.498596) (xy 41.874009 -227.520507) (xy 41.986233 -227.550232) (xy 42.096139 -227.587628)
			(xy 42.203202 -227.632517) (xy 42.306914 -227.684686) (xy 42.406779 -227.743886) (xy 42.502322 -227.809835)
			(xy 42.593088 -227.882218) (xy 42.678643 -227.960691) (xy 42.758581 -228.044879) (xy 42.83252 -228.134381)
			(xy 42.900108 -228.228772) (xy 42.961022 -228.3276) (xy 43.014974 -228.430396) (xy 43.061704 -228.536669)
			(xy 43.100992 -228.645913) (xy 43.132649 -228.757606) (xy 43.156525 -228.871218) (xy 43.172506 -228.986206)
			(xy 43.180515 -229.102023) (xy 43.181016 -229.16007) (xy 43.180515 -229.218117) (xy 43.172506 -229.333934)
			(xy 43.156525 -229.448922) (xy 43.132649 -229.562534) (xy 43.100992 -229.674227) (xy 43.061704 -229.783471)
			(xy 43.014974 -229.889744) (xy 42.961022 -229.99254) (xy 42.900108 -230.091368) (xy 42.83252 -230.185759)
			(xy 42.758581 -230.275261) (xy 42.678643 -230.359449) (xy 42.593088 -230.437922) (xy 42.502604 -230.51008)
			(xy 93.154506 -230.51008) (xy 93.158522 -230.39381) (xy 93.170549 -230.278095) (xy 93.190531 -230.163485)
			(xy 93.218373 -230.050526) (xy 93.253942 -229.939758) (xy 93.297068 -229.831707) (xy 93.347545 -229.726889)
			(xy 93.405134 -229.625804) (xy 93.46956 -229.528932) (xy 93.540515 -229.436736) (xy 93.617662 -229.349655)
			(xy 93.700633 -229.268104) (xy 93.789033 -229.192472) (xy 93.88244 -229.123118) (xy 93.980409 -229.060375)
			(xy 94.082473 -229.004539) (xy 94.188147 -228.955878) (xy 94.296926 -228.914624) (xy 94.408291 -228.880973)
			(xy 94.521714 -228.855085) (xy 94.636651 -228.837084) (xy 94.752557 -228.827055) (xy 94.868879 -228.825047)
			(xy 94.985062 -228.831069) (xy 95.100553 -228.845092) (xy 95.214801 -228.86705) (xy 95.327262 -228.896837)
			(xy 95.4374 -228.934312) (xy 95.54469 -228.979297) (xy 95.648621 -229.031576) (xy 95.748697 -229.090901)
			(xy 95.844443 -229.156989) (xy 95.9354 -229.229525) (xy 96.021136 -229.308164) (xy 96.101243 -229.39253)
			(xy 96.175339 -229.482222) (xy 96.243069 -229.576812) (xy 96.304113 -229.67585) (xy 96.358178 -229.778863)
			(xy 96.405008 -229.88536) (xy 96.444379 -229.994835) (xy 96.476103 -230.106765) (xy 96.500029 -230.220617)
			(xy 96.516043 -230.335849) (xy 96.52407 -230.451911) (xy 96.524572 -230.51008) (xy 96.52407 -230.568249)
			(xy 96.516043 -230.684311) (xy 96.500029 -230.799543) (xy 96.476103 -230.913395) (xy 96.444379 -231.025325)
			(xy 96.405008 -231.1348) (xy 96.358178 -231.241297) (xy 96.304113 -231.34431) (xy 96.243069 -231.443348)
			(xy 96.175339 -231.537938) (xy 96.101243 -231.62763) (xy 96.021136 -231.711996) (xy 95.9354 -231.790635)
			(xy 95.844443 -231.863171) (xy 95.748697 -231.929259) (xy 95.648621 -231.988584) (xy 95.54469 -232.040863)
			(xy 95.4374 -232.085848) (xy 95.327262 -232.123323) (xy 95.214801 -232.15311) (xy 95.100553 -232.175068)
			(xy 94.985062 -232.189091) (xy 94.868879 -232.195113) (xy 94.752557 -232.193105) (xy 94.636651 -232.183076)
			(xy 94.521714 -232.165075) (xy 94.408291 -232.139187) (xy 94.296926 -232.105536) (xy 94.188147 -232.064282)
			(xy 94.082473 -232.015621) (xy 93.980409 -231.959785) (xy 93.88244 -231.897042) (xy 93.789033 -231.827688)
			(xy 93.700633 -231.752056) (xy 93.617662 -231.670505) (xy 93.540515 -231.583424) (xy 93.46956 -231.491228)
			(xy 93.405134 -231.394356) (xy 93.347545 -231.293271) (xy 93.297068 -231.188453) (xy 93.253942 -231.080402)
			(xy 93.218373 -230.969634) (xy 93.190531 -230.856675) (xy 93.170549 -230.742065) (xy 93.158522 -230.62635)
			(xy 93.154506 -230.51008) (xy 42.502604 -230.51008) (xy 42.502322 -230.510305) (xy 42.406779 -230.576254)
			(xy 42.306914 -230.635454) (xy 42.203202 -230.687623) (xy 42.096139 -230.732512) (xy 41.986233 -230.769908)
			(xy 41.874009 -230.799633) (xy 41.760003 -230.821544) (xy 41.644756 -230.835537) (xy 41.528818 -230.841546)
			(xy 41.412742 -230.839543) (xy 41.29708 -230.829535) (xy 41.182385 -230.811572) (xy 41.069202 -230.785739)
			(xy 40.958071 -230.752159) (xy 40.849522 -230.710991) (xy 40.744072 -230.662433) (xy 40.642223 -230.606716)
			(xy 40.54446 -230.544104) (xy 40.45125 -230.474897) (xy 40.363037 -230.399424) (xy 40.280241 -230.318045)
			(xy 40.203257 -230.231148) (xy 40.132452 -230.139147) (xy 40.068162 -230.04248) (xy 40.010695 -229.941608)
			(xy 39.960324 -229.837011) (xy 39.917289 -229.729188) (xy 39.881795 -229.618654) (xy 39.854012 -229.505934)
			(xy 39.834072 -229.391566) (xy 39.82207 -229.276094) (xy 39.818063 -229.16007) (xy 1.016 -229.16007)
			(xy 1.016 -240.971578) (xy 1.047496 -241.054382) (xy 1.059942 -241.069876) (xy 1.077482 -241.09257)
			(xy 1.106268 -241.142179) (xy 1.127305 -241.195537) (xy 1.14012 -241.251442) (xy 1.144423 -241.308636)
			(xy 1.14012 -241.36583) (xy 1.127305 -241.421735) (xy 1.106268 -241.475093) (xy 1.077482 -241.524702)
			(xy 1.059942 -241.547396) (xy 1.047496 -241.56289) (xy 1.016 -241.645694) (xy 1.016 -242.26012) (xy 86.877404 -242.26012)
			(xy 86.881424 -242.069469) (xy 86.893478 -241.879156) (xy 86.913544 -241.689521) (xy 86.941587 -241.5009)
			(xy 86.977556 -241.31363) (xy 87.021388 -241.128042) (xy 87.073005 -240.944467) (xy 87.132315 -240.763231)
			(xy 87.199213 -240.584656) (xy 87.273579 -240.409061) (xy 87.355281 -240.236756) (xy 87.444175 -240.068049)
			(xy 87.540101 -239.903239) (xy 87.64289 -239.74262) (xy 87.752359 -239.586477) (xy 87.868313 -239.435088)
			(xy 87.990547 -239.288721) (xy 88.118841 -239.147637) (xy 88.252969 -239.012088) (xy 88.392693 -238.882313)
			(xy 88.537763 -238.758543) (xy 88.687921 -238.641) (xy 88.842902 -238.529891) (xy 89.002429 -238.425414)
			(xy 89.166218 -238.327755) (xy 89.333978 -238.237088) (xy 89.505412 -238.153574) (xy 89.680214 -238.077361)
			(xy 89.858073 -238.008585) (xy 90.038674 -237.947367) (xy 90.221694 -237.893818) (xy 90.40681 -237.848032)
			(xy 90.593691 -237.81009) (xy 90.782006 -237.780061) (xy 90.971419 -237.757996) (xy 91.161593 -237.743937)
			(xy 91.352192 -237.737907) (xy 91.542875 -237.739917) (xy 91.733304 -237.749964) (xy 91.92314 -237.76803)
			(xy 92.112046 -237.794083) (xy 92.299685 -237.828076) (xy 92.485725 -237.869949) (xy 92.669834 -237.919628)
			(xy 92.851685 -237.977024) (xy 93.030955 -238.042035) (xy 93.207325 -238.114546) (xy 93.380481 -238.194427)
			(xy 93.550116 -238.281537) (xy 93.715928 -238.375721) (xy 93.877622 -238.476812) (xy 94.03491 -238.584628)
			(xy 94.187513 -238.69898) (xy 94.335161 -238.819663) (xy 94.477589 -238.946464) (xy 94.614545 -239.079155)
			(xy 94.745786 -239.217503) (xy 94.871078 -239.36126) (xy 94.990198 -239.510171) (xy 95.102934 -239.663972)
			(xy 95.209087 -239.822388) (xy 95.308467 -239.985139) (xy 95.400897 -240.151934) (xy 95.486214 -240.322478)
			(xy 95.564266 -240.496466) (xy 95.634913 -240.673591) (xy 95.698031 -240.853536) (xy 95.753507 -241.035982)
			(xy 95.801242 -241.220605) (xy 95.841152 -241.407075) (xy 95.873165 -241.595063) (xy 95.897225 -241.784233)
			(xy 95.913288 -241.974249) (xy 95.921327 -242.164773) (xy 95.92183 -242.26012) (xy 95.921327 -242.355467)
			(xy 95.913288 -242.545991) (xy 95.897225 -242.736007) (xy 95.873165 -242.925177) (xy 95.841152 -243.113165)
			(xy 95.801242 -243.299635) (xy 95.753507 -243.484258) (xy 95.698031 -243.666704) (xy 95.634913 -243.846649)
			(xy 95.564266 -244.023774) (xy 95.486214 -244.197762) (xy 95.400897 -244.368306) (xy 95.308467 -244.535101)
			(xy 95.209087 -244.697852) (xy 95.102934 -244.856268) (xy 94.990198 -245.010069) (xy 94.871078 -245.15898)
			(xy 94.745786 -245.302737) (xy 94.614545 -245.441085) (xy 94.477589 -245.573776) (xy 94.335161 -245.700577)
			(xy 94.187513 -245.82126) (xy 94.03491 -245.935612) (xy 93.877622 -246.043428) (xy 93.715928 -246.144519)
			(xy 93.550116 -246.238703) (xy 93.380481 -246.325813) (xy 93.207325 -246.405694) (xy 93.030955 -246.478205)
			(xy 92.851685 -246.543216) (xy 92.669834 -246.600612) (xy 92.485725 -246.650291) (xy 92.299685 -246.692164)
			(xy 92.112046 -246.726157) (xy 91.92314 -246.75221) (xy 91.733304 -246.770276) (xy 91.542875 -246.780323)
			(xy 91.352192 -246.782333) (xy 91.161593 -246.776303) (xy 90.971419 -246.762244) (xy 90.782006 -246.740179)
			(xy 90.593691 -246.71015) (xy 90.40681 -246.672208) (xy 90.221694 -246.626422) (xy 90.038674 -246.572873)
			(xy 89.858073 -246.511655) (xy 89.680214 -246.442879) (xy 89.505412 -246.366666) (xy 89.333978 -246.283152)
			(xy 89.166218 -246.192485) (xy 89.002429 -246.094826) (xy 88.842902 -245.990349) (xy 88.687921 -245.87924)
			(xy 88.537763 -245.761697) (xy 88.392693 -245.637927) (xy 88.252969 -245.508152) (xy 88.118841 -245.372603)
			(xy 87.990547 -245.231519) (xy 87.868313 -245.085152) (xy 87.752359 -244.933763) (xy 87.64289 -244.77762)
			(xy 87.540101 -244.617001) (xy 87.444175 -244.452191) (xy 87.355281 -244.283484) (xy 87.273579 -244.111179)
			(xy 87.199213 -243.935584) (xy 87.132315 -243.757009) (xy 87.073005 -243.575773) (xy 87.021388 -243.392198)
			(xy 86.977556 -243.20661) (xy 86.941587 -243.01934) (xy 86.913544 -242.830719) (xy 86.893478 -242.641084)
			(xy 86.881424 -242.450771) (xy 86.877404 -242.26012) (xy 1.016 -242.26012) (xy 1.016 -250.020582)
			(xy 3.582162 -250.020582) (xy 3.582659 -249.96334) (xy 3.590757 -249.849142) (xy 3.606915 -249.735803)
			(xy 3.631052 -249.623892) (xy 3.663046 -249.513969) (xy 3.702737 -249.406585) (xy 3.749927 -249.302279)
			(xy 3.804379 -249.201573) (xy 3.865819 -249.104971) (xy 3.93394 -249.012959) (xy 4.008401 -248.925998)
			(xy 4.088828 -248.844523) (xy 4.174818 -248.768942) (xy 4.26594 -248.699635) (xy 4.361737 -248.636949)
			(xy 4.46173 -248.581198) (xy 4.565416 -248.532661) (xy 4.672277 -248.491582) (xy 4.781777 -248.458167)
			(xy 4.893366 -248.432584) (xy 5.006486 -248.414959) (xy 5.120569 -248.405383) (xy 5.235044 -248.403902)
			(xy 5.349337 -248.410524) (xy 5.462875 -248.425217) (xy 5.575088 -248.447906) (xy 5.685416 -248.478477)
			(xy 5.793303 -248.516778) (xy 5.898211 -248.562616) (xy 5.999612 -248.615762) (xy 6.096999 -248.67595)
			(xy 6.189883 -248.742876) (xy 6.277799 -248.816208) (xy 6.360307 -248.895575) (xy 6.436992 -248.980582)
			(xy 6.50747 -249.070801) (xy 6.571389 -249.16578) (xy 6.628427 -249.265044) (xy 6.678299 -249.368095)
			(xy 6.720755 -249.474417) (xy 6.755581 -249.583475) (xy 6.782604 -249.694725) (xy 6.801689 -249.807607)
			(xy 6.812738 -249.921558) (xy 6.815698 -250.036004) (xy 6.810552 -250.150373) (xy 6.797328 -250.264091)
			(xy 6.77609 -250.376588) (xy 6.746947 -250.487301) (xy 6.710043 -250.595675) (xy 6.665563 -250.701165)
			(xy 6.613732 -250.803245) (xy 6.554808 -250.901401) (xy 6.489086 -250.995142) (xy 6.453378 -251.039884)
			(xy 6.059424 -251.039884) (xy 6.020367 -251.072253) (xy 5.938107 -251.131626) (xy 5.895086 -251.158502)
			(xy 5.881509 -251.167452) (xy 5.858992 -251.190897) (xy 5.843109 -251.219259) (xy 5.834884 -251.250707)
			(xy 5.83438 -251.26696) (xy 5.83438 -251.50699) (xy 5.779686 -251.529797) (xy 5.667599 -251.568292)
			(xy 5.552993 -251.598476) (xy 5.436486 -251.620186) (xy 5.318701 -251.633307) (xy 5.200272 -251.637768)
			(xy 5.081834 -251.633545) (xy 4.964023 -251.62066) (xy 4.847473 -251.599183) (xy 4.732807 -251.569229)
			(xy 4.620643 -251.530959) (xy 4.565904 -251.50826) (xy 4.565904 -251.26823) (xy 4.56544 -251.25195)
			(xy 4.557181 -251.220454) (xy 4.541219 -251.192074) (xy 4.518594 -251.168658) (xy 4.504944 -251.159772)
			(xy 4.45885 -251.131059) (xy 4.370982 -251.067228) (xy 4.32943 -251.032264) (xy 3.937762 -251.032264)
			(xy 3.903919 -250.989342) (xy 3.841441 -250.89964) (xy 3.785164 -250.805923) (xy 3.735346 -250.708619)
			(xy 3.692214 -250.608172) (xy 3.655964 -250.505042) (xy 3.626762 -250.399698) (xy 3.604742 -250.292623)
			(xy 3.590005 -250.184306) (xy 3.582617 -250.07524) (xy 3.582162 -250.020582) (xy 1.016 -250.020582)
			(xy 1.016 -253.671578) (xy 1.047496 -253.754382) (xy 1.059942 -253.769876) (xy 1.077482 -253.79257)
			(xy 1.106268 -253.842179) (xy 1.127305 -253.895537) (xy 1.14012 -253.951442) (xy 1.144423 -254.008636)
			(xy 1.14012 -254.06583) (xy 1.127305 -254.121735) (xy 1.106268 -254.175093) (xy 1.077482 -254.224702)
			(xy 1.059942 -254.247396) (xy 1.047496 -254.26289) (xy 1.016 -254.345694) (xy 1.016 -266.371578)
			(xy 1.047496 -266.454382) (xy 1.059942 -266.469876) (xy 1.077482 -266.49257) (xy 1.106268 -266.542179)
			(xy 1.127305 -266.595537) (xy 1.14012 -266.651442) (xy 1.144423 -266.708636) (xy 1.14012 -266.76583)
			(xy 1.127305 -266.821735) (xy 1.106268 -266.875093) (xy 1.077482 -266.924702) (xy 1.059942 -266.947396)
			(xy 1.047496 -266.96289) (xy 1.016 -267.045694) (xy 1.016 -267.869924) (xy 3.584453 -267.869924)
			(xy 3.588477 -267.755973) (xy 3.600528 -267.642589) (xy 3.620548 -267.530339) (xy 3.648436 -267.419779)
			(xy 3.684054 -267.311463) (xy 3.727223 -267.205929) (xy 3.777729 -267.103702) (xy 3.83532 -267.005294)
			(xy 3.899709 -266.911192) (xy 3.970576 -266.821867) (xy 4.047567 -266.737763) (xy 4.130299 -266.6593)
			(xy 4.218359 -266.586868) (xy 4.31131 -266.520828) (xy 4.408687 -266.461509) (xy 4.510006 -266.409207)
			(xy 4.614762 -266.364182) (xy 4.722433 -266.326658) (xy 4.832482 -266.296824) (xy 4.944363 -266.274826)
			(xy 5.057516 -266.260775) (xy 5.171378 -266.25474) (xy 5.285382 -266.256752) (xy 5.398961 -266.266801)
			(xy 5.511548 -266.284837) (xy 5.622582 -266.31077) (xy 5.73151 -266.34447) (xy 5.83779 -266.38577)
			(xy 5.940891 -266.434464) (xy 6.040301 -266.490309) (xy 6.135524 -266.553028) (xy 6.226086 -266.622307)
			(xy 6.311536 -266.697801) (xy 6.391447 -266.779136) (xy 6.465422 -266.865904) (xy 6.533092 -266.957675)
			(xy 6.59412 -267.05399) (xy 6.648202 -267.15437) (xy 6.695069 -267.258315) (xy 6.734487 -267.365307)
			(xy 6.766259 -267.474813) (xy 6.790228 -267.586287) (xy 6.806274 -267.699175) (xy 6.814317 -267.812913)
			(xy 6.81482 -267.869924) (xy 6.814317 -267.926935) (xy 6.806274 -268.040673) (xy 6.790228 -268.153561)
			(xy 6.766259 -268.265035) (xy 6.734487 -268.374541) (xy 6.695069 -268.481533) (xy 6.648202 -268.585478)
			(xy 6.59412 -268.685858) (xy 6.533092 -268.782173) (xy 6.465422 -268.873944) (xy 6.391447 -268.960712)
			(xy 6.311536 -269.042047) (xy 6.226086 -269.117541) (xy 6.135524 -269.18682) (xy 6.040301 -269.249539)
			(xy 5.940891 -269.305384) (xy 5.83779 -269.354078) (xy 5.73151 -269.395378) (xy 5.622582 -269.429078)
			(xy 5.511548 -269.455011) (xy 5.398961 -269.473047) (xy 5.285382 -269.483096) (xy 5.171378 -269.485108)
			(xy 5.057516 -269.479073) (xy 4.944363 -269.465022) (xy 4.832482 -269.443024) (xy 4.722433 -269.41319)
			(xy 4.614762 -269.375666) (xy 4.510006 -269.330641) (xy 4.408687 -269.278339) (xy 4.31131 -269.21902)
			(xy 4.218359 -269.15298) (xy 4.130299 -269.080548) (xy 4.047567 -269.002085) (xy 3.970576 -268.917981)
			(xy 3.899709 -268.828656) (xy 3.83532 -268.734554) (xy 3.777729 -268.636146) (xy 3.727223 -268.533919)
			(xy 3.684054 -268.428385) (xy 3.648436 -268.320069) (xy 3.620548 -268.209509) (xy 3.600528 -268.097259)
			(xy 3.588477 -267.983875) (xy 3.584453 -267.869924) (xy 1.016 -267.869924) (xy 1.016 -273.61007)
			(xy 39.818063 -273.61007) (xy 39.82207 -273.494046) (xy 39.834072 -273.378574) (xy 39.854012 -273.264206)
			(xy 39.881795 -273.151486) (xy 39.917289 -273.040952) (xy 39.960324 -272.933129) (xy 40.010695 -272.828532)
			(xy 40.068162 -272.72766) (xy 40.132452 -272.630993) (xy 40.203257 -272.538992) (xy 40.280241 -272.452095)
			(xy 40.363037 -272.370716) (xy 40.45125 -272.295243) (xy 40.54446 -272.226036) (xy 40.642223 -272.163424)
			(xy 40.744072 -272.107707) (xy 40.849522 -272.059149) (xy 40.958071 -272.017981) (xy 41.069202 -271.984401)
			(xy 41.182385 -271.958568) (xy 41.29708 -271.940605) (xy 41.412742 -271.930597) (xy 41.528818 -271.928594)
			(xy 41.644756 -271.934603) (xy 41.760003 -271.948596) (xy 41.874009 -271.970507) (xy 41.986233 -272.000232)
			(xy 42.096139 -272.037628) (xy 42.203202 -272.082517) (xy 42.306914 -272.134686) (xy 42.406779 -272.193886)
			(xy 42.502322 -272.259835) (xy 42.593088 -272.332218) (xy 42.678643 -272.410691) (xy 42.758581 -272.494879)
			(xy 42.83252 -272.584381) (xy 42.900108 -272.678772) (xy 42.961022 -272.7776) (xy 43.014974 -272.880396)
			(xy 43.061704 -272.986669) (xy 43.100992 -273.095913) (xy 43.132649 -273.207606) (xy 43.156525 -273.321218)
			(xy 43.172506 -273.436206) (xy 43.180515 -273.552023) (xy 43.181016 -273.61007) (xy 43.180515 -273.668117)
			(xy 43.172506 -273.783934) (xy 43.156525 -273.898922) (xy 43.132649 -274.012534) (xy 43.100992 -274.124227)
			(xy 43.061704 -274.233471) (xy 43.014974 -274.339744) (xy 42.961022 -274.44254) (xy 42.900108 -274.541368)
			(xy 42.83252 -274.635759) (xy 42.758581 -274.725261) (xy 42.678643 -274.809449) (xy 42.593088 -274.887922)
			(xy 42.502604 -274.96008) (xy 93.154506 -274.96008) (xy 93.158522 -274.84381) (xy 93.170549 -274.728095)
			(xy 93.190531 -274.613485) (xy 93.218373 -274.500526) (xy 93.253942 -274.389758) (xy 93.297068 -274.281707)
			(xy 93.347545 -274.176889) (xy 93.405134 -274.075804) (xy 93.46956 -273.978932) (xy 93.540515 -273.886736)
			(xy 93.617662 -273.799655) (xy 93.700633 -273.718104) (xy 93.789033 -273.642472) (xy 93.88244 -273.573118)
			(xy 93.980409 -273.510375) (xy 94.082473 -273.454539) (xy 94.188147 -273.405878) (xy 94.296926 -273.364624)
			(xy 94.408291 -273.330973) (xy 94.521714 -273.305085) (xy 94.636651 -273.287084) (xy 94.752557 -273.277055)
			(xy 94.868879 -273.275047) (xy 94.985062 -273.281069) (xy 95.100553 -273.295092) (xy 95.214801 -273.31705)
			(xy 95.327262 -273.346837) (xy 95.4374 -273.384312) (xy 95.54469 -273.429297) (xy 95.648621 -273.481576)
			(xy 95.748697 -273.540901) (xy 95.844443 -273.606989) (xy 95.9354 -273.679525) (xy 96.021136 -273.758164)
			(xy 96.101243 -273.84253) (xy 96.175339 -273.932222) (xy 96.243069 -274.026812) (xy 96.304113 -274.12585)
			(xy 96.358178 -274.228863) (xy 96.405008 -274.33536) (xy 96.444379 -274.444835) (xy 96.476103 -274.556765)
			(xy 96.500029 -274.670617) (xy 96.516043 -274.785849) (xy 96.52407 -274.901911) (xy 96.524572 -274.96008)
			(xy 96.52407 -275.018249) (xy 96.516043 -275.134311) (xy 96.500029 -275.249543) (xy 96.476103 -275.363395)
			(xy 96.444379 -275.475325) (xy 96.405008 -275.5848) (xy 96.358178 -275.691297) (xy 96.304113 -275.79431)
			(xy 96.243069 -275.893348) (xy 96.175339 -275.987938) (xy 96.101243 -276.07763) (xy 96.021136 -276.161996)
			(xy 95.9354 -276.240635) (xy 95.844443 -276.313171) (xy 95.748697 -276.379259) (xy 95.648621 -276.438584)
			(xy 95.54469 -276.490863) (xy 95.4374 -276.535848) (xy 95.327262 -276.573323) (xy 95.214801 -276.60311)
			(xy 95.100553 -276.625068) (xy 94.985062 -276.639091) (xy 94.868879 -276.645113) (xy 94.752557 -276.643105)
			(xy 94.636651 -276.633076) (xy 94.521714 -276.615075) (xy 94.408291 -276.589187) (xy 94.296926 -276.555536)
			(xy 94.188147 -276.514282) (xy 94.082473 -276.465621) (xy 93.980409 -276.409785) (xy 93.88244 -276.347042)
			(xy 93.789033 -276.277688) (xy 93.700633 -276.202056) (xy 93.617662 -276.120505) (xy 93.540515 -276.033424)
			(xy 93.46956 -275.941228) (xy 93.405134 -275.844356) (xy 93.347545 -275.743271) (xy 93.297068 -275.638453)
			(xy 93.253942 -275.530402) (xy 93.218373 -275.419634) (xy 93.190531 -275.306675) (xy 93.170549 -275.192065)
			(xy 93.158522 -275.07635) (xy 93.154506 -274.96008) (xy 42.502604 -274.96008) (xy 42.502322 -274.960305)
			(xy 42.406779 -275.026254) (xy 42.306914 -275.085454) (xy 42.203202 -275.137623) (xy 42.096139 -275.182512)
			(xy 41.986233 -275.219908) (xy 41.874009 -275.249633) (xy 41.760003 -275.271544) (xy 41.644756 -275.285537)
			(xy 41.528818 -275.291546) (xy 41.412742 -275.289543) (xy 41.29708 -275.279535) (xy 41.182385 -275.261572)
			(xy 41.069202 -275.235739) (xy 40.958071 -275.202159) (xy 40.849522 -275.160991) (xy 40.744072 -275.112433)
			(xy 40.642223 -275.056716) (xy 40.54446 -274.994104) (xy 40.45125 -274.924897) (xy 40.363037 -274.849424)
			(xy 40.280241 -274.768045) (xy 40.203257 -274.681148) (xy 40.132452 -274.589147) (xy 40.068162 -274.49248)
			(xy 40.010695 -274.391608) (xy 39.960324 -274.287011) (xy 39.917289 -274.179188) (xy 39.881795 -274.068654)
			(xy 39.854012 -273.955934) (xy 39.834072 -273.841566) (xy 39.82207 -273.726094) (xy 39.818063 -273.61007)
			(xy 1.016 -273.61007) (xy 1.016 -279.071578) (xy 1.047496 -279.154382) (xy 1.059942 -279.169876)
			(xy 1.077482 -279.19257) (xy 1.106268 -279.242179) (xy 1.127305 -279.295537) (xy 1.14012 -279.351442)
			(xy 1.144423 -279.408636) (xy 1.14012 -279.46583) (xy 1.127305 -279.521735) (xy 1.106268 -279.575093)
			(xy 1.077482 -279.624702) (xy 1.059942 -279.647396) (xy 1.047496 -279.66289) (xy 1.016 -279.745694)
			(xy 1.016 -286.709866) (xy 86.877404 -286.709866) (xy 86.881424 -286.519215) (xy 86.893478 -286.328902)
			(xy 86.913544 -286.139267) (xy 86.941587 -285.950646) (xy 86.977556 -285.763376) (xy 87.021388 -285.577788)
			(xy 87.073005 -285.394213) (xy 87.132315 -285.212977) (xy 87.199213 -285.034402) (xy 87.273579 -284.858807)
			(xy 87.355281 -284.686502) (xy 87.444175 -284.517795) (xy 87.540101 -284.352985) (xy 87.64289 -284.192366)
			(xy 87.752359 -284.036223) (xy 87.868313 -283.884834) (xy 87.990547 -283.738467) (xy 88.118841 -283.597383)
			(xy 88.252969 -283.461834) (xy 88.392693 -283.332059) (xy 88.537763 -283.208289) (xy 88.687921 -283.090746)
			(xy 88.842902 -282.979637) (xy 89.002429 -282.87516) (xy 89.166218 -282.777501) (xy 89.333978 -282.686834)
			(xy 89.505412 -282.60332) (xy 89.680214 -282.527107) (xy 89.858073 -282.458331) (xy 90.038674 -282.397113)
			(xy 90.221694 -282.343564) (xy 90.40681 -282.297778) (xy 90.593691 -282.259836) (xy 90.782006 -282.229807)
			(xy 90.971419 -282.207742) (xy 91.161593 -282.193683) (xy 91.352192 -282.187653) (xy 91.542875 -282.189663)
			(xy 91.733304 -282.19971) (xy 91.92314 -282.217776) (xy 92.112046 -282.243829) (xy 92.299685 -282.277822)
			(xy 92.485725 -282.319695) (xy 92.669834 -282.369374) (xy 92.851685 -282.42677) (xy 93.030955 -282.491781)
			(xy 93.207325 -282.564292) (xy 93.380481 -282.644173) (xy 93.550116 -282.731283) (xy 93.715928 -282.825467)
			(xy 93.877622 -282.926558) (xy 94.03491 -283.034374) (xy 94.187513 -283.148726) (xy 94.335161 -283.269409)
			(xy 94.477589 -283.39621) (xy 94.614545 -283.528901) (xy 94.745786 -283.667249) (xy 94.871078 -283.811006)
			(xy 94.990198 -283.959917) (xy 95.102934 -284.113718) (xy 95.209087 -284.272134) (xy 95.308467 -284.434885)
			(xy 95.400897 -284.60168) (xy 95.486214 -284.772224) (xy 95.564266 -284.946212) (xy 95.634913 -285.123337)
			(xy 95.698031 -285.303282) (xy 95.753507 -285.485728) (xy 95.801242 -285.670351) (xy 95.841152 -285.856821)
			(xy 95.873165 -286.044809) (xy 95.897225 -286.233979) (xy 95.913288 -286.423995) (xy 95.921327 -286.614519)
			(xy 95.92183 -286.709866) (xy 95.921327 -286.805213) (xy 95.913288 -286.995737) (xy 95.897225 -287.185753)
			(xy 95.873165 -287.374923) (xy 95.841152 -287.562911) (xy 95.801242 -287.749381) (xy 95.753507 -287.934004)
			(xy 95.698031 -288.11645) (xy 95.634913 -288.296395) (xy 95.564266 -288.47352) (xy 95.486214 -288.647508)
			(xy 95.400897 -288.818052) (xy 95.308467 -288.984847) (xy 95.209087 -289.147598) (xy 95.102934 -289.306014)
			(xy 94.990198 -289.459815) (xy 94.871078 -289.608726) (xy 94.745786 -289.752483) (xy 94.614545 -289.890831)
			(xy 94.477589 -290.023522) (xy 94.335161 -290.150323) (xy 94.187513 -290.271006) (xy 94.03491 -290.385358)
			(xy 93.877622 -290.493174) (xy 93.715928 -290.594265) (xy 93.550116 -290.688449) (xy 93.380481 -290.775559)
			(xy 93.207325 -290.85544) (xy 93.030955 -290.927951) (xy 92.851685 -290.992962) (xy 92.669834 -291.050358)
			(xy 92.485725 -291.100037) (xy 92.299685 -291.14191) (xy 92.112046 -291.175903) (xy 91.92314 -291.201956)
			(xy 91.733304 -291.220022) (xy 91.542875 -291.230069) (xy 91.352192 -291.232079) (xy 91.161593 -291.226049)
			(xy 90.971419 -291.21199) (xy 90.782006 -291.189925) (xy 90.593691 -291.159896) (xy 90.40681 -291.121954)
			(xy 90.221694 -291.076168) (xy 90.038674 -291.022619) (xy 89.858073 -290.961401) (xy 89.680214 -290.892625)
			(xy 89.505412 -290.816412) (xy 89.333978 -290.732898) (xy 89.166218 -290.642231) (xy 89.002429 -290.544572)
			(xy 88.842902 -290.440095) (xy 88.687921 -290.328986) (xy 88.537763 -290.211443) (xy 88.392693 -290.087673)
			(xy 88.252969 -289.957898) (xy 88.118841 -289.822349) (xy 87.990547 -289.681265) (xy 87.868313 -289.534898)
			(xy 87.752359 -289.383509) (xy 87.64289 -289.227366) (xy 87.540101 -289.066747) (xy 87.444175 -288.901937)
			(xy 87.355281 -288.73323) (xy 87.273579 -288.560925) (xy 87.199213 -288.38533) (xy 87.132315 -288.206755)
			(xy 87.073005 -288.025519) (xy 87.021388 -287.841944) (xy 86.977556 -287.656356) (xy 86.941587 -287.469086)
			(xy 86.913544 -287.280465) (xy 86.893478 -287.09083) (xy 86.881424 -286.900517) (xy 86.877404 -286.709866)
			(xy 1.016 -286.709866) (xy 1.016 -291.771578) (xy 1.047496 -291.854382) (xy 1.059942 -291.869876)
			(xy 1.077482 -291.89257) (xy 1.106268 -291.942179) (xy 1.127305 -291.995537) (xy 1.14012 -292.051442)
			(xy 1.144423 -292.108636) (xy 1.14012 -292.16583) (xy 1.127305 -292.221735) (xy 1.106268 -292.275093)
			(xy 1.077482 -292.324702) (xy 1.059942 -292.347396) (xy 1.047496 -292.36289) (xy 1.016 -292.445694)
			(xy 1.016 -295.89984) (xy 11.34441 -295.89984) (xy 11.348411 -295.694791) (xy 11.36041 -295.490054)
			(xy 11.380388 -295.285941) (xy 11.408314 -295.082762) (xy 11.444146 -294.880829) (xy 11.48783 -294.680446)
			(xy 11.539298 -294.481921) (xy 11.598473 -294.285555) (xy 11.665264 -294.091648) (xy 11.73957 -293.900494)
			(xy 11.821277 -293.712384) (xy 11.910262 -293.527606) (xy 12.006388 -293.34644) (xy 12.109509 -293.169163)
			(xy 12.219469 -292.996044) (xy 12.336099 -292.827347) (xy 12.459222 -292.663329) (xy 12.588651 -292.50424)
			(xy 12.724188 -292.350322) (xy 12.865627 -292.201808) (xy 13.012754 -292.058927) (xy 13.165342 -291.921894)
			(xy 13.323161 -291.79092) (xy 13.48597 -291.666202) (xy 13.653521 -291.547932) (xy 13.825559 -291.436288)
			(xy 14.001822 -291.331442) (xy 14.182041 -291.233553) (xy 14.365942 -291.14277) (xy 14.553246 -291.059232)
			(xy 14.743666 -290.983064) (xy 14.936912 -290.914384) (xy 15.132692 -290.853296) (xy 15.330705 -290.799894)
			(xy 15.530652 -290.754257) (xy 15.732226 -290.716457) (xy 15.935122 -290.686549) (xy 16.139031 -290.664581)
			(xy 16.343641 -290.650586) (xy 16.548641 -290.644584) (xy 16.75372 -290.646585) (xy 16.958564 -290.656585)
			(xy 17.162863 -290.674571) (xy 17.366304 -290.700513) (xy 17.568577 -290.734374) (xy 17.769376 -290.7761)
			(xy 17.968394 -290.825629) (xy 18.165328 -290.882885) (xy 18.359878 -290.947782) (xy 18.551748 -291.020219)
			(xy 18.740645 -291.100087) (xy 18.926283 -291.187265) (xy 19.108378 -291.281619) (xy 19.286653 -291.383006)
			(xy 19.460836 -291.491271) (xy 19.630663 -291.606249) (xy 19.795875 -291.727767) (xy 19.956219 -291.855637)
			(xy 20.111453 -291.989666) (xy 20.261339 -292.12965) (xy 20.405649 -292.275375) (xy 20.544163 -292.42662)
			(xy 20.676672 -292.583153) (xy 20.802972 -292.744738) (xy 20.922871 -292.911127) (xy 21.036188 -293.082067)
			(xy 21.142748 -293.257299) (xy 21.242391 -293.436554) (xy 21.334964 -293.619561) (xy 21.420326 -293.80604)
			(xy 21.498347 -293.995708) (xy 21.56891 -294.188276) (xy 21.631905 -294.38345) (xy 21.687237 -294.580933)
			(xy 21.734822 -294.780424) (xy 21.774587 -294.981621) (xy 21.806472 -295.184215) (xy 21.830429 -295.3879)
			(xy 21.84642 -295.592364) (xy 21.854422 -295.797296) (xy 21.854922 -295.89984) (xy 21.854422 -296.002384)
			(xy 21.84642 -296.207316) (xy 21.830429 -296.41178) (xy 21.806472 -296.615465) (xy 21.774587 -296.818059)
			(xy 21.734822 -297.019256) (xy 21.687237 -297.218747) (xy 21.631905 -297.41623) (xy 21.56891 -297.611404)
			(xy 21.498347 -297.803972) (xy 21.420326 -297.99364) (xy 21.334964 -298.180119) (xy 21.242391 -298.363126)
			(xy 21.142748 -298.542381) (xy 21.036188 -298.717613) (xy 20.922871 -298.888553) (xy 20.802972 -299.054942)
			(xy 20.676672 -299.216527) (xy 20.544163 -299.37306) (xy 20.405649 -299.524305) (xy 20.261339 -299.67003)
			(xy 20.111453 -299.810014) (xy 19.956219 -299.944043) (xy 19.795875 -300.071913) (xy 19.630663 -300.193431)
			(xy 19.460836 -300.308409) (xy 19.286653 -300.416674) (xy 19.108378 -300.518061) (xy 18.926283 -300.612415)
			(xy 18.740645 -300.699593) (xy 18.551748 -300.779461) (xy 18.359878 -300.851898) (xy 18.165328 -300.916795)
			(xy 17.968394 -300.974051) (xy 17.769376 -301.02358) (xy 17.568577 -301.065306) (xy 17.366304 -301.099167)
			(xy 17.162863 -301.125109) (xy 16.958564 -301.143095) (xy 16.75372 -301.153095) (xy 16.548641 -301.155096)
			(xy 16.343641 -301.149094) (xy 16.139031 -301.135099) (xy 15.935122 -301.113131) (xy 15.732226 -301.083223)
			(xy 15.530652 -301.045423) (xy 15.330705 -300.999786) (xy 15.132692 -300.946384) (xy 14.936912 -300.885296)
			(xy 14.743666 -300.816616) (xy 14.553246 -300.740448) (xy 14.365942 -300.65691) (xy 14.182041 -300.566127)
			(xy 14.001822 -300.468238) (xy 13.825559 -300.363392) (xy 13.653521 -300.251748) (xy 13.48597 -300.133478)
			(xy 13.323161 -300.00876) (xy 13.165342 -299.877786) (xy 13.012754 -299.740753) (xy 12.865627 -299.597872)
			(xy 12.724188 -299.449358) (xy 12.588651 -299.29544) (xy 12.459222 -299.136351) (xy 12.336099 -298.972333)
			(xy 12.219469 -298.803636) (xy 12.109509 -298.630517) (xy 12.006388 -298.45324) (xy 11.910262 -298.272074)
			(xy 11.821277 -298.087296) (xy 11.73957 -297.899186) (xy 11.665264 -297.708032) (xy 11.598473 -297.514125)
			(xy 11.539298 -297.317759) (xy 11.48783 -297.119234) (xy 11.444146 -296.918851) (xy 11.408314 -296.716918)
			(xy 11.380388 -296.513739) (xy 11.36041 -296.309626) (xy 11.348411 -296.104889) (xy 11.34441 -295.89984)
			(xy 1.016 -295.89984) (xy 1.016 -304.471578) (xy 1.047496 -304.554382) (xy 1.059942 -304.569876)
			(xy 1.077482 -304.59257) (xy 1.106268 -304.642179) (xy 1.127305 -304.695537) (xy 1.14012 -304.751442)
			(xy 1.144423 -304.808636) (xy 1.14012 -304.86583) (xy 1.127305 -304.921735) (xy 1.106268 -304.975093)
			(xy 1.077482 -305.024702) (xy 1.059942 -305.047396) (xy 1.047496 -305.06289) (xy 1.016 -305.145694)
			(xy 1.016 -317.171578) (xy 1.047496 -317.254382) (xy 1.059942 -317.269876) (xy 1.077482 -317.29257)
			(xy 1.106268 -317.342179) (xy 1.127305 -317.395537) (xy 1.14012 -317.451442) (xy 1.144423 -317.508636)
			(xy 1.14012 -317.56583) (xy 1.127305 -317.621735) (xy 1.106268 -317.675093) (xy 1.077482 -317.724702)
			(xy 1.059942 -317.747396) (xy 1.047496 -317.76289) (xy 1.016 -317.845694) (xy 1.016 -318.06007) (xy 39.818063 -318.06007)
			(xy 39.82207 -317.944046) (xy 39.834072 -317.828574) (xy 39.854012 -317.714206) (xy 39.881795 -317.601486)
			(xy 39.917289 -317.490952) (xy 39.960324 -317.383129) (xy 40.010695 -317.278532) (xy 40.068162 -317.17766)
			(xy 40.132452 -317.080993) (xy 40.203257 -316.988992) (xy 40.280241 -316.902095) (xy 40.363037 -316.820716)
			(xy 40.45125 -316.745243) (xy 40.54446 -316.676036) (xy 40.642223 -316.613424) (xy 40.744072 -316.557707)
			(xy 40.849522 -316.509149) (xy 40.958071 -316.467981) (xy 41.069202 -316.434401) (xy 41.182385 -316.408568)
			(xy 41.29708 -316.390605) (xy 41.412742 -316.380597) (xy 41.528818 -316.378594) (xy 41.644756 -316.384603)
			(xy 41.760003 -316.398596) (xy 41.874009 -316.420507) (xy 41.986233 -316.450232) (xy 42.096139 -316.487628)
			(xy 42.203202 -316.532517) (xy 42.306914 -316.584686) (xy 42.406779 -316.643886) (xy 42.502322 -316.709835)
			(xy 42.593088 -316.782218) (xy 42.678643 -316.860691) (xy 42.758581 -316.944879) (xy 42.83252 -317.034381)
			(xy 42.900108 -317.128772) (xy 42.961022 -317.2276) (xy 43.014974 -317.330396) (xy 43.061704 -317.436669)
			(xy 43.100992 -317.545913) (xy 43.132649 -317.657606) (xy 43.156525 -317.771218) (xy 43.172506 -317.886206)
			(xy 43.180515 -318.002023) (xy 43.181016 -318.06007) (xy 43.180515 -318.118117) (xy 43.172506 -318.233934)
			(xy 43.156525 -318.348922) (xy 43.132649 -318.462534) (xy 43.100992 -318.574227) (xy 43.061704 -318.683471)
			(xy 43.014974 -318.789744) (xy 42.961022 -318.89254) (xy 42.900108 -318.991368) (xy 42.83252 -319.085759)
			(xy 42.758581 -319.175261) (xy 42.678643 -319.259449) (xy 42.593088 -319.337922) (xy 42.502604 -319.41008)
			(xy 93.154506 -319.41008) (xy 93.158522 -319.29381) (xy 93.170549 -319.178095) (xy 93.190531 -319.063485)
			(xy 93.218373 -318.950526) (xy 93.253942 -318.839758) (xy 93.297068 -318.731707) (xy 93.347545 -318.626889)
			(xy 93.405134 -318.525804) (xy 93.46956 -318.428932) (xy 93.540515 -318.336736) (xy 93.617662 -318.249655)
			(xy 93.700633 -318.168104) (xy 93.789033 -318.092472) (xy 93.88244 -318.023118) (xy 93.980409 -317.960375)
			(xy 94.082473 -317.904539) (xy 94.188147 -317.855878) (xy 94.296926 -317.814624) (xy 94.408291 -317.780973)
			(xy 94.521714 -317.755085) (xy 94.636651 -317.737084) (xy 94.752557 -317.727055) (xy 94.868879 -317.725047)
			(xy 94.985062 -317.731069) (xy 95.100553 -317.745092) (xy 95.214801 -317.76705) (xy 95.327262 -317.796837)
			(xy 95.4374 -317.834312) (xy 95.54469 -317.879297) (xy 95.648621 -317.931576) (xy 95.748697 -317.990901)
			(xy 95.844443 -318.056989) (xy 95.9354 -318.129525) (xy 96.021136 -318.208164) (xy 96.101243 -318.29253)
			(xy 96.175339 -318.382222) (xy 96.243069 -318.476812) (xy 96.304113 -318.57585) (xy 96.358178 -318.678863)
			(xy 96.405008 -318.78536) (xy 96.444379 -318.894835) (xy 96.476103 -319.006765) (xy 96.500029 -319.120617)
			(xy 96.516043 -319.235849) (xy 96.52407 -319.351911) (xy 96.524572 -319.41008) (xy 96.52407 -319.468249)
			(xy 96.516043 -319.584311) (xy 96.500029 -319.699543) (xy 96.476103 -319.813395) (xy 96.444379 -319.925325)
			(xy 96.405008 -320.0348) (xy 96.358178 -320.141297) (xy 96.304113 -320.24431) (xy 96.243069 -320.343348)
			(xy 96.175339 -320.437938) (xy 96.101243 -320.52763) (xy 96.021136 -320.611996) (xy 95.9354 -320.690635)
			(xy 95.844443 -320.763171) (xy 95.748697 -320.829259) (xy 95.648621 -320.888584) (xy 95.54469 -320.940863)
			(xy 95.4374 -320.985848) (xy 95.327262 -321.023323) (xy 95.214801 -321.05311) (xy 95.100553 -321.075068)
			(xy 94.985062 -321.089091) (xy 94.868879 -321.095113) (xy 94.752557 -321.093105) (xy 94.636651 -321.083076)
			(xy 94.521714 -321.065075) (xy 94.408291 -321.039187) (xy 94.296926 -321.005536) (xy 94.188147 -320.964282)
			(xy 94.082473 -320.915621) (xy 93.980409 -320.859785) (xy 93.88244 -320.797042) (xy 93.789033 -320.727688)
			(xy 93.700633 -320.652056) (xy 93.617662 -320.570505) (xy 93.540515 -320.483424) (xy 93.46956 -320.391228)
			(xy 93.405134 -320.294356) (xy 93.347545 -320.193271) (xy 93.297068 -320.088453) (xy 93.253942 -319.980402)
			(xy 93.218373 -319.869634) (xy 93.190531 -319.756675) (xy 93.170549 -319.642065) (xy 93.158522 -319.52635)
			(xy 93.154506 -319.41008) (xy 42.502604 -319.41008) (xy 42.502322 -319.410305) (xy 42.406779 -319.476254)
			(xy 42.306914 -319.535454) (xy 42.203202 -319.587623) (xy 42.096139 -319.632512) (xy 41.986233 -319.669908)
			(xy 41.874009 -319.699633) (xy 41.760003 -319.721544) (xy 41.644756 -319.735537) (xy 41.528818 -319.741546)
			(xy 41.412742 -319.739543) (xy 41.29708 -319.729535) (xy 41.182385 -319.711572) (xy 41.069202 -319.685739)
			(xy 40.958071 -319.652159) (xy 40.849522 -319.610991) (xy 40.744072 -319.562433) (xy 40.642223 -319.506716)
			(xy 40.54446 -319.444104) (xy 40.45125 -319.374897) (xy 40.363037 -319.299424) (xy 40.280241 -319.218045)
			(xy 40.203257 -319.131148) (xy 40.132452 -319.039147) (xy 40.068162 -318.94248) (xy 40.010695 -318.841608)
			(xy 39.960324 -318.737011) (xy 39.917289 -318.629188) (xy 39.881795 -318.518654) (xy 39.854012 -318.405934)
			(xy 39.834072 -318.291566) (xy 39.82207 -318.176094) (xy 39.818063 -318.06007) (xy 1.016 -318.06007)
			(xy 1.016 -329.871578) (xy 1.047496 -329.954382) (xy 1.059942 -329.969876) (xy 1.077482 -329.99257)
			(xy 1.106268 -330.042179) (xy 1.127305 -330.095537) (xy 1.14012 -330.151442) (xy 1.144423 -330.208636)
			(xy 1.14012 -330.26583) (xy 1.127305 -330.321735) (xy 1.106268 -330.375093) (xy 1.077482 -330.424702)
			(xy 1.059942 -330.447396) (xy 1.047496 -330.46289) (xy 1.016 -330.545694) (xy 1.016 -331.16012) (xy 86.877404 -331.16012)
			(xy 86.881424 -330.969469) (xy 86.893478 -330.779156) (xy 86.913544 -330.589521) (xy 86.941587 -330.4009)
			(xy 86.977556 -330.21363) (xy 87.021388 -330.028042) (xy 87.073005 -329.844467) (xy 87.132315 -329.663231)
			(xy 87.199213 -329.484656) (xy 87.273579 -329.309061) (xy 87.355281 -329.136756) (xy 87.444175 -328.968049)
			(xy 87.540101 -328.803239) (xy 87.64289 -328.64262) (xy 87.752359 -328.486477) (xy 87.868313 -328.335088)
			(xy 87.990547 -328.188721) (xy 88.118841 -328.047637) (xy 88.252969 -327.912088) (xy 88.392693 -327.782313)
			(xy 88.537763 -327.658543) (xy 88.687921 -327.541) (xy 88.842902 -327.429891) (xy 89.002429 -327.325414)
			(xy 89.166218 -327.227755) (xy 89.333978 -327.137088) (xy 89.505412 -327.053574) (xy 89.680214 -326.977361)
			(xy 89.858073 -326.908585) (xy 90.038674 -326.847367) (xy 90.221694 -326.793818) (xy 90.40681 -326.748032)
			(xy 90.593691 -326.71009) (xy 90.782006 -326.680061) (xy 90.971419 -326.657996) (xy 91.161593 -326.643937)
			(xy 91.352192 -326.637907) (xy 91.542875 -326.639917) (xy 91.733304 -326.649964) (xy 91.92314 -326.66803)
			(xy 92.112046 -326.694083) (xy 92.299685 -326.728076) (xy 92.485725 -326.769949) (xy 92.669834 -326.819628)
			(xy 92.851685 -326.877024) (xy 93.030955 -326.942035) (xy 93.207325 -327.014546) (xy 93.380481 -327.094427)
			(xy 93.550116 -327.181537) (xy 93.715928 -327.275721) (xy 93.877622 -327.376812) (xy 94.03491 -327.484628)
			(xy 94.187513 -327.59898) (xy 94.335161 -327.719663) (xy 94.477589 -327.846464) (xy 94.614545 -327.979155)
			(xy 94.745786 -328.117503) (xy 94.871078 -328.26126) (xy 94.990198 -328.410171) (xy 95.102934 -328.563972)
			(xy 95.209087 -328.722388) (xy 95.308467 -328.885139) (xy 95.400897 -329.051934) (xy 95.486214 -329.222478)
			(xy 95.564266 -329.396466) (xy 95.634913 -329.573591) (xy 95.698031 -329.753536) (xy 95.753507 -329.935982)
			(xy 95.801242 -330.120605) (xy 95.841152 -330.307075) (xy 95.873165 -330.495063) (xy 95.897225 -330.684233)
			(xy 95.913288 -330.874249) (xy 95.921327 -331.064773) (xy 95.92183 -331.16012) (xy 95.921327 -331.255467)
			(xy 95.913288 -331.445991) (xy 95.897225 -331.636007) (xy 95.873165 -331.825177) (xy 95.841152 -332.013165)
			(xy 95.801242 -332.199635) (xy 95.753507 -332.384258) (xy 95.698031 -332.566704) (xy 95.634913 -332.746649)
			(xy 95.564266 -332.923774) (xy 95.486214 -333.097762) (xy 95.400897 -333.268306) (xy 95.308467 -333.435101)
			(xy 95.209087 -333.597852) (xy 95.102934 -333.756268) (xy 94.990198 -333.910069) (xy 94.871078 -334.05898)
			(xy 94.745786 -334.202737) (xy 94.614545 -334.341085) (xy 94.477589 -334.473776) (xy 94.335161 -334.600577)
			(xy 94.187513 -334.72126) (xy 94.03491 -334.835612) (xy 93.877622 -334.943428) (xy 93.715928 -335.044519)
			(xy 93.550116 -335.138703) (xy 93.380481 -335.225813) (xy 93.207325 -335.305694) (xy 93.030955 -335.378205)
			(xy 92.851685 -335.443216) (xy 92.669834 -335.500612) (xy 92.485725 -335.550291) (xy 92.299685 -335.592164)
			(xy 92.112046 -335.626157) (xy 91.92314 -335.65221) (xy 91.733304 -335.670276) (xy 91.542875 -335.680323)
			(xy 91.352192 -335.682333) (xy 91.161593 -335.676303) (xy 90.971419 -335.662244) (xy 90.782006 -335.640179)
			(xy 90.593691 -335.61015) (xy 90.40681 -335.572208) (xy 90.221694 -335.526422) (xy 90.038674 -335.472873)
			(xy 89.858073 -335.411655) (xy 89.680214 -335.342879) (xy 89.505412 -335.266666) (xy 89.333978 -335.183152)
			(xy 89.166218 -335.092485) (xy 89.002429 -334.994826) (xy 88.842902 -334.890349) (xy 88.687921 -334.77924)
			(xy 88.537763 -334.661697) (xy 88.392693 -334.537927) (xy 88.252969 -334.408152) (xy 88.118841 -334.272603)
			(xy 87.990547 -334.131519) (xy 87.868313 -333.985152) (xy 87.752359 -333.833763) (xy 87.64289 -333.67762)
			(xy 87.540101 -333.517001) (xy 87.444175 -333.352191) (xy 87.355281 -333.183484) (xy 87.273579 -333.011179)
			(xy 87.199213 -332.835584) (xy 87.132315 -332.657009) (xy 87.073005 -332.475773) (xy 87.021388 -332.292198)
			(xy 86.977556 -332.10661) (xy 86.941587 -331.91934) (xy 86.913544 -331.730719) (xy 86.893478 -331.541084)
			(xy 86.881424 -331.350771) (xy 86.877404 -331.16012) (xy 1.016 -331.16012) (xy 1.016 -341.019892)
			(xy 3.583178 -341.019892) (xy 3.583678 -340.962646) (xy 3.59178 -340.848441) (xy 3.607943 -340.735095)
			(xy 3.632086 -340.623177) (xy 3.664086 -340.513247) (xy 3.703785 -340.405858) (xy 3.750982 -340.301546)
			(xy 3.805442 -340.200836) (xy 3.866891 -340.104231) (xy 3.935021 -340.012216) (xy 4.009491 -339.925252)
			(xy 4.089928 -339.843775) (xy 4.175928 -339.768194) (xy 4.26706 -339.698887) (xy 4.362867 -339.636202)
			(xy 4.46287 -339.580453) (xy 4.566566 -339.531919) (xy 4.673437 -339.490844) (xy 4.782946 -339.457434)
			(xy 4.894545 -339.431855) (xy 5.007674 -339.414237) (xy 5.121765 -339.404668) (xy 5.236248 -339.403195)
			(xy 5.350548 -339.409826) (xy 5.464093 -339.424528) (xy 5.576313 -339.447227) (xy 5.686645 -339.477809)
			(xy 5.794537 -339.516121) (xy 5.899448 -339.561971) (xy 6.000852 -339.615129) (xy 6.09824 -339.675328)
			(xy 6.191125 -339.742268) (xy 6.279041 -339.815611) (xy 6.361547 -339.894992) (xy 6.43823 -339.980011)
			(xy 6.508705 -340.070243) (xy 6.572619 -340.165235) (xy 6.629651 -340.264511) (xy 6.679516 -340.367574)
			(xy 6.721964 -340.473907) (xy 6.756783 -340.582977) (xy 6.783796 -340.694236) (xy 6.80287 -340.807129)
			(xy 6.813908 -340.921088) (xy 6.816855 -341.035542) (xy 6.811697 -341.149918) (xy 6.800075 -341.249762)
			(xy 72.864987 -341.249762) (xy 72.868996 -341.046891) (xy 72.881016 -340.844337) (xy 72.90103 -340.642416)
			(xy 72.929005 -340.441443) (xy 72.964898 -340.241733) (xy 73.008652 -340.043596) (xy 73.060201 -339.847343)
			(xy 73.119462 -339.653279) (xy 73.186344 -339.461708) (xy 73.260742 -339.272929) (xy 73.34254 -339.087236)
			(xy 73.43161 -338.90492) (xy 73.527813 -338.726265) (xy 73.631 -338.551551) (xy 73.741008 -338.381049)
			(xy 73.857666 -338.215026) (xy 73.980792 -338.053742) (xy 74.110194 -337.897448) (xy 74.245669 -337.746388)
			(xy 74.387006 -337.600798) (xy 74.533985 -337.460906) (xy 74.686376 -337.32693) (xy 74.843941 -337.199078)
			(xy 75.006434 -337.077552) (xy 75.173601 -336.962539) (xy 75.345181 -336.854221) (xy 75.520906 -336.752766)
			(xy 75.700503 -336.658332) (xy 75.88369 -336.571067) (xy 76.070182 -336.491108) (xy 76.259687 -336.418579)
			(xy 76.451909 -336.353593) (xy 76.646549 -336.296251) (xy 76.843302 -336.246644) (xy 77.041861 -336.204849)
			(xy 77.241917 -336.170931) (xy 77.443156 -336.144943) (xy 77.645265 -336.126925) (xy 77.847928 -336.116906)
			(xy 78.050828 -336.114902) (xy 78.253649 -336.120914) (xy 78.456075 -336.134935) (xy 78.657788 -336.156943)
			(xy 78.858475 -336.186902) (xy 79.057821 -336.224766) (xy 79.255516 -336.270476) (xy 79.45125 -336.32396)
			(xy 79.644719 -336.385136) (xy 79.83562 -336.453907) (xy 80.023655 -336.530167) (xy 80.208531 -336.613795)
			(xy 80.389958 -336.704662) (xy 80.567654 -336.802625) (xy 80.74134 -336.907533) (xy 80.910747 -337.01922)
			(xy 81.075609 -337.137512) (xy 81.235669 -337.262226) (xy 81.390677 -337.393165) (xy 81.540391 -337.530126)
			(xy 81.684577 -337.672895) (xy 81.823011 -337.821249) (xy 81.955475 -337.974956) (xy 82.081764 -338.133776)
			(xy 82.201679 -338.297461) (xy 82.315035 -338.465756) (xy 82.421653 -338.638398) (xy 82.521367 -338.815118)
			(xy 82.614022 -338.995638) (xy 82.699472 -339.179678) (xy 82.777586 -339.366951) (xy 82.848239 -339.557163)
			(xy 82.911323 -339.750018) (xy 82.966739 -339.945215) (xy 83.0144 -340.142448) (xy 83.054231 -340.341411)
			(xy 83.086171 -340.541792) (xy 83.11017 -340.743278) (xy 83.12619 -340.945555) (xy 83.134207 -341.148307)
			(xy 83.134708 -341.249762) (xy 83.134207 -341.351217) (xy 83.12619 -341.553969) (xy 83.11017 -341.756246)
			(xy 83.086171 -341.957732) (xy 83.054231 -342.158113) (xy 83.0144 -342.357076) (xy 82.966739 -342.554309)
			(xy 82.911323 -342.749506) (xy 82.848239 -342.942361) (xy 82.777586 -343.132573) (xy 82.699472 -343.319846)
			(xy 82.614022 -343.503886) (xy 82.521367 -343.684406) (xy 82.421653 -343.861126) (xy 82.315035 -344.033768)
			(xy 82.201679 -344.202063) (xy 82.081764 -344.365748) (xy 81.955475 -344.524568) (xy 81.823011 -344.678275)
			(xy 81.684577 -344.826629) (xy 81.540391 -344.969398) (xy 81.390677 -345.106359) (xy 81.235669 -345.237298)
			(xy 81.075609 -345.362012) (xy 80.910747 -345.480304) (xy 80.74134 -345.591991) (xy 80.567654 -345.696899)
			(xy 80.389958 -345.794862) (xy 80.208531 -345.885729) (xy 80.023655 -345.969357) (xy 79.83562 -346.045617)
			(xy 79.644719 -346.114388) (xy 79.45125 -346.175564) (xy 79.255516 -346.229048) (xy 79.057821 -346.274758)
			(xy 78.858475 -346.312622) (xy 78.657788 -346.342581) (xy 78.456075 -346.364589) (xy 78.253649 -346.37861)
			(xy 78.050828 -346.384622) (xy 77.847928 -346.382618) (xy 77.645265 -346.372599) (xy 77.443156 -346.354581)
			(xy 77.241917 -346.328593) (xy 77.041861 -346.294675) (xy 76.843302 -346.25288) (xy 76.646549 -346.203273)
			(xy 76.451909 -346.145931) (xy 76.259687 -346.080945) (xy 76.070182 -346.008416) (xy 75.88369 -345.928457)
			(xy 75.700503 -345.841192) (xy 75.520906 -345.746758) (xy 75.345181 -345.645303) (xy 75.173601 -345.536985)
			(xy 75.006434 -345.421972) (xy 74.843941 -345.300446) (xy 74.686376 -345.172594) (xy 74.533985 -345.038618)
			(xy 74.387006 -344.898726) (xy 74.245669 -344.753136) (xy 74.110194 -344.602076) (xy 73.980792 -344.445782)
			(xy 73.857666 -344.284498) (xy 73.741008 -344.118475) (xy 73.631 -343.947973) (xy 73.527813 -343.773259)
			(xy 73.43161 -343.594604) (xy 73.34254 -343.412288) (xy 73.260742 -343.226595) (xy 73.186344 -343.037816)
			(xy 73.119462 -342.846245) (xy 73.060201 -342.652181) (xy 73.008652 -342.455928) (xy 72.964898 -342.257791)
			(xy 72.929005 -342.058081) (xy 72.90103 -341.857108) (xy 72.881016 -341.655187) (xy 72.868996 -341.452633)
			(xy 72.864987 -341.249762) (xy 6.800075 -341.249762) (xy 6.798459 -341.263643) (xy 6.777208 -341.376146)
			(xy 6.748049 -341.486863) (xy 6.71113 -341.595239) (xy 6.666635 -341.700732) (xy 6.614788 -341.802812)
			(xy 6.555848 -341.900968) (xy 6.49011 -341.994707) (xy 6.454394 -342.039448) (xy 6.060186 -342.039448)
			(xy 6.021179 -342.071737) (xy 5.939048 -342.130983) (xy 5.896102 -342.157812) (xy 5.882524 -342.166761)
			(xy 5.860006 -342.190206) (xy 5.844123 -342.218568) (xy 5.8359 -342.250017) (xy 5.835396 -342.26627)
			(xy 5.835396 -342.5063) (xy 5.780703 -342.52911) (xy 5.668615 -342.567604) (xy 5.55401 -342.597788)
			(xy 5.437502 -342.619498) (xy 5.319718 -342.632619) (xy 5.201288 -342.63708) (xy 5.08285 -342.632856)
			(xy 4.96504 -342.619971) (xy 4.848489 -342.598494) (xy 4.733823 -342.56854) (xy 4.621659 -342.53027)
			(xy 4.56692 -342.50757) (xy 4.56692 -342.26754) (xy 4.566441 -342.251261) (xy 4.558186 -342.219766)
			(xy 4.542229 -342.191387) (xy 4.519608 -342.167969) (xy 4.50596 -342.159082) (xy 4.459776 -342.130343)
			(xy 4.371783 -342.066378) (xy 4.330192 -342.03132) (xy 3.938778 -342.03132) (xy 3.904941 -341.988409)
			(xy 3.842477 -341.898728) (xy 3.78621 -341.805035) (xy 3.736399 -341.707756) (xy 3.69327 -341.607335)
			(xy 3.657021 -341.504231) (xy 3.627816 -341.398915) (xy 3.60579 -341.291867) (xy 3.591042 -341.183577)
			(xy 3.583641 -341.074537) (xy 3.583178 -341.019892) (xy 1.016 -341.019892) (xy 1.016 -342.571578)
			(xy 1.047496 -342.654382) (xy 1.059942 -342.669876) (xy 1.077482 -342.69257) (xy 1.106268 -342.742179)
			(xy 1.127305 -342.795537) (xy 1.14012 -342.851442) (xy 1.144423 -342.908636) (xy 1.14012 -342.96583)
			(xy 1.127305 -343.021735) (xy 1.106268 -343.075093) (xy 1.077482 -343.124702) (xy 1.059942 -343.147396)
			(xy 1.047496 -343.16289) (xy 1.016 -343.245694) (xy 1.016 -355.271578) (xy 1.047496 -355.354382)
			(xy 1.059942 -355.369876) (xy 1.077482 -355.39257) (xy 1.106268 -355.442179) (xy 1.127305 -355.495537)
			(xy 1.14012 -355.551442) (xy 1.144423 -355.608636) (xy 1.14012 -355.66583) (xy 1.127305 -355.721735)
			(xy 1.106268 -355.775093) (xy 1.077482 -355.824702) (xy 1.059942 -355.847396) (xy 1.047496 -355.86289)
			(xy 1.016 -355.945694) (xy 1.016 -362.51007) (xy 39.818063 -362.51007) (xy 39.82207 -362.394046)
			(xy 39.834072 -362.278574) (xy 39.854012 -362.164206) (xy 39.881795 -362.051486) (xy 39.917289 -361.940952)
			(xy 39.960324 -361.833129) (xy 40.010695 -361.728532) (xy 40.068162 -361.62766) (xy 40.132452 -361.530993)
			(xy 40.203257 -361.438992) (xy 40.280241 -361.352095) (xy 40.363037 -361.270716) (xy 40.45125 -361.195243)
			(xy 40.54446 -361.126036) (xy 40.642223 -361.063424) (xy 40.744072 -361.007707) (xy 40.849522 -360.959149)
			(xy 40.958071 -360.917981) (xy 41.069202 -360.884401) (xy 41.182385 -360.858568) (xy 41.29708 -360.840605)
			(xy 41.412742 -360.830597) (xy 41.528818 -360.828594) (xy 41.644756 -360.834603) (xy 41.760003 -360.848596)
			(xy 41.874009 -360.870507) (xy 41.986233 -360.900232) (xy 42.096139 -360.937628) (xy 42.203202 -360.982517)
			(xy 42.306914 -361.034686) (xy 42.406779 -361.093886) (xy 42.502322 -361.159835) (xy 42.593088 -361.232218)
			(xy 42.678643 -361.310691) (xy 42.758581 -361.394879) (xy 42.83252 -361.484381) (xy 42.900108 -361.578772)
			(xy 42.961022 -361.6776) (xy 43.014974 -361.780396) (xy 43.061704 -361.886669) (xy 43.100992 -361.995913)
			(xy 43.132649 -362.107606) (xy 43.156525 -362.221218) (xy 43.172506 -362.336206) (xy 43.180515 -362.452023)
			(xy 43.181016 -362.51007) (xy 43.180515 -362.568117) (xy 43.172506 -362.683934) (xy 43.156525 -362.798922)
			(xy 43.132649 -362.912534) (xy 43.100992 -363.024227) (xy 43.061704 -363.133471) (xy 43.014974 -363.239744)
			(xy 42.961022 -363.34254) (xy 42.900108 -363.441368) (xy 42.83252 -363.535759) (xy 42.758581 -363.625261)
			(xy 42.678643 -363.709449) (xy 42.593088 -363.787922) (xy 42.502604 -363.86008) (xy 93.154506 -363.86008)
			(xy 93.158522 -363.74381) (xy 93.170549 -363.628095) (xy 93.190531 -363.513485) (xy 93.218373 -363.400526)
			(xy 93.253942 -363.289758) (xy 93.297068 -363.181707) (xy 93.347545 -363.076889) (xy 93.405134 -362.975804)
			(xy 93.46956 -362.878932) (xy 93.540515 -362.786736) (xy 93.617662 -362.699655) (xy 93.700633 -362.618104)
			(xy 93.789033 -362.542472) (xy 93.88244 -362.473118) (xy 93.980409 -362.410375) (xy 94.082473 -362.354539)
			(xy 94.188147 -362.305878) (xy 94.296926 -362.264624) (xy 94.408291 -362.230973) (xy 94.521714 -362.205085)
			(xy 94.636651 -362.187084) (xy 94.752557 -362.177055) (xy 94.868879 -362.175047) (xy 94.985062 -362.181069)
			(xy 95.100553 -362.195092) (xy 95.214801 -362.21705) (xy 95.327262 -362.246837) (xy 95.4374 -362.284312)
			(xy 95.54469 -362.329297) (xy 95.648621 -362.381576) (xy 95.748697 -362.440901) (xy 95.844443 -362.506989)
			(xy 95.9354 -362.579525) (xy 96.021136 -362.658164) (xy 96.101243 -362.74253) (xy 96.175339 -362.832222)
			(xy 96.243069 -362.926812) (xy 96.304113 -363.02585) (xy 96.358178 -363.128863) (xy 96.405008 -363.23536)
			(xy 96.444379 -363.344835) (xy 96.476103 -363.456765) (xy 96.500029 -363.570617) (xy 96.516043 -363.685849)
			(xy 96.52407 -363.801911) (xy 96.524572 -363.86008) (xy 96.52407 -363.918249) (xy 96.516043 -364.034311)
			(xy 96.500029 -364.149543) (xy 96.476103 -364.263395) (xy 96.444379 -364.375325) (xy 96.405008 -364.4848)
			(xy 96.358178 -364.591297) (xy 96.304113 -364.69431) (xy 96.243069 -364.793348) (xy 96.175339 -364.887938)
			(xy 96.101243 -364.97763) (xy 96.021136 -365.061996) (xy 95.9354 -365.140635) (xy 95.844443 -365.213171)
			(xy 95.748697 -365.279259) (xy 95.648621 -365.338584) (xy 95.54469 -365.390863) (xy 95.4374 -365.435848)
			(xy 95.327262 -365.473323) (xy 95.214801 -365.50311) (xy 95.100553 -365.525068) (xy 94.985062 -365.539091)
			(xy 94.868879 -365.545113) (xy 94.752557 -365.543105) (xy 94.636651 -365.533076) (xy 94.521714 -365.515075)
			(xy 94.408291 -365.489187) (xy 94.296926 -365.455536) (xy 94.188147 -365.414282) (xy 94.082473 -365.365621)
			(xy 93.980409 -365.309785) (xy 93.88244 -365.247042) (xy 93.789033 -365.177688) (xy 93.700633 -365.102056)
			(xy 93.617662 -365.020505) (xy 93.540515 -364.933424) (xy 93.46956 -364.841228) (xy 93.405134 -364.744356)
			(xy 93.347545 -364.643271) (xy 93.297068 -364.538453) (xy 93.253942 -364.430402) (xy 93.218373 -364.319634)
			(xy 93.190531 -364.206675) (xy 93.170549 -364.092065) (xy 93.158522 -363.97635) (xy 93.154506 -363.86008)
			(xy 42.502604 -363.86008) (xy 42.502322 -363.860305) (xy 42.406779 -363.926254) (xy 42.306914 -363.985454)
			(xy 42.203202 -364.037623) (xy 42.096139 -364.082512) (xy 41.986233 -364.119908) (xy 41.874009 -364.149633)
			(xy 41.760003 -364.171544) (xy 41.644756 -364.185537) (xy 41.528818 -364.191546) (xy 41.412742 -364.189543)
			(xy 41.29708 -364.179535) (xy 41.182385 -364.161572) (xy 41.069202 -364.135739) (xy 40.958071 -364.102159)
			(xy 40.849522 -364.060991) (xy 40.744072 -364.012433) (xy 40.642223 -363.956716) (xy 40.54446 -363.894104)
			(xy 40.45125 -363.824897) (xy 40.363037 -363.749424) (xy 40.280241 -363.668045) (xy 40.203257 -363.581148)
			(xy 40.132452 -363.489147) (xy 40.068162 -363.39248) (xy 40.010695 -363.291608) (xy 39.960324 -363.187011)
			(xy 39.917289 -363.079188) (xy 39.881795 -362.968654) (xy 39.854012 -362.855934) (xy 39.834072 -362.741566)
			(xy 39.82207 -362.626094) (xy 39.818063 -362.51007) (xy 1.016 -362.51007) (xy 1.016 -367.971578)
			(xy 1.047496 -368.054382) (xy 1.059942 -368.069876) (xy 1.077482 -368.09257) (xy 1.106268 -368.142179)
			(xy 1.127305 -368.195537) (xy 1.14012 -368.251442) (xy 1.144423 -368.308636) (xy 1.14012 -368.36583)
			(xy 1.127305 -368.421735) (xy 1.106268 -368.475093) (xy 1.077482 -368.524702) (xy 1.059942 -368.547396)
			(xy 1.047496 -368.56289) (xy 1.016 -368.645694) (xy 1.016 -375.61012) (xy 86.877404 -375.61012) (xy 86.881424 -375.419469)
			(xy 86.893478 -375.229156) (xy 86.913544 -375.039521) (xy 86.941587 -374.8509) (xy 86.977556 -374.66363)
			(xy 87.021388 -374.478042) (xy 87.073005 -374.294467) (xy 87.132315 -374.113231) (xy 87.199213 -373.934656)
			(xy 87.273579 -373.759061) (xy 87.355281 -373.586756) (xy 87.444175 -373.418049) (xy 87.540101 -373.253239)
			(xy 87.64289 -373.09262) (xy 87.752359 -372.936477) (xy 87.868313 -372.785088) (xy 87.990547 -372.638721)
			(xy 88.118841 -372.497637) (xy 88.252969 -372.362088) (xy 88.392693 -372.232313) (xy 88.537763 -372.108543)
			(xy 88.687921 -371.991) (xy 88.842902 -371.879891) (xy 89.002429 -371.775414) (xy 89.166218 -371.677755)
			(xy 89.333978 -371.587088) (xy 89.505412 -371.503574) (xy 89.680214 -371.427361) (xy 89.858073 -371.358585)
			(xy 90.038674 -371.297367) (xy 90.221694 -371.243818) (xy 90.40681 -371.198032) (xy 90.593691 -371.16009)
			(xy 90.782006 -371.130061) (xy 90.971419 -371.107996) (xy 91.161593 -371.093937) (xy 91.352192 -371.087907)
			(xy 91.542875 -371.089917) (xy 91.733304 -371.099964) (xy 91.92314 -371.11803) (xy 92.112046 -371.144083)
			(xy 92.299685 -371.178076) (xy 92.485725 -371.219949) (xy 92.669834 -371.269628) (xy 92.851685 -371.327024)
			(xy 93.030955 -371.392035) (xy 93.207325 -371.464546) (xy 93.380481 -371.544427) (xy 93.550116 -371.631537)
			(xy 93.715928 -371.725721) (xy 93.877622 -371.826812) (xy 94.03491 -371.934628) (xy 94.187513 -372.04898)
			(xy 94.335161 -372.169663) (xy 94.477589 -372.296464) (xy 94.614545 -372.429155) (xy 94.745786 -372.567503)
			(xy 94.871078 -372.71126) (xy 94.990198 -372.860171) (xy 95.102934 -373.013972) (xy 95.209087 -373.172388)
			(xy 95.308467 -373.335139) (xy 95.400897 -373.501934) (xy 95.486214 -373.672478) (xy 95.564266 -373.846466)
			(xy 95.634913 -374.023591) (xy 95.698031 -374.203536) (xy 95.753507 -374.385982) (xy 95.801242 -374.570605)
			(xy 95.841152 -374.757075) (xy 95.873165 -374.945063) (xy 95.897225 -375.134233) (xy 95.913288 -375.324249)
			(xy 95.921327 -375.514773) (xy 95.92183 -375.61012) (xy 95.921327 -375.705467) (xy 95.913288 -375.895991)
			(xy 95.897225 -376.086007) (xy 95.873165 -376.275177) (xy 95.841152 -376.463165) (xy 95.801242 -376.649635)
			(xy 95.753507 -376.834258) (xy 95.698031 -377.016704) (xy 95.634913 -377.196649) (xy 95.564266 -377.373774)
			(xy 95.486214 -377.547762) (xy 95.400897 -377.718306) (xy 95.308467 -377.885101) (xy 95.209087 -378.047852)
			(xy 95.102934 -378.206268) (xy 94.990198 -378.360069) (xy 94.871078 -378.50898) (xy 94.745786 -378.652737)
			(xy 94.614545 -378.791085) (xy 94.477589 -378.923776) (xy 94.335161 -379.050577) (xy 94.187513 -379.17126)
			(xy 94.03491 -379.285612) (xy 93.877622 -379.393428) (xy 93.715928 -379.494519) (xy 93.550116 -379.588703)
			(xy 93.380481 -379.675813) (xy 93.207325 -379.755694) (xy 93.030955 -379.828205) (xy 92.851685 -379.893216)
			(xy 92.669834 -379.950612) (xy 92.485725 -380.000291) (xy 92.299685 -380.042164) (xy 92.112046 -380.076157)
			(xy 91.92314 -380.10221) (xy 91.733304 -380.120276) (xy 91.542875 -380.130323) (xy 91.352192 -380.132333)
			(xy 91.161593 -380.126303) (xy 90.971419 -380.112244) (xy 90.782006 -380.090179) (xy 90.593691 -380.06015)
			(xy 90.40681 -380.022208) (xy 90.221694 -379.976422) (xy 90.038674 -379.922873) (xy 89.858073 -379.861655)
			(xy 89.680214 -379.792879) (xy 89.505412 -379.716666) (xy 89.333978 -379.633152) (xy 89.166218 -379.542485)
			(xy 89.002429 -379.444826) (xy 88.842902 -379.340349) (xy 88.687921 -379.22924) (xy 88.537763 -379.111697)
			(xy 88.392693 -378.987927) (xy 88.252969 -378.858152) (xy 88.118841 -378.722603) (xy 87.990547 -378.581519)
			(xy 87.868313 -378.435152) (xy 87.752359 -378.283763) (xy 87.64289 -378.12762) (xy 87.540101 -377.967001)
			(xy 87.444175 -377.802191) (xy 87.355281 -377.633484) (xy 87.273579 -377.461179) (xy 87.199213 -377.285584)
			(xy 87.132315 -377.107009) (xy 87.073005 -376.925773) (xy 87.021388 -376.742198) (xy 86.977556 -376.55661)
			(xy 86.941587 -376.36934) (xy 86.913544 -376.180719) (xy 86.893478 -375.991084) (xy 86.881424 -375.800771)
			(xy 86.877404 -375.61012) (xy 1.016 -375.61012) (xy 1.016 -380.671578) (xy 1.047496 -380.754382)
			(xy 1.059942 -380.769876) (xy 1.077482 -380.79257) (xy 1.106268 -380.842179) (xy 1.127305 -380.895537)
			(xy 1.14012 -380.951442) (xy 1.144423 -381.008636) (xy 1.14012 -381.06583) (xy 1.127305 -381.121735)
			(xy 1.106268 -381.175093) (xy 1.077482 -381.224702) (xy 1.059942 -381.247396) (xy 1.047496 -381.26289)
			(xy 1.016 -381.345694) (xy 1.016 -384.79984) (xy 11.34441 -384.79984) (xy 11.348411 -384.594791)
			(xy 11.36041 -384.390054) (xy 11.380388 -384.185941) (xy 11.408314 -383.982762) (xy 11.444146 -383.780829)
			(xy 11.48783 -383.580446) (xy 11.539298 -383.381921) (xy 11.598473 -383.185555) (xy 11.665264 -382.991648)
			(xy 11.73957 -382.800494) (xy 11.821277 -382.612384) (xy 11.910262 -382.427606) (xy 12.006388 -382.24644)
			(xy 12.109509 -382.069163) (xy 12.219469 -381.896044) (xy 12.336099 -381.727347) (xy 12.459222 -381.563329)
			(xy 12.588651 -381.40424) (xy 12.724188 -381.250322) (xy 12.865627 -381.101808) (xy 13.012754 -380.958927)
			(xy 13.165342 -380.821894) (xy 13.323161 -380.69092) (xy 13.48597 -380.566202) (xy 13.653521 -380.447932)
			(xy 13.825559 -380.336288) (xy 14.001822 -380.231442) (xy 14.182041 -380.133553) (xy 14.365942 -380.04277)
			(xy 14.553246 -379.959232) (xy 14.743666 -379.883064) (xy 14.936912 -379.814384) (xy 15.132692 -379.753296)
			(xy 15.330705 -379.699894) (xy 15.530652 -379.654257) (xy 15.732226 -379.616457) (xy 15.935122 -379.586549)
			(xy 16.139031 -379.564581) (xy 16.343641 -379.550586) (xy 16.548641 -379.544584) (xy 16.75372 -379.546585)
			(xy 16.958564 -379.556585) (xy 17.162863 -379.574571) (xy 17.366304 -379.600513) (xy 17.568577 -379.634374)
			(xy 17.769376 -379.6761) (xy 17.968394 -379.725629) (xy 18.165328 -379.782885) (xy 18.359878 -379.847782)
			(xy 18.551748 -379.920219) (xy 18.740645 -380.000087) (xy 18.926283 -380.087265) (xy 19.108378 -380.181619)
			(xy 19.286653 -380.283006) (xy 19.460836 -380.391271) (xy 19.630663 -380.506249) (xy 19.795875 -380.627767)
			(xy 19.956219 -380.755637) (xy 20.111453 -380.889666) (xy 20.261339 -381.02965) (xy 20.405649 -381.175375)
			(xy 20.544163 -381.32662) (xy 20.676672 -381.483153) (xy 20.802972 -381.644738) (xy 20.922871 -381.811127)
			(xy 21.036188 -381.982067) (xy 21.142748 -382.157299) (xy 21.242391 -382.336554) (xy 21.334964 -382.519561)
			(xy 21.420326 -382.70604) (xy 21.498347 -382.895708) (xy 21.56891 -383.088276) (xy 21.631905 -383.28345)
			(xy 21.687237 -383.480933) (xy 21.734822 -383.680424) (xy 21.774587 -383.881621) (xy 21.806472 -384.084215)
			(xy 21.830429 -384.2879) (xy 21.84642 -384.492364) (xy 21.854422 -384.697296) (xy 21.854922 -384.79984)
			(xy 21.854422 -384.902384) (xy 21.84642 -385.107316) (xy 21.830429 -385.31178) (xy 21.806472 -385.515465)
			(xy 21.774587 -385.718059) (xy 21.734822 -385.919256) (xy 21.687237 -386.118747) (xy 21.631905 -386.31623)
			(xy 21.56891 -386.511404) (xy 21.498347 -386.703972) (xy 21.420326 -386.89364) (xy 21.334964 -387.080119)
			(xy 21.242391 -387.263126) (xy 21.142748 -387.442381) (xy 21.036188 -387.617613) (xy 20.922871 -387.788553)
			(xy 20.802972 -387.954942) (xy 20.676672 -388.116527) (xy 20.544163 -388.27306) (xy 20.405649 -388.424305)
			(xy 20.261339 -388.57003) (xy 20.111453 -388.710014) (xy 19.956219 -388.844043) (xy 19.795875 -388.971913)
			(xy 19.630663 -389.093431) (xy 19.460836 -389.208409) (xy 19.286653 -389.316674) (xy 19.108378 -389.418061)
			(xy 18.926283 -389.512415) (xy 18.740645 -389.599593) (xy 18.551748 -389.679461) (xy 18.359878 -389.751898)
			(xy 18.165328 -389.816795) (xy 17.968394 -389.874051) (xy 17.769376 -389.92358) (xy 17.568577 -389.965306)
			(xy 17.366304 -389.999167) (xy 17.162863 -390.025109) (xy 16.958564 -390.043095) (xy 16.75372 -390.053095)
			(xy 16.548641 -390.055096) (xy 16.343641 -390.049094) (xy 16.139031 -390.035099) (xy 15.935122 -390.013131)
			(xy 15.732226 -389.983223) (xy 15.530652 -389.945423) (xy 15.330705 -389.899786) (xy 15.132692 -389.846384)
			(xy 14.936912 -389.785296) (xy 14.743666 -389.716616) (xy 14.553246 -389.640448) (xy 14.365942 -389.55691)
			(xy 14.182041 -389.466127) (xy 14.001822 -389.368238) (xy 13.825559 -389.263392) (xy 13.653521 -389.151748)
			(xy 13.48597 -389.033478) (xy 13.323161 -388.90876) (xy 13.165342 -388.777786) (xy 13.012754 -388.640753)
			(xy 12.865627 -388.497872) (xy 12.724188 -388.349358) (xy 12.588651 -388.19544) (xy 12.459222 -388.036351)
			(xy 12.336099 -387.872333) (xy 12.219469 -387.703636) (xy 12.109509 -387.530517) (xy 12.006388 -387.35324)
			(xy 11.910262 -387.172074) (xy 11.821277 -386.987296) (xy 11.73957 -386.799186) (xy 11.665264 -386.608032)
			(xy 11.598473 -386.414125) (xy 11.539298 -386.217759) (xy 11.48783 -386.019234) (xy 11.444146 -385.818851)
			(xy 11.408314 -385.616918) (xy 11.380388 -385.413739) (xy 11.36041 -385.209626) (xy 11.348411 -385.004889)
			(xy 11.34441 -384.79984) (xy 1.016 -384.79984) (xy 1.016 -393.371578) (xy 1.047496 -393.454382) (xy 1.059942 -393.469876)
			(xy 1.077482 -393.49257) (xy 1.106268 -393.542179) (xy 1.127305 -393.595537) (xy 1.14012 -393.651442)
			(xy 1.144423 -393.708636) (xy 1.14012 -393.76583) (xy 1.127305 -393.821735) (xy 1.106268 -393.875093)
			(xy 1.077482 -393.924702) (xy 1.059942 -393.947396) (xy 1.047496 -393.96289) (xy 1.016 -394.045694)
			(xy 1.016 -403.413036) (xy 1.547863 -403.413036) (xy 1.547863 -403.2869) (xy 1.555783 -403.161012)
			(xy 1.571593 -403.03587) (xy 1.595228 -402.911967) (xy 1.626597 -402.789794) (xy 1.665575 -402.669831)
			(xy 1.712009 -402.552552) (xy 1.765716 -402.43842) (xy 1.826483 -402.327885) (xy 1.89407 -402.221385)
			(xy 1.968211 -402.119338) (xy 2.048614 -402.022148) (xy 2.13496 -401.930198) (xy 2.22691 -401.843852)
			(xy 2.3241 -401.763449) (xy 2.426147 -401.689308) (xy 2.532647 -401.621721) (xy 2.643182 -401.560954)
			(xy 2.757314 -401.507247) (xy 2.874593 -401.460813) (xy 2.994556 -401.421835) (xy 3.116729 -401.390466)
			(xy 3.240632 -401.366831) (xy 3.365774 -401.351021) (xy 3.491662 -401.343101) (xy 3.617798 -401.343101)
			(xy 3.743686 -401.351021) (xy 3.868828 -401.366831) (xy 3.992731 -401.390466) (xy 4.114904 -401.421835)
			(xy 4.234867 -401.460813) (xy 4.352146 -401.507247) (xy 4.466278 -401.560954) (xy 4.576813 -401.621721)
			(xy 4.683313 -401.689308) (xy 4.78536 -401.763449) (xy 4.88255 -401.843852) (xy 4.9745 -401.930198)
			(xy 5.060846 -402.022148) (xy 5.141249 -402.119338) (xy 5.21539 -402.221385) (xy 5.282977 -402.327885)
			(xy 5.343744 -402.43842) (xy 5.397451 -402.552552) (xy 5.443885 -402.669831) (xy 5.482863 -402.789794)
			(xy 5.514232 -402.911967) (xy 5.537867 -403.03587) (xy 5.553677 -403.161012) (xy 5.561597 -403.2869)
			(xy 5.562092 -403.349968) (xy 5.561597 -403.413036) (xy 12.977863 -403.413036) (xy 12.977863 -403.2869)
			(xy 12.985783 -403.161012) (xy 13.001593 -403.03587) (xy 13.025228 -402.911967) (xy 13.056597 -402.789794)
			(xy 13.095575 -402.669831) (xy 13.142009 -402.552552) (xy 13.195716 -402.43842) (xy 13.256483 -402.327885)
			(xy 13.32407 -402.221385) (xy 13.398211 -402.119338) (xy 13.478614 -402.022148) (xy 13.56496 -401.930198)
			(xy 13.65691 -401.843852) (xy 13.7541 -401.763449) (xy 13.856147 -401.689308) (xy 13.962647 -401.621721)
			(xy 14.073182 -401.560954) (xy 14.187314 -401.507247) (xy 14.304593 -401.460813) (xy 14.424556 -401.421835)
			(xy 14.546729 -401.390466) (xy 14.670632 -401.366831) (xy 14.795774 -401.351021) (xy 14.921662 -401.343101)
			(xy 15.047798 -401.343101) (xy 15.173686 -401.351021) (xy 15.298828 -401.366831) (xy 15.422731 -401.390466)
			(xy 15.544904 -401.421835) (xy 15.664867 -401.460813) (xy 15.782146 -401.507247) (xy 15.896278 -401.560954)
			(xy 16.006813 -401.621721) (xy 16.113313 -401.689308) (xy 16.21536 -401.763449) (xy 16.31255 -401.843852)
			(xy 16.4045 -401.930198) (xy 16.490846 -402.022148) (xy 16.571249 -402.119338) (xy 16.64539 -402.221385)
			(xy 16.712977 -402.327885) (xy 16.773744 -402.43842) (xy 16.827451 -402.552552) (xy 16.873885 -402.669831)
			(xy 16.912863 -402.789794) (xy 16.944232 -402.911967) (xy 16.967867 -403.03587) (xy 16.983677 -403.161012)
			(xy 16.991597 -403.2869) (xy 16.992092 -403.349968) (xy 16.991597 -403.413036) (xy 16.983677 -403.538924)
			(xy 16.967867 -403.664066) (xy 16.944232 -403.787969) (xy 16.912863 -403.910142) (xy 16.873885 -404.030105)
			(xy 16.827451 -404.147384) (xy 16.773744 -404.261516) (xy 16.712977 -404.372051) (xy 16.64539 -404.478551)
			(xy 16.571249 -404.580598) (xy 16.490846 -404.677788) (xy 16.4045 -404.769738) (xy 16.31255 -404.856084)
			(xy 16.21536 -404.936487) (xy 16.113313 -405.010628) (xy 16.006813 -405.078215) (xy 15.896278 -405.138982)
			(xy 15.782146 -405.192689) (xy 15.664867 -405.239123) (xy 15.544904 -405.278101) (xy 15.422731 -405.30947)
			(xy 15.298828 -405.333105) (xy 15.173686 -405.348915) (xy 15.047798 -405.356835) (xy 14.921662 -405.356835)
			(xy 14.795774 -405.348915) (xy 14.670632 -405.333105) (xy 14.546729 -405.30947) (xy 14.424556 -405.278101)
			(xy 14.304593 -405.239123) (xy 14.187314 -405.192689) (xy 14.073182 -405.138982) (xy 13.962647 -405.078215)
			(xy 13.856147 -405.010628) (xy 13.7541 -404.936487) (xy 13.65691 -404.856084) (xy 13.56496 -404.769738)
			(xy 13.478614 -404.677788) (xy 13.398211 -404.580598) (xy 13.32407 -404.478551) (xy 13.256483 -404.372051)
			(xy 13.195716 -404.261516) (xy 13.142009 -404.147384) (xy 13.095575 -404.030105) (xy 13.056597 -403.910142)
			(xy 13.025228 -403.787969) (xy 13.001593 -403.664066) (xy 12.985783 -403.538924) (xy 12.977863 -403.413036)
			(xy 5.561597 -403.413036) (xy 5.553677 -403.538924) (xy 5.537867 -403.664066) (xy 5.514232 -403.787969)
			(xy 5.482863 -403.910142) (xy 5.443885 -404.030105) (xy 5.397451 -404.147384) (xy 5.343744 -404.261516)
			(xy 5.282977 -404.372051) (xy 5.21539 -404.478551) (xy 5.141249 -404.580598) (xy 5.060846 -404.677788)
			(xy 4.9745 -404.769738) (xy 4.88255 -404.856084) (xy 4.78536 -404.936487) (xy 4.683313 -405.010628)
			(xy 4.576813 -405.078215) (xy 4.466278 -405.138982) (xy 4.352146 -405.192689) (xy 4.234867 -405.239123)
			(xy 4.114904 -405.278101) (xy 3.992731 -405.30947) (xy 3.868828 -405.333105) (xy 3.743686 -405.348915)
			(xy 3.617798 -405.356835) (xy 3.491662 -405.356835) (xy 3.365774 -405.348915) (xy 3.240632 -405.333105)
			(xy 3.116729 -405.30947) (xy 2.994556 -405.278101) (xy 2.874593 -405.239123) (xy 2.757314 -405.192689)
			(xy 2.643182 -405.138982) (xy 2.532647 -405.078215) (xy 2.426147 -405.010628) (xy 2.3241 -404.936487)
			(xy 2.22691 -404.856084) (xy 2.13496 -404.769738) (xy 2.048614 -404.677788) (xy 1.968211 -404.580598)
			(xy 1.89407 -404.478551) (xy 1.826483 -404.372051) (xy 1.765716 -404.261516) (xy 1.712009 -404.147384)
			(xy 1.665575 -404.030105) (xy 1.626597 -403.910142) (xy 1.595228 -403.787969) (xy 1.571593 -403.664066)
			(xy 1.555783 -403.538924) (xy 1.547863 -403.413036) (xy 1.016 -403.413036) (xy 1.016 -404.690326)
			(xy 1.047496 -404.77313) (xy 1.060196 -404.788878) (xy 1.077936 -404.811646) (xy 1.107068 -404.861472)
			(xy 1.128365 -404.915116) (xy 1.141341 -404.971356) (xy 1.145699 -405.028908) (xy 1.141341 -405.086461)
			(xy 1.128366 -405.142701) (xy 1.10707 -405.196345) (xy 1.077938 -405.246171) (xy 1.060196 -405.268938)
			(xy 1.047496 -405.284686) (xy 1.016 -405.36749) (xy 1.016 -406.96007) (xy 39.818063 -406.96007) (xy 39.82207 -406.844046)
			(xy 39.834072 -406.728574) (xy 39.854012 -406.614206) (xy 39.881795 -406.501486) (xy 39.917289 -406.390952)
			(xy 39.960324 -406.283129) (xy 40.010695 -406.178532) (xy 40.068162 -406.07766) (xy 40.132452 -405.980993)
			(xy 40.203257 -405.888992) (xy 40.280241 -405.802095) (xy 40.363037 -405.720716) (xy 40.45125 -405.645243)
			(xy 40.54446 -405.576036) (xy 40.642223 -405.513424) (xy 40.744072 -405.457707) (xy 40.849522 -405.409149)
			(xy 40.958071 -405.367981) (xy 41.069202 -405.334401) (xy 41.182385 -405.308568) (xy 41.29708 -405.290605)
			(xy 41.412742 -405.280597) (xy 41.528818 -405.278594) (xy 41.644756 -405.284603) (xy 41.760003 -405.298596)
			(xy 41.874009 -405.320507) (xy 41.986233 -405.350232) (xy 42.096139 -405.387628) (xy 42.203202 -405.432517)
			(xy 42.306914 -405.484686) (xy 42.406779 -405.543886) (xy 42.502322 -405.609835) (xy 42.593088 -405.682218)
			(xy 42.678643 -405.760691) (xy 42.758581 -405.844879) (xy 42.83252 -405.934381) (xy 42.900108 -406.028772)
			(xy 42.961022 -406.1276) (xy 43.014974 -406.230396) (xy 43.061704 -406.336669) (xy 43.100992 -406.445913)
			(xy 43.132649 -406.557606) (xy 43.156525 -406.671218) (xy 43.172506 -406.786206) (xy 43.180515 -406.902023)
			(xy 43.181016 -406.96007) (xy 43.180515 -407.018117) (xy 43.172506 -407.133934) (xy 43.156525 -407.248922)
			(xy 43.132649 -407.362534) (xy 43.100992 -407.474227) (xy 43.061704 -407.583471) (xy 43.014974 -407.689744)
			(xy 42.961022 -407.79254) (xy 42.900108 -407.891368) (xy 42.83252 -407.985759) (xy 42.758581 -408.075261)
			(xy 42.678643 -408.159449) (xy 42.593088 -408.237922) (xy 42.502604 -408.31008) (xy 93.154506 -408.31008)
			(xy 93.158522 -408.19381) (xy 93.170549 -408.078095) (xy 93.190531 -407.963485) (xy 93.218373 -407.850526)
			(xy 93.253942 -407.739758) (xy 93.297068 -407.631707) (xy 93.347545 -407.526889) (xy 93.405134 -407.425804)
			(xy 93.46956 -407.328932) (xy 93.540515 -407.236736) (xy 93.617662 -407.149655) (xy 93.700633 -407.068104)
			(xy 93.789033 -406.992472) (xy 93.88244 -406.923118) (xy 93.980409 -406.860375) (xy 94.082473 -406.804539)
			(xy 94.188147 -406.755878) (xy 94.296926 -406.714624) (xy 94.408291 -406.680973) (xy 94.521714 -406.655085)
			(xy 94.636651 -406.637084) (xy 94.752557 -406.627055) (xy 94.868879 -406.625047) (xy 94.985062 -406.631069)
			(xy 95.100553 -406.645092) (xy 95.214801 -406.66705) (xy 95.327262 -406.696837) (xy 95.4374 -406.734312)
			(xy 95.54469 -406.779297) (xy 95.648621 -406.831576) (xy 95.748697 -406.890901) (xy 95.844443 -406.956989)
			(xy 95.9354 -407.029525) (xy 96.021136 -407.108164) (xy 96.101243 -407.19253) (xy 96.175339 -407.282222)
			(xy 96.243069 -407.376812) (xy 96.304113 -407.47585) (xy 96.358178 -407.578863) (xy 96.405008 -407.68536)
			(xy 96.444379 -407.794835) (xy 96.476103 -407.906765) (xy 96.500029 -408.020617) (xy 96.516043 -408.135849)
			(xy 96.52407 -408.251911) (xy 96.524572 -408.31008) (xy 96.52407 -408.368249) (xy 96.516043 -408.484311)
			(xy 96.500029 -408.599543) (xy 96.476103 -408.713395) (xy 96.444379 -408.825325) (xy 96.405008 -408.9348)
			(xy 96.358178 -409.041297) (xy 96.304113 -409.14431) (xy 96.243069 -409.243348) (xy 96.175339 -409.337938)
			(xy 96.101243 -409.42763) (xy 96.021136 -409.511996) (xy 95.9354 -409.590635) (xy 95.844443 -409.663171)
			(xy 95.748697 -409.729259) (xy 95.648621 -409.788584) (xy 95.54469 -409.840863) (xy 95.4374 -409.885848)
			(xy 95.327262 -409.923323) (xy 95.214801 -409.95311) (xy 95.100553 -409.975068) (xy 94.985062 -409.989091)
			(xy 94.868879 -409.995113) (xy 94.752557 -409.993105) (xy 94.636651 -409.983076) (xy 94.521714 -409.965075)
			(xy 94.408291 -409.939187) (xy 94.296926 -409.905536) (xy 94.188147 -409.864282) (xy 94.082473 -409.815621)
			(xy 93.980409 -409.759785) (xy 93.88244 -409.697042) (xy 93.789033 -409.627688) (xy 93.700633 -409.552056)
			(xy 93.617662 -409.470505) (xy 93.540515 -409.383424) (xy 93.46956 -409.291228) (xy 93.405134 -409.194356)
			(xy 93.347545 -409.093271) (xy 93.297068 -408.988453) (xy 93.253942 -408.880402) (xy 93.218373 -408.769634)
			(xy 93.190531 -408.656675) (xy 93.170549 -408.542065) (xy 93.158522 -408.42635) (xy 93.154506 -408.31008)
			(xy 42.502604 -408.31008) (xy 42.502322 -408.310305) (xy 42.406779 -408.376254) (xy 42.306914 -408.435454)
			(xy 42.203202 -408.487623) (xy 42.096139 -408.532512) (xy 41.986233 -408.569908) (xy 41.874009 -408.599633)
			(xy 41.760003 -408.621544) (xy 41.644756 -408.635537) (xy 41.528818 -408.641546) (xy 41.412742 -408.639543)
			(xy 41.29708 -408.629535) (xy 41.182385 -408.611572) (xy 41.069202 -408.585739) (xy 40.958071 -408.552159)
			(xy 40.849522 -408.510991) (xy 40.744072 -408.462433) (xy 40.642223 -408.406716) (xy 40.54446 -408.344104)
			(xy 40.45125 -408.274897) (xy 40.363037 -408.199424) (xy 40.280241 -408.118045) (xy 40.203257 -408.031148)
			(xy 40.132452 -407.939147) (xy 40.068162 -407.84248) (xy 40.010695 -407.741608) (xy 39.960324 -407.637011)
			(xy 39.917289 -407.529188) (xy 39.881795 -407.418654) (xy 39.854012 -407.305934) (xy 39.834072 -407.191566)
			(xy 39.82207 -407.076094) (xy 39.818063 -406.96007) (xy 1.016 -406.96007) (xy 1.016 -408.641804)
			(xy 1.048004 -408.725116) (xy 1.060704 -408.741118) (xy 1.061212 -408.741626) (xy 1.079005 -408.764403)
			(xy 1.10823 -408.814266) (xy 1.129596 -408.867968) (xy 1.142615 -408.924279) (xy 1.146988 -408.98191)
			(xy 1.142615 -409.039541) (xy 1.129596 -409.095852) (xy 1.10823 -409.149554) (xy 1.079005 -409.199417)
			(xy 1.061212 -409.222194) (xy 1.060704 -409.222702) (xy 1.048004 -409.238704) (xy 1.016 -409.322016)
			(xy 1.016 -418.771578) (xy 1.047496 -418.854382) (xy 1.059942 -418.869876) (xy 1.077482 -418.89257)
			(xy 1.106268 -418.942179) (xy 1.127305 -418.995537) (xy 1.14012 -419.051442) (xy 1.144423 -419.108636)
			(xy 1.14012 -419.16583) (xy 1.127305 -419.221735) (xy 1.106268 -419.275093) (xy 1.077482 -419.324702)
			(xy 1.059942 -419.347396) (xy 1.047496 -419.36289) (xy 1.016 -419.445694) (xy 1.016 -420.06012) (xy 86.877404 -420.06012)
			(xy 86.881424 -419.869469) (xy 86.893478 -419.679156) (xy 86.913544 -419.489521) (xy 86.941587 -419.3009)
			(xy 86.977556 -419.11363) (xy 87.021388 -418.928042) (xy 87.073005 -418.744467) (xy 87.132315 -418.563231)
			(xy 87.199213 -418.384656) (xy 87.273579 -418.209061) (xy 87.355281 -418.036756) (xy 87.444175 -417.868049)
			(xy 87.540101 -417.703239) (xy 87.64289 -417.54262) (xy 87.752359 -417.386477) (xy 87.868313 -417.235088)
			(xy 87.990547 -417.088721) (xy 88.118841 -416.947637) (xy 88.252969 -416.812088) (xy 88.392693 -416.682313)
			(xy 88.537763 -416.558543) (xy 88.687921 -416.441) (xy 88.842902 -416.329891) (xy 89.002429 -416.225414)
			(xy 89.166218 -416.127755) (xy 89.333978 -416.037088) (xy 89.505412 -415.953574) (xy 89.680214 -415.877361)
			(xy 89.858073 -415.808585) (xy 90.038674 -415.747367) (xy 90.221694 -415.693818) (xy 90.40681 -415.648032)
			(xy 90.593691 -415.61009) (xy 90.782006 -415.580061) (xy 90.971419 -415.557996) (xy 91.161593 -415.543937)
			(xy 91.352192 -415.537907) (xy 91.542875 -415.539917) (xy 91.733304 -415.549964) (xy 91.92314 -415.56803)
			(xy 92.112046 -415.594083) (xy 92.299685 -415.628076) (xy 92.485725 -415.669949) (xy 92.669834 -415.719628)
			(xy 92.851685 -415.777024) (xy 93.030955 -415.842035) (xy 93.207325 -415.914546) (xy 93.380481 -415.994427)
			(xy 93.550116 -416.081537) (xy 93.715928 -416.175721) (xy 93.877622 -416.276812) (xy 94.03491 -416.384628)
			(xy 94.187513 -416.49898) (xy 94.335161 -416.619663) (xy 94.477589 -416.746464) (xy 94.614545 -416.879155)
			(xy 94.745786 -417.017503) (xy 94.871078 -417.16126) (xy 94.990198 -417.310171) (xy 95.102934 -417.463972)
			(xy 95.209087 -417.622388) (xy 95.308467 -417.785139) (xy 95.400897 -417.951934) (xy 95.486214 -418.122478)
			(xy 95.564266 -418.296466) (xy 95.634913 -418.473591) (xy 95.698031 -418.653536) (xy 95.753507 -418.835982)
			(xy 95.801242 -419.020605) (xy 95.841152 -419.207075) (xy 95.873165 -419.395063) (xy 95.897225 -419.584233)
			(xy 95.913288 -419.774249) (xy 95.921327 -419.964773) (xy 95.92183 -420.06012) (xy 95.921327 -420.155467)
			(xy 95.913288 -420.345991) (xy 95.897225 -420.536007) (xy 95.873165 -420.725177) (xy 95.841152 -420.913165)
			(xy 95.801242 -421.099635) (xy 95.753507 -421.284258) (xy 95.698031 -421.466704) (xy 95.634913 -421.646649)
			(xy 95.564266 -421.823774) (xy 95.486214 -421.997762) (xy 95.400897 -422.168306) (xy 95.308467 -422.335101)
			(xy 95.209087 -422.497852) (xy 95.102934 -422.656268) (xy 94.990198 -422.810069) (xy 94.871078 -422.95898)
			(xy 94.745786 -423.102737) (xy 94.614545 -423.241085) (xy 94.477589 -423.373776) (xy 94.335161 -423.500577)
			(xy 94.187513 -423.62126) (xy 94.03491 -423.735612) (xy 93.877622 -423.843428) (xy 93.715928 -423.944519)
			(xy 93.550116 -424.038703) (xy 93.380481 -424.125813) (xy 93.207325 -424.205694) (xy 93.030955 -424.278205)
			(xy 92.851685 -424.343216) (xy 92.669834 -424.400612) (xy 92.485725 -424.450291) (xy 92.299685 -424.492164)
			(xy 92.112046 -424.526157) (xy 91.92314 -424.55221) (xy 91.733304 -424.570276) (xy 91.542875 -424.580323)
			(xy 91.352192 -424.582333) (xy 91.161593 -424.576303) (xy 90.971419 -424.562244) (xy 90.782006 -424.540179)
			(xy 90.593691 -424.51015) (xy 90.40681 -424.472208) (xy 90.221694 -424.426422) (xy 90.038674 -424.372873)
			(xy 89.858073 -424.311655) (xy 89.680214 -424.242879) (xy 89.505412 -424.166666) (xy 89.333978 -424.083152)
			(xy 89.166218 -423.992485) (xy 89.002429 -423.894826) (xy 88.842902 -423.790349) (xy 88.687921 -423.67924)
			(xy 88.537763 -423.561697) (xy 88.392693 -423.437927) (xy 88.252969 -423.308152) (xy 88.118841 -423.172603)
			(xy 87.990547 -423.031519) (xy 87.868313 -422.885152) (xy 87.752359 -422.733763) (xy 87.64289 -422.57762)
			(xy 87.540101 -422.417001) (xy 87.444175 -422.252191) (xy 87.355281 -422.083484) (xy 87.273579 -421.911179)
			(xy 87.199213 -421.735584) (xy 87.132315 -421.557009) (xy 87.073005 -421.375773) (xy 87.021388 -421.192198)
			(xy 86.977556 -421.00661) (xy 86.941587 -420.81934) (xy 86.913544 -420.630719) (xy 86.893478 -420.441084)
			(xy 86.881424 -420.250771) (xy 86.877404 -420.06012) (xy 1.016 -420.06012) (xy 1.016 -430.149762)
			(xy 72.864987 -430.149762) (xy 72.868996 -429.946891) (xy 72.881016 -429.744337) (xy 72.90103 -429.542416)
			(xy 72.929005 -429.341443) (xy 72.964898 -429.141733) (xy 73.008652 -428.943596) (xy 73.060201 -428.747343)
			(xy 73.119462 -428.553279) (xy 73.186344 -428.361708) (xy 73.260742 -428.172929) (xy 73.34254 -427.987236)
			(xy 73.43161 -427.80492) (xy 73.527813 -427.626265) (xy 73.631 -427.451551) (xy 73.741008 -427.281049)
			(xy 73.857666 -427.115026) (xy 73.980792 -426.953742) (xy 74.110194 -426.797448) (xy 74.245669 -426.646388)
			(xy 74.387006 -426.500798) (xy 74.533985 -426.360906) (xy 74.686376 -426.22693) (xy 74.843941 -426.099078)
			(xy 75.006434 -425.977552) (xy 75.173601 -425.862539) (xy 75.345181 -425.754221) (xy 75.520906 -425.652766)
			(xy 75.700503 -425.558332) (xy 75.88369 -425.471067) (xy 76.070182 -425.391108) (xy 76.259687 -425.318579)
			(xy 76.451909 -425.253593) (xy 76.646549 -425.196251) (xy 76.843302 -425.146644) (xy 77.041861 -425.104849)
			(xy 77.241917 -425.070931) (xy 77.443156 -425.044943) (xy 77.645265 -425.026925) (xy 77.847928 -425.016906)
			(xy 78.050828 -425.014902) (xy 78.253649 -425.020914) (xy 78.456075 -425.034935) (xy 78.657788 -425.056943)
			(xy 78.858475 -425.086902) (xy 79.057821 -425.124766) (xy 79.255516 -425.170476) (xy 79.45125 -425.22396)
			(xy 79.644719 -425.285136) (xy 79.83562 -425.353907) (xy 80.023655 -425.430167) (xy 80.208531 -425.513795)
			(xy 80.389958 -425.604662) (xy 80.567654 -425.702625) (xy 80.74134 -425.807533) (xy 80.910747 -425.91922)
			(xy 81.075609 -426.037512) (xy 81.235669 -426.162226) (xy 81.390677 -426.293165) (xy 81.540391 -426.430126)
			(xy 81.684577 -426.572895) (xy 81.823011 -426.721249) (xy 81.955475 -426.874956) (xy 82.081764 -427.033776)
			(xy 82.201679 -427.197461) (xy 82.315035 -427.365756) (xy 82.421653 -427.538398) (xy 82.521367 -427.715118)
			(xy 82.614022 -427.895638) (xy 82.699472 -428.079678) (xy 82.777586 -428.266951) (xy 82.848239 -428.457163)
			(xy 82.911323 -428.650018) (xy 82.966739 -428.845215) (xy 83.0144 -429.042448) (xy 83.054231 -429.241411)
			(xy 83.086171 -429.441792) (xy 83.11017 -429.643278) (xy 83.12619 -429.845555) (xy 83.134207 -430.048307)
			(xy 83.134708 -430.149762) (xy 83.134207 -430.251217) (xy 83.12619 -430.453969) (xy 83.11017 -430.656246)
			(xy 83.086171 -430.857732) (xy 83.054231 -431.058113) (xy 83.0144 -431.257076) (xy 82.966739 -431.454309)
			(xy 82.911323 -431.649506) (xy 82.848239 -431.842361) (xy 82.777586 -432.032573) (xy 82.699472 -432.219846)
			(xy 82.614022 -432.403886) (xy 82.521367 -432.584406) (xy 82.421653 -432.761126) (xy 82.315035 -432.933768)
			(xy 82.201679 -433.102063) (xy 82.081764 -433.265748) (xy 81.955475 -433.424568) (xy 81.823011 -433.578275)
			(xy 81.684577 -433.726629) (xy 81.540391 -433.869398) (xy 81.390677 -434.006359) (xy 81.235669 -434.137298)
			(xy 81.075609 -434.262012) (xy 80.910747 -434.380304) (xy 80.74134 -434.491991) (xy 80.567654 -434.596899)
			(xy 80.389958 -434.694862) (xy 80.208531 -434.785729) (xy 80.023655 -434.869357) (xy 79.83562 -434.945617)
			(xy 79.644719 -435.014388) (xy 79.45125 -435.075564) (xy 79.255516 -435.129048) (xy 79.057821 -435.174758)
			(xy 78.858475 -435.212622) (xy 78.657788 -435.242581) (xy 78.456075 -435.264589) (xy 78.253649 -435.27861)
			(xy 78.050828 -435.284622) (xy 77.847928 -435.282618) (xy 77.645265 -435.272599) (xy 77.443156 -435.254581)
			(xy 77.241917 -435.228593) (xy 77.041861 -435.194675) (xy 76.843302 -435.15288) (xy 76.646549 -435.103273)
			(xy 76.451909 -435.045931) (xy 76.259687 -434.980945) (xy 76.070182 -434.908416) (xy 75.88369 -434.828457)
			(xy 75.700503 -434.741192) (xy 75.520906 -434.646758) (xy 75.345181 -434.545303) (xy 75.173601 -434.436985)
			(xy 75.006434 -434.321972) (xy 74.843941 -434.200446) (xy 74.686376 -434.072594) (xy 74.533985 -433.938618)
			(xy 74.387006 -433.798726) (xy 74.245669 -433.653136) (xy 74.110194 -433.502076) (xy 73.980792 -433.345782)
			(xy 73.857666 -433.184498) (xy 73.741008 -433.018475) (xy 73.631 -432.847973) (xy 73.527813 -432.673259)
			(xy 73.43161 -432.494604) (xy 73.34254 -432.312288) (xy 73.260742 -432.126595) (xy 73.186344 -431.937816)
			(xy 73.119462 -431.746245) (xy 73.060201 -431.552181) (xy 73.008652 -431.355928) (xy 72.964898 -431.157791)
			(xy 72.929005 -430.958081) (xy 72.90103 -430.757108) (xy 72.881016 -430.555187) (xy 72.868996 -430.352633)
			(xy 72.864987 -430.149762) (xy 1.016 -430.149762) (xy 1.016 -431.471578) (xy 1.047496 -431.554382)
			(xy 1.059942 -431.569876) (xy 1.077482 -431.59257) (xy 1.106268 -431.642179) (xy 1.127305 -431.695537)
			(xy 1.14012 -431.751442) (xy 1.144423 -431.808636) (xy 1.14012 -431.86583) (xy 1.127305 -431.921735)
			(xy 1.106268 -431.975093) (xy 1.077482 -432.024702) (xy 1.059942 -432.047396) (xy 1.047496 -432.06289)
			(xy 1.016 -432.145694) (xy 1.016 -444.171578) (xy 1.047496 -444.254382) (xy 1.059942 -444.269876)
			(xy 1.077482 -444.29257) (xy 1.106268 -444.342179) (xy 1.127305 -444.395537) (xy 1.14012 -444.451442)
			(xy 1.144423 -444.508636) (xy 1.14012 -444.56583) (xy 1.127305 -444.621735) (xy 1.106268 -444.675093)
			(xy 1.077482 -444.724702) (xy 1.059942 -444.747396) (xy 1.047496 -444.76289) (xy 1.016 -444.845694)
			(xy 1.016 -451.41007) (xy 39.818063 -451.41007) (xy 39.82207 -451.294046) (xy 39.834072 -451.178574)
			(xy 39.854012 -451.064206) (xy 39.881795 -450.951486) (xy 39.917289 -450.840952) (xy 39.960324 -450.733129)
			(xy 40.010695 -450.628532) (xy 40.068162 -450.52766) (xy 40.132452 -450.430993) (xy 40.203257 -450.338992)
			(xy 40.280241 -450.252095) (xy 40.363037 -450.170716) (xy 40.45125 -450.095243) (xy 40.54446 -450.026036)
			(xy 40.642223 -449.963424) (xy 40.744072 -449.907707) (xy 40.849522 -449.859149) (xy 40.958071 -449.817981)
			(xy 41.069202 -449.784401) (xy 41.182385 -449.758568) (xy 41.29708 -449.740605) (xy 41.412742 -449.730597)
			(xy 41.528818 -449.728594) (xy 41.644756 -449.734603) (xy 41.760003 -449.748596) (xy 41.874009 -449.770507)
			(xy 41.986233 -449.800232) (xy 42.096139 -449.837628) (xy 42.203202 -449.882517) (xy 42.306914 -449.934686)
			(xy 42.406779 -449.993886) (xy 42.502322 -450.059835) (xy 42.593088 -450.132218) (xy 42.678643 -450.210691)
			(xy 42.758581 -450.294879) (xy 42.83252 -450.384381) (xy 42.900108 -450.478772) (xy 42.961022 -450.5776)
			(xy 43.014974 -450.680396) (xy 43.061704 -450.786669) (xy 43.100992 -450.895913) (xy 43.132649 -451.007606)
			(xy 43.156525 -451.121218) (xy 43.172506 -451.236206) (xy 43.180515 -451.352023) (xy 43.181016 -451.41007)
			(xy 43.180515 -451.468117) (xy 43.172506 -451.583934) (xy 43.156525 -451.698922) (xy 43.132649 -451.812534)
			(xy 43.100992 -451.924227) (xy 43.061704 -452.033471) (xy 43.014974 -452.139744) (xy 42.961022 -452.24254)
			(xy 42.900108 -452.341368) (xy 42.83252 -452.435759) (xy 42.758581 -452.525261) (xy 42.678643 -452.609449)
			(xy 42.593088 -452.687922) (xy 42.502604 -452.76008) (xy 93.154506 -452.76008) (xy 93.158522 -452.64381)
			(xy 93.170549 -452.528095) (xy 93.190531 -452.413485) (xy 93.218373 -452.300526) (xy 93.253942 -452.189758)
			(xy 93.297068 -452.081707) (xy 93.347545 -451.976889) (xy 93.405134 -451.875804) (xy 93.46956 -451.778932)
			(xy 93.540515 -451.686736) (xy 93.617662 -451.599655) (xy 93.700633 -451.518104) (xy 93.789033 -451.442472)
			(xy 93.88244 -451.373118) (xy 93.980409 -451.310375) (xy 94.082473 -451.254539) (xy 94.188147 -451.205878)
			(xy 94.296926 -451.164624) (xy 94.408291 -451.130973) (xy 94.521714 -451.105085) (xy 94.636651 -451.087084)
			(xy 94.752557 -451.077055) (xy 94.868879 -451.075047) (xy 94.985062 -451.081069) (xy 95.100553 -451.095092)
			(xy 95.214801 -451.11705) (xy 95.327262 -451.146837) (xy 95.4374 -451.184312) (xy 95.54469 -451.229297)
			(xy 95.648621 -451.281576) (xy 95.748697 -451.340901) (xy 95.844443 -451.406989) (xy 95.9354 -451.479525)
			(xy 96.021136 -451.558164) (xy 96.101243 -451.64253) (xy 96.175339 -451.732222) (xy 96.243069 -451.826812)
			(xy 96.304113 -451.92585) (xy 96.358178 -452.028863) (xy 96.405008 -452.13536) (xy 96.444379 -452.244835)
			(xy 96.476103 -452.356765) (xy 96.500029 -452.470617) (xy 96.516043 -452.585849) (xy 96.52407 -452.701911)
			(xy 96.524572 -452.76008) (xy 96.52407 -452.818249) (xy 96.516043 -452.934311) (xy 96.500029 -453.049543)
			(xy 96.476103 -453.163395) (xy 96.444379 -453.275325) (xy 96.405008 -453.3848) (xy 96.358178 -453.491297)
			(xy 96.304113 -453.59431) (xy 96.243069 -453.693348) (xy 96.175339 -453.787938) (xy 96.101243 -453.87763)
			(xy 96.021136 -453.961996) (xy 95.9354 -454.040635) (xy 95.844443 -454.113171) (xy 95.748697 -454.179259)
			(xy 95.648621 -454.238584) (xy 95.54469 -454.290863) (xy 95.4374 -454.335848) (xy 95.327262 -454.373323)
			(xy 95.214801 -454.40311) (xy 95.100553 -454.425068) (xy 94.985062 -454.439091) (xy 94.868879 -454.445113)
			(xy 94.752557 -454.443105) (xy 94.636651 -454.433076) (xy 94.521714 -454.415075) (xy 94.408291 -454.389187)
			(xy 94.296926 -454.355536) (xy 94.188147 -454.314282) (xy 94.082473 -454.265621) (xy 93.980409 -454.209785)
			(xy 93.88244 -454.147042) (xy 93.789033 -454.077688) (xy 93.700633 -454.002056) (xy 93.617662 -453.920505)
			(xy 93.540515 -453.833424) (xy 93.46956 -453.741228) (xy 93.405134 -453.644356) (xy 93.347545 -453.543271)
			(xy 93.297068 -453.438453) (xy 93.253942 -453.330402) (xy 93.218373 -453.219634) (xy 93.190531 -453.106675)
			(xy 93.170549 -452.992065) (xy 93.158522 -452.87635) (xy 93.154506 -452.76008) (xy 42.502604 -452.76008)
			(xy 42.502322 -452.760305) (xy 42.406779 -452.826254) (xy 42.306914 -452.885454) (xy 42.203202 -452.937623)
			(xy 42.096139 -452.982512) (xy 41.986233 -453.019908) (xy 41.874009 -453.049633) (xy 41.760003 -453.071544)
			(xy 41.644756 -453.085537) (xy 41.528818 -453.091546) (xy 41.412742 -453.089543) (xy 41.29708 -453.079535)
			(xy 41.182385 -453.061572) (xy 41.069202 -453.035739) (xy 40.958071 -453.002159) (xy 40.849522 -452.960991)
			(xy 40.744072 -452.912433) (xy 40.642223 -452.856716) (xy 40.54446 -452.794104) (xy 40.45125 -452.724897)
			(xy 40.363037 -452.649424) (xy 40.280241 -452.568045) (xy 40.203257 -452.481148) (xy 40.132452 -452.389147)
			(xy 40.068162 -452.29248) (xy 40.010695 -452.191608) (xy 39.960324 -452.087011) (xy 39.917289 -451.979188)
			(xy 39.881795 -451.868654) (xy 39.854012 -451.755934) (xy 39.834072 -451.641566) (xy 39.82207 -451.526094)
			(xy 39.818063 -451.41007) (xy 1.016 -451.41007) (xy 1.016 -456.871578) (xy 1.047496 -456.954382)
			(xy 1.059942 -456.969876) (xy 1.077482 -456.99257) (xy 1.106268 -457.042179) (xy 1.127305 -457.095537)
			(xy 1.14012 -457.151442) (xy 1.144423 -457.208636) (xy 1.14012 -457.26583) (xy 1.127305 -457.321735)
			(xy 1.106268 -457.375093) (xy 1.077482 -457.424702) (xy 1.059942 -457.447396) (xy 1.047496 -457.46289)
			(xy 1.016 -457.545694) (xy 1.016 -464.509866) (xy 86.877404 -464.509866) (xy 86.881424 -464.319215)
			(xy 86.893478 -464.128902) (xy 86.913544 -463.939267) (xy 86.941587 -463.750646) (xy 86.977556 -463.563376)
			(xy 87.021388 -463.377788) (xy 87.073005 -463.194213) (xy 87.132315 -463.012977) (xy 87.199213 -462.834402)
			(xy 87.273579 -462.658807) (xy 87.355281 -462.486502) (xy 87.444175 -462.317795) (xy 87.540101 -462.152985)
			(xy 87.64289 -461.992366) (xy 87.752359 -461.836223) (xy 87.868313 -461.684834) (xy 87.990547 -461.538467)
			(xy 88.118841 -461.397383) (xy 88.252969 -461.261834) (xy 88.392693 -461.132059) (xy 88.537763 -461.008289)
			(xy 88.687921 -460.890746) (xy 88.842902 -460.779637) (xy 89.002429 -460.67516) (xy 89.166218 -460.577501)
			(xy 89.333978 -460.486834) (xy 89.505412 -460.40332) (xy 89.680214 -460.327107) (xy 89.858073 -460.258331)
			(xy 90.038674 -460.197113) (xy 90.221694 -460.143564) (xy 90.40681 -460.097778) (xy 90.593691 -460.059836)
			(xy 90.782006 -460.029807) (xy 90.971419 -460.007742) (xy 91.161593 -459.993683) (xy 91.352192 -459.987653)
			(xy 91.542875 -459.989663) (xy 91.733304 -459.99971) (xy 91.92314 -460.017776) (xy 92.112046 -460.043829)
			(xy 92.299685 -460.077822) (xy 92.485725 -460.119695) (xy 92.669834 -460.169374) (xy 92.851685 -460.22677)
			(xy 93.030955 -460.291781) (xy 93.207325 -460.364292) (xy 93.380481 -460.444173) (xy 93.550116 -460.531283)
			(xy 93.715928 -460.625467) (xy 93.877622 -460.726558) (xy 94.03491 -460.834374) (xy 94.187513 -460.948726)
			(xy 94.335161 -461.069409) (xy 94.477589 -461.19621) (xy 94.614545 -461.328901) (xy 94.745786 -461.467249)
			(xy 94.871078 -461.611006) (xy 94.990198 -461.759917) (xy 95.102934 -461.913718) (xy 95.209087 -462.072134)
			(xy 95.308467 -462.234885) (xy 95.400897 -462.40168) (xy 95.486214 -462.572224) (xy 95.564266 -462.746212)
			(xy 95.634913 -462.923337) (xy 95.698031 -463.103282) (xy 95.753507 -463.285728) (xy 95.801242 -463.470351)
			(xy 95.841152 -463.656821) (xy 95.873165 -463.844809) (xy 95.897225 -464.033979) (xy 95.913288 -464.223995)
			(xy 95.921327 -464.414519) (xy 95.92183 -464.509866) (xy 95.921327 -464.605213) (xy 95.913288 -464.795737)
			(xy 95.897225 -464.985753) (xy 95.873165 -465.174923) (xy 95.841152 -465.362911) (xy 95.801242 -465.549381)
			(xy 95.753507 -465.734004) (xy 95.698031 -465.91645) (xy 95.634913 -466.096395) (xy 95.564266 -466.27352)
			(xy 95.486214 -466.447508) (xy 95.400897 -466.618052) (xy 95.308467 -466.784847) (xy 95.209087 -466.947598)
			(xy 95.102934 -467.106014) (xy 94.990198 -467.259815) (xy 94.871078 -467.408726) (xy 94.745786 -467.552483)
			(xy 94.614545 -467.690831) (xy 94.477589 -467.823522) (xy 94.335161 -467.950323) (xy 94.187513 -468.071006)
			(xy 94.03491 -468.185358) (xy 93.877622 -468.293174) (xy 93.715928 -468.394265) (xy 93.550116 -468.488449)
			(xy 93.380481 -468.575559) (xy 93.207325 -468.65544) (xy 93.030955 -468.727951) (xy 92.851685 -468.792962)
			(xy 92.669834 -468.850358) (xy 92.485725 -468.900037) (xy 92.299685 -468.94191) (xy 92.112046 -468.975903)
			(xy 91.92314 -469.001956) (xy 91.733304 -469.020022) (xy 91.542875 -469.030069) (xy 91.352192 -469.032079)
			(xy 91.161593 -469.026049) (xy 90.971419 -469.01199) (xy 90.782006 -468.989925) (xy 90.593691 -468.959896)
			(xy 90.40681 -468.921954) (xy 90.221694 -468.876168) (xy 90.038674 -468.822619) (xy 89.858073 -468.761401)
			(xy 89.680214 -468.692625) (xy 89.505412 -468.616412) (xy 89.333978 -468.532898) (xy 89.166218 -468.442231)
			(xy 89.002429 -468.344572) (xy 88.842902 -468.240095) (xy 88.687921 -468.128986) (xy 88.537763 -468.011443)
			(xy 88.392693 -467.887673) (xy 88.252969 -467.757898) (xy 88.118841 -467.622349) (xy 87.990547 -467.481265)
			(xy 87.868313 -467.334898) (xy 87.752359 -467.183509) (xy 87.64289 -467.027366) (xy 87.540101 -466.866747)
			(xy 87.444175 -466.701937) (xy 87.355281 -466.53323) (xy 87.273579 -466.360925) (xy 87.199213 -466.18533)
			(xy 87.132315 -466.006755) (xy 87.073005 -465.825519) (xy 87.021388 -465.641944) (xy 86.977556 -465.456356)
			(xy 86.941587 -465.269086) (xy 86.913544 -465.080465) (xy 86.893478 -464.89083) (xy 86.881424 -464.700517)
			(xy 86.877404 -464.509866) (xy 1.016 -464.509866) (xy 1.016 -469.571578) (xy 1.047496 -469.654382)
			(xy 1.059942 -469.669876) (xy 1.077482 -469.69257) (xy 1.106268 -469.742179) (xy 1.127305 -469.795537)
			(xy 1.14012 -469.851442) (xy 1.144423 -469.908636) (xy 1.14012 -469.96583) (xy 1.127305 -470.021735)
			(xy 1.106268 -470.075093) (xy 1.077482 -470.124702) (xy 1.059942 -470.147396) (xy 1.047496 -470.16289)
			(xy 1.016 -470.245694) (xy 1.016 -473.758104) (xy 11.344959 -473.758104) (xy 11.346673 -473.553483)
			(xy 11.35635 -473.349084) (xy 11.373978 -473.145217) (xy 11.399529 -472.942191) (xy 11.432964 -472.740314)
			(xy 11.474234 -472.539891) (xy 11.523275 -472.341226) (xy 11.580012 -472.144622) (xy 11.644361 -471.950375)
			(xy 11.716222 -471.758781) (xy 11.795488 -471.570129) (xy 11.882039 -471.384706) (xy 11.975742 -471.202794)
			(xy 12.076456 -471.024667) (xy 12.184029 -470.850596) (xy 12.298296 -470.680845) (xy 12.419086 -470.515671)
			(xy 12.546214 -470.355325) (xy 12.679488 -470.200049) (xy 12.818706 -470.050079) (xy 12.963657 -469.905643)
			(xy 13.114121 -469.76696) (xy 13.26987 -469.634239) (xy 13.430667 -469.507682) (xy 13.59627 -469.387481)
			(xy 13.766427 -469.273819) (xy 13.940879 -469.166866) (xy 14.119363 -469.066786) (xy 14.301608 -468.973731)
			(xy 14.487338 -468.887841) (xy 14.67627 -468.809247) (xy 14.868119 -468.738067) (xy 15.062593 -468.67441)
			(xy 15.259399 -468.618373) (xy 15.458236 -468.570039) (xy 15.658805 -468.529483) (xy 15.8608 -468.496766)
			(xy 16.063916 -468.471938) (xy 16.267844 -468.455036) (xy 16.472276 -468.446085) (xy 16.676902 -468.4451)
			(xy 16.88141 -468.452082) (xy 17.085492 -468.46702) (xy 17.288838 -468.489892) (xy 17.491139 -468.520663)
			(xy 17.692088 -468.559287) (xy 17.891382 -468.605704) (xy 18.088717 -468.659844) (xy 18.283796 -468.721626)
			(xy 18.476321 -468.790955) (xy 18.666001 -468.867727) (xy 18.852549 -468.951825) (xy 18.944336 -468.99703)
			(xy 19.037195 -469.043881) (xy 19.219551 -469.143967) (xy 19.397802 -469.251192) (xy 19.57167 -469.365387)
			(xy 19.740882 -469.486374) (xy 19.905174 -469.613963) (xy 20.064287 -469.747954) (xy 20.217973 -469.888138)
			(xy 20.36599 -470.034293) (xy 20.508107 -470.186193) (xy 20.644101 -470.343598) (xy 20.773758 -470.506261)
			(xy 20.896877 -470.673929) (xy 21.013263 -470.846338) (xy 21.122735 -471.023218) (xy 21.225121 -471.204292)
			(xy 21.32026 -471.389277) (xy 21.408003 -471.577881) (xy 21.488214 -471.769811) (xy 21.560765 -471.964764)
			(xy 21.625544 -472.162437) (xy 21.682449 -472.362518) (xy 21.731392 -472.564694) (xy 21.772294 -472.768649)
			(xy 21.805092 -472.974063) (xy 21.829735 -473.180614) (xy 21.846184 -473.387979) (xy 21.854414 -473.595832)
			(xy 21.854922 -473.69984) (xy 21.854428 -473.801748) (xy 21.846517 -474.005409) (xy 21.830715 -474.208611)
			(xy 21.807045 -474.411047) (xy 21.775544 -474.612413) (xy 21.736258 -474.812406) (xy 21.689246 -475.010725)
			(xy 21.63458 -475.207072) (xy 21.572341 -475.401152) (xy 21.502623 -475.592672) (xy 21.425532 -475.781345)
			(xy 21.341182 -475.966887) (xy 21.249701 -476.149019) (xy 21.151227 -476.327466) (xy 21.045907 -476.50196)
			(xy 20.9339 -476.67224) (xy 20.815375 -476.838048) (xy 20.690509 -476.999135) (xy 20.559491 -477.15526)
			(xy 20.422517 -477.306186) (xy 20.279794 -477.451688) (xy 20.131537 -477.591546) (xy 19.977967 -477.72555)
			(xy 19.819317 -477.853499) (xy 19.655825 -477.975199) (xy 19.487737 -478.090468) (xy 19.315306 -478.199133)
			(xy 19.227292 -478.250504) (xy 19.138436 -478.301228) (xy 18.957375 -478.396567) (xy 18.77274 -478.484785)
			(xy 18.58481 -478.565748) (xy 18.393871 -478.639333) (xy 18.200212 -478.70543) (xy 18.004127 -478.763937)
			(xy 17.863861 -478.799906) (xy 74.3839 -478.799906) (xy 74.3839 -477.799908) (xy 74.384397 -477.715129)
			(xy 74.392344 -477.545758) (xy 74.408222 -477.376946) (xy 74.431995 -477.209063) (xy 74.46361 -477.04248)
			(xy 74.503 -476.877561) (xy 74.550075 -476.71467) (xy 74.604735 -476.554164) (xy 74.666857 -476.396397)
			(xy 74.736306 -476.241715) (xy 74.812929 -476.090458) (xy 74.896558 -475.942959) (xy 74.987008 -475.799542)
			(xy 75.084081 -475.660522) (xy 75.187564 -475.526205) (xy 75.297228 -475.396886) (xy 75.412834 -475.27285)
			(xy 75.534126 -475.154368) (xy 75.660839 -475.041702) (xy 75.792693 -474.935099) (xy 75.929399 -474.834794)
			(xy 76.070656 -474.741006) (xy 76.216154 -474.653943) (xy 76.365573 -474.573795) (xy 76.518585 -474.500739)
			(xy 76.674852 -474.434935) (xy 76.834032 -474.376528) (xy 76.995775 -474.325647) (xy 77.159725 -474.282402)
			(xy 77.325522 -474.24689) (xy 77.492801 -474.219188) (xy 77.661195 -474.199358) (xy 77.830333 -474.187442)
			(xy 77.999844 -474.183467) (xy 78.169355 -474.187442) (xy 78.338493 -474.199358) (xy 78.506887 -474.219188)
			(xy 78.674166 -474.24689) (xy 78.839963 -474.282402) (xy 79.003913 -474.325647) (xy 79.165656 -474.376528)
			(xy 79.324836 -474.434935) (xy 79.481103 -474.500739) (xy 79.634115 -474.573795) (xy 79.783534 -474.653943)
			(xy 79.929032 -474.741006) (xy 80.070289 -474.834794) (xy 80.206995 -474.935099) (xy 80.338849 -475.041702)
			(xy 80.465562 -475.154368) (xy 80.586854 -475.27285) (xy 80.70246 -475.396886) (xy 80.812124 -475.526205)
			(xy 80.915607 -475.660522) (xy 81.01268 -475.799542) (xy 81.10313 -475.942959) (xy 81.186759 -476.090458)
			(xy 81.263382 -476.241715) (xy 81.332831 -476.396397) (xy 81.394953 -476.554164) (xy 81.449613 -476.71467)
			(xy 81.496688 -476.877561) (xy 81.536078 -477.04248) (xy 81.567693 -477.209063) (xy 81.591466 -477.376946)
			(xy 81.607344 -477.545758) (xy 81.615291 -477.715129) (xy 81.615788 -477.799908) (xy 81.615788 -478.799906)
			(xy 81.615291 -478.884685) (xy 81.607344 -479.054056) (xy 81.591466 -479.222868) (xy 81.567693 -479.390751)
			(xy 81.536078 -479.557334) (xy 81.496688 -479.722253) (xy 81.449613 -479.885144) (xy 81.394953 -480.04565)
			(xy 81.332831 -480.203417) (xy 81.263382 -480.358099) (xy 81.186759 -480.509356) (xy 81.10313 -480.656855)
			(xy 81.01268 -480.800272) (xy 80.915607 -480.939292) (xy 80.812124 -481.073609) (xy 80.70246 -481.202928)
			(xy 80.586854 -481.326964) (xy 80.465562 -481.445446) (xy 80.338849 -481.558112) (xy 80.206995 -481.664715)
			(xy 80.070289 -481.76502) (xy 79.929032 -481.858808) (xy 79.783534 -481.945871) (xy 79.634115 -482.026019)
			(xy 79.481103 -482.099075) (xy 79.324836 -482.164879) (xy 79.165656 -482.223286) (xy 79.003913 -482.274167)
			(xy 78.839963 -482.317412) (xy 78.674166 -482.352924) (xy 78.506887 -482.380626) (xy 78.338493 -482.400456)
			(xy 78.169355 -482.412372) (xy 77.999844 -482.416347) (xy 77.830333 -482.412372) (xy 77.661195 -482.400456)
			(xy 77.492801 -482.380626) (xy 77.325522 -482.352924) (xy 77.159725 -482.317412) (xy 76.995775 -482.274167)
			(xy 76.834032 -482.223286) (xy 76.674852 -482.164879) (xy 76.518585 -482.099075) (xy 76.365573 -482.026019)
			(xy 76.216154 -481.945871) (xy 76.070656 -481.858808) (xy 75.929399 -481.76502) (xy 75.792693 -481.664715)
			(xy 75.660839 -481.558112) (xy 75.534126 -481.445446) (xy 75.412834 -481.326964) (xy 75.297228 -481.202928)
			(xy 75.187564 -481.073609) (xy 75.084081 -480.939292) (xy 74.987008 -480.800272) (xy 74.896558 -480.656855)
			(xy 74.812929 -480.509356) (xy 74.736306 -480.358099) (xy 74.666857 -480.203417) (xy 74.604735 -480.04565)
			(xy 74.550075 -479.885144) (xy 74.503 -479.722253) (xy 74.46361 -479.557334) (xy 74.431995 -479.390751)
			(xy 74.408222 -479.222868) (xy 74.392344 -479.054056) (xy 74.384397 -478.884685) (xy 74.3839 -478.799906)
			(xy 17.863861 -478.799906) (xy 17.805913 -478.814766) (xy 17.60587 -478.857839) (xy 17.404302 -478.893093)
			(xy 17.201514 -478.920472) (xy 16.997814 -478.939937) (xy 16.793511 -478.951456) (xy 16.588914 -478.955013)
			(xy 16.384334 -478.950602) (xy 16.18008 -478.93823) (xy 15.976463 -478.917916) (xy 15.773792 -478.88969)
			(xy 15.572372 -478.853596) (xy 15.372511 -478.809688) (xy 15.17451 -478.758032) (xy 14.978671 -478.698707)
			(xy 14.78529 -478.631803) (xy 14.594659 -478.557422) (xy 14.407069 -478.475675) (xy 14.222804 -478.386687)
			(xy 14.042143 -478.290594) (xy 13.865359 -478.18754) (xy 13.692722 -478.077682) (xy 13.524492 -477.961186)
			(xy 13.360925 -477.838229) (xy 13.202269 -477.708998) (xy 13.048764 -477.573688) (xy 12.900643 -477.432505)
			(xy 12.75813 -477.285662) (xy 12.621443 -477.133383) (xy 12.490787 -476.975898) (xy 12.366361 -476.813445)
			(xy 12.248354 -476.646272) (xy 12.136945 -476.474632) (xy 12.032302 -476.298784) (xy 11.934584 -476.118996)
			(xy 11.84394 -475.93554) (xy 11.760506 -475.748694) (xy 11.684409 -475.558742) (xy 11.615765 -475.365972)
			(xy 11.554678 -475.170675) (xy 11.50124 -474.973148) (xy 11.455533 -474.77369) (xy 11.417625 -474.572604)
			(xy 11.387574 -474.370195) (xy 11.365426 -474.16677) (xy 11.351214 -473.962636) (xy 11.344959 -473.758104)
			(xy 1.016 -473.758104) (xy 1.016 -482.271578) (xy 1.047496 -482.354382) (xy 1.059942 -482.369876)
			(xy 1.077482 -482.39257) (xy 1.106268 -482.442179) (xy 1.127305 -482.495537) (xy 1.14012 -482.551442)
			(xy 1.144423 -482.608636) (xy 1.14012 -482.66583) (xy 1.127305 -482.721735) (xy 1.106268 -482.775093)
			(xy 1.077482 -482.824702) (xy 1.059942 -482.847396) (xy 1.047496 -482.86289) (xy 1.016 -482.945694)
			(xy 1.016 -486.99547) (xy 1.016504 -487.01881) (xy 1.024982 -487.064714) (xy 1.041699 -487.108297)
			(xy 1.066094 -487.148095) (xy 1.097346 -487.182768) (xy 1.134405 -487.211152) (xy 1.176024 -487.232291)
			(xy 1.220803 -487.245475) (xy 1.267237 -487.250259) (xy 1.313763 -487.246484) (xy 1.358818 -487.234276)
			(xy 1.400886 -487.214045) (xy 1.438552 -487.186473) (xy 1.47055 -487.152486) (xy 1.483614 -487.133138)
			(xy 1.51897 -487.079202) (xy 1.595424 -486.975326) (xy 1.678157 -486.876378) (xy 1.766854 -486.782738)
			(xy 1.861173 -486.694764) (xy 1.960754 -486.612795) (xy 2.065216 -486.537142) (xy 2.174158 -486.468097)
			(xy 2.287162 -486.405924) (xy 2.403796 -486.350861) (xy 2.523614 -486.303119) (xy 2.646155 -486.26288)
			(xy 2.770951 -486.2303) (xy 2.897523 -486.205502) (xy 3.025387 -486.188583) (xy 3.154053 -486.179606)
			(xy 3.283028 -486.178606) (xy 3.411818 -486.185586) (xy 3.539929 -486.200521) (xy 3.66687 -486.223353)
			(xy 3.792157 -486.253994) (xy 3.915307 -486.292328) (xy 4.03585 -486.338206) (xy 4.153324 -486.391454)
			(xy 4.267279 -486.451868) (xy 4.377278 -486.519215) (xy 4.482901 -486.593239) (xy 4.583741 -486.673655)
			(xy 4.679413 -486.760155) (xy 4.769551 -486.852408) (xy 4.853809 -486.950061) (xy 4.931864 -487.05274)
			(xy 5.003418 -487.16005) (xy 5.068196 -487.271582) (xy 5.12595 -487.386907) (xy 5.176459 -487.505585)
			(xy 5.219529 -487.62716) (xy 5.254996 -487.751166) (xy 5.282723 -487.87713) (xy 5.302604 -488.004567)
			(xy 5.314563 -488.13299) (xy 5.318555 -488.261907) (xy 5.318555 -488.261914) (xy 12.580624 -488.261914)
			(xy 12.584655 -488.132348) (xy 12.596734 -488.003284) (xy 12.616813 -487.87522) (xy 12.644815 -487.748653)
			(xy 12.680632 -487.62407) (xy 12.724124 -487.501956) (xy 12.775124 -487.382782) (xy 12.833435 -487.267009)
			(xy 12.89883 -487.155085) (xy 12.971057 -487.047443) (xy 13.049837 -486.9445) (xy 13.134864 -486.846654)
			(xy 13.225809 -486.754282) (xy 13.322321 -486.667744) (xy 13.424027 -486.587373) (xy 13.530533 -486.513481)
			(xy 13.641426 -486.446353) (xy 13.756278 -486.386249) (xy 13.874645 -486.333402) (xy 13.996068 -486.288015)
			(xy 14.120078 -486.250266) (xy 14.246195 -486.220299) (xy 14.373931 -486.19823) (xy 14.502792 -486.184146)
			(xy 14.632279 -486.1781) (xy 14.761892 -486.180116) (xy 14.891128 -486.190186) (xy 15.019489 -486.208271)
			(xy 15.146477 -486.234301) (xy 15.271601 -486.268176) (xy 15.394377 -486.309764) (xy 15.51433 -486.358905)
			(xy 15.630995 -486.415408) (xy 15.743923 -486.479055) (xy 15.852675 -486.549599) (xy 15.956831 -486.626768)
			(xy 16.055988 -486.710263) (xy 16.149762 -486.799761) (xy 16.237791 -486.894916) (xy 16.319734 -486.995359)
			(xy 16.395273 -487.100702) (xy 16.464118 -487.210538) (xy 16.526001 -487.324442) (xy 16.580682 -487.441972)
			(xy 16.627952 -487.562675) (xy 16.667625 -487.686083) (xy 16.69955 -487.811719) (xy 16.723602 -487.939096)
			(xy 16.739689 -488.067722) (xy 16.747748 -488.1971) (xy 16.748252 -488.261914) (xy 16.747748 -488.326728)
			(xy 16.739689 -488.456106) (xy 16.723602 -488.584732) (xy 16.69955 -488.712109) (xy 16.667625 -488.837745)
			(xy 16.627952 -488.961153) (xy 16.580682 -489.081856) (xy 16.526001 -489.199386) (xy 16.464118 -489.31329)
			(xy 16.395273 -489.423126) (xy 16.319734 -489.528469) (xy 16.237791 -489.628912) (xy 16.149762 -489.724067)
			(xy 16.055988 -489.813565) (xy 15.956831 -489.89706) (xy 15.852675 -489.974229) (xy 15.743923 -490.044773)
			(xy 15.630995 -490.10842) (xy 15.51433 -490.164923) (xy 15.394377 -490.214064) (xy 15.271601 -490.255652)
			(xy 15.146477 -490.289527) (xy 15.019489 -490.315557) (xy 14.891128 -490.333642) (xy 14.761892 -490.343712)
			(xy 14.632279 -490.345728) (xy 14.502792 -490.339682) (xy 14.373931 -490.325598) (xy 14.246195 -490.303529)
			(xy 14.120078 -490.273562) (xy 13.996068 -490.235813) (xy 13.874645 -490.190426) (xy 13.756278 -490.137579)
			(xy 13.641426 -490.077475) (xy 13.530533 -490.010347) (xy 13.424027 -489.936455) (xy 13.322321 -489.856084)
			(xy 13.225809 -489.769546) (xy 13.134864 -489.677174) (xy 13.049837 -489.579328) (xy 12.971057 -489.476385)
			(xy 12.89883 -489.368743) (xy 12.833435 -489.256819) (xy 12.775124 -489.141046) (xy 12.724124 -489.021872)
			(xy 12.680632 -488.899758) (xy 12.644815 -488.775175) (xy 12.616813 -488.648608) (xy 12.596734 -488.520544)
			(xy 12.584655 -488.39148) (xy 12.580624 -488.261914) (xy 5.318555 -488.261914) (xy 5.314564 -488.390824)
			(xy 5.302605 -488.519247) (xy 5.282724 -488.646684) (xy 5.254997 -488.772647) (xy 5.219531 -488.896654)
			(xy 5.176461 -489.018229) (xy 5.125953 -489.136906) (xy 5.068199 -489.252232) (xy 5.003422 -489.363764)
			(xy 4.931868 -489.471075) (xy 4.853813 -489.573754) (xy 4.769556 -489.671407) (xy 4.679418 -489.76366)
			(xy 4.583746 -489.850161) (xy 4.482906 -489.930577) (xy 4.377284 -490.004601) (xy 4.267285 -490.071949)
			(xy 4.15333 -490.132363) (xy 4.035857 -490.185611) (xy 3.915313 -490.23149) (xy 3.792163 -490.269824)
			(xy 3.666877 -490.300465) (xy 3.539935 -490.323298) (xy 3.411824 -490.338233) (xy 3.283035 -490.345214)
			(xy 3.15406 -490.344215) (xy 3.025394 -490.335238) (xy 2.89753 -490.318319) (xy 2.770957 -490.293522)
			(xy 2.646161 -490.260942) (xy 2.52362 -490.220704) (xy 2.403802 -490.172962) (xy 2.287168 -490.117899)
			(xy 2.174163 -490.055726) (xy 2.065222 -489.986682) (xy 1.96076 -489.91103) (xy 1.861178 -489.82906)
			(xy 1.766858 -489.741087) (xy 1.678162 -489.647447) (xy 1.595428 -489.5485) (xy 1.518974 -489.444623)
			(xy 1.483614 -489.39069) (xy 1.470543 -489.371347) (xy 1.438546 -489.337361) (xy 1.400881 -489.30979)
			(xy 1.358815 -489.289561) (xy 1.313761 -489.277353) (xy 1.267236 -489.273578) (xy 1.220804 -489.278362)
			(xy 1.176027 -489.291545) (xy 1.134409 -489.312684) (xy 1.097352 -489.341066) (xy 1.0661 -489.375739)
			(xy 1.041706 -489.415535) (xy 1.024989 -489.459117) (xy 1.016512 -489.505018) (xy 1.016 -489.528358)
			(xy 1.016 -494.971578) (xy 1.047496 -495.054382) (xy 1.059942 -495.069876) (xy 1.077482 -495.09257)
			(xy 1.106268 -495.142179) (xy 1.127305 -495.195537) (xy 1.14012 -495.251442) (xy 1.144423 -495.308636)
			(xy 1.14012 -495.36583) (xy 1.127305 -495.421735) (xy 1.106268 -495.475093) (xy 1.077482 -495.524702)
			(xy 1.059942 -495.547396) (xy 1.047496 -495.56289) (xy 1.016 -495.645694) (xy 1.016 -495.86007) (xy 39.818063 -495.86007)
			(xy 39.82207 -495.744046) (xy 39.834072 -495.628574) (xy 39.854012 -495.514206) (xy 39.881795 -495.401486)
			(xy 39.917289 -495.290952) (xy 39.960324 -495.183129) (xy 40.010695 -495.078532) (xy 40.068162 -494.97766)
			(xy 40.132452 -494.880993) (xy 40.203257 -494.788992) (xy 40.280241 -494.702095) (xy 40.363037 -494.620716)
			(xy 40.45125 -494.545243) (xy 40.54446 -494.476036) (xy 40.642223 -494.413424) (xy 40.744072 -494.357707)
			(xy 40.849522 -494.309149) (xy 40.958071 -494.267981) (xy 41.069202 -494.234401) (xy 41.182385 -494.208568)
			(xy 41.29708 -494.190605) (xy 41.412742 -494.180597) (xy 41.528818 -494.178594) (xy 41.644756 -494.184603)
			(xy 41.760003 -494.198596) (xy 41.874009 -494.220507) (xy 41.986233 -494.250232) (xy 42.096139 -494.287628)
			(xy 42.203202 -494.332517) (xy 42.306914 -494.384686) (xy 42.406779 -494.443886) (xy 42.502322 -494.509835)
			(xy 42.593088 -494.582218) (xy 42.678643 -494.660691) (xy 42.758581 -494.744879) (xy 42.83252 -494.834381)
			(xy 42.900108 -494.928772) (xy 42.961022 -495.0276) (xy 43.014974 -495.130396) (xy 43.061704 -495.236669)
			(xy 43.100992 -495.345913) (xy 43.132649 -495.457606) (xy 43.156525 -495.571218) (xy 43.172506 -495.686206)
			(xy 43.180515 -495.802023) (xy 43.181016 -495.86007) (xy 43.180515 -495.918117) (xy 43.172506 -496.033934)
			(xy 43.156525 -496.148922) (xy 43.132649 -496.262534) (xy 43.100992 -496.374227) (xy 43.061704 -496.483471)
			(xy 43.014974 -496.589744) (xy 42.961022 -496.69254) (xy 42.900108 -496.791368) (xy 42.83252 -496.885759)
			(xy 42.758581 -496.975261) (xy 42.678643 -497.059449) (xy 42.593088 -497.137922) (xy 42.502604 -497.21008)
			(xy 93.154506 -497.21008) (xy 93.158522 -497.09381) (xy 93.170549 -496.978095) (xy 93.190531 -496.863485)
			(xy 93.218373 -496.750526) (xy 93.253942 -496.639758) (xy 93.297068 -496.531707) (xy 93.347545 -496.426889)
			(xy 93.405134 -496.325804) (xy 93.46956 -496.228932) (xy 93.540515 -496.136736) (xy 93.617662 -496.049655)
			(xy 93.700633 -495.968104) (xy 93.789033 -495.892472) (xy 93.88244 -495.823118) (xy 93.980409 -495.760375)
			(xy 94.082473 -495.704539) (xy 94.188147 -495.655878) (xy 94.296926 -495.614624) (xy 94.408291 -495.580973)
			(xy 94.521714 -495.555085) (xy 94.636651 -495.537084) (xy 94.752557 -495.527055) (xy 94.868879 -495.525047)
			(xy 94.985062 -495.531069) (xy 95.100553 -495.545092) (xy 95.214801 -495.56705) (xy 95.327262 -495.596837)
			(xy 95.4374 -495.634312) (xy 95.54469 -495.679297) (xy 95.648621 -495.731576) (xy 95.748697 -495.790901)
			(xy 95.844443 -495.856989) (xy 95.9354 -495.929525) (xy 96.021136 -496.008164) (xy 96.101243 -496.09253)
			(xy 96.175339 -496.182222) (xy 96.243069 -496.276812) (xy 96.304113 -496.37585) (xy 96.358178 -496.478863)
			(xy 96.405008 -496.58536) (xy 96.444379 -496.694835) (xy 96.476103 -496.806765) (xy 96.500029 -496.920617)
			(xy 96.516043 -497.035849) (xy 96.52407 -497.151911) (xy 96.524572 -497.21008) (xy 96.52407 -497.268249)
			(xy 96.516043 -497.384311) (xy 96.500029 -497.499543) (xy 96.476103 -497.613395) (xy 96.444379 -497.725325)
			(xy 96.405008 -497.8348) (xy 96.358178 -497.941297) (xy 96.304113 -498.04431) (xy 96.243069 -498.143348)
			(xy 96.175339 -498.237938) (xy 96.101243 -498.32763) (xy 96.021136 -498.411996) (xy 95.9354 -498.490635)
			(xy 95.844443 -498.563171) (xy 95.748697 -498.629259) (xy 95.648621 -498.688584) (xy 95.54469 -498.740863)
			(xy 95.4374 -498.785848) (xy 95.327262 -498.823323) (xy 95.214801 -498.85311) (xy 95.100553 -498.875068)
			(xy 94.985062 -498.889091) (xy 94.868879 -498.895113) (xy 94.752557 -498.893105) (xy 94.636651 -498.883076)
			(xy 94.521714 -498.865075) (xy 94.408291 -498.839187) (xy 94.296926 -498.805536) (xy 94.188147 -498.764282)
			(xy 94.082473 -498.715621) (xy 93.980409 -498.659785) (xy 93.88244 -498.597042) (xy 93.789033 -498.527688)
			(xy 93.700633 -498.452056) (xy 93.617662 -498.370505) (xy 93.540515 -498.283424) (xy 93.46956 -498.191228)
			(xy 93.405134 -498.094356) (xy 93.347545 -497.993271) (xy 93.297068 -497.888453) (xy 93.253942 -497.780402)
			(xy 93.218373 -497.669634) (xy 93.190531 -497.556675) (xy 93.170549 -497.442065) (xy 93.158522 -497.32635)
			(xy 93.154506 -497.21008) (xy 42.502604 -497.21008) (xy 42.502322 -497.210305) (xy 42.406779 -497.276254)
			(xy 42.306914 -497.335454) (xy 42.203202 -497.387623) (xy 42.096139 -497.432512) (xy 41.986233 -497.469908)
			(xy 41.874009 -497.499633) (xy 41.760003 -497.521544) (xy 41.644756 -497.535537) (xy 41.528818 -497.541546)
			(xy 41.412742 -497.539543) (xy 41.29708 -497.529535) (xy 41.182385 -497.511572) (xy 41.069202 -497.485739)
			(xy 40.958071 -497.452159) (xy 40.849522 -497.410991) (xy 40.744072 -497.362433) (xy 40.642223 -497.306716)
			(xy 40.54446 -497.244104) (xy 40.45125 -497.174897) (xy 40.363037 -497.099424) (xy 40.280241 -497.018045)
			(xy 40.203257 -496.931148) (xy 40.132452 -496.839147) (xy 40.068162 -496.74248) (xy 40.010695 -496.641608)
			(xy 39.960324 -496.537011) (xy 39.917289 -496.429188) (xy 39.881795 -496.318654) (xy 39.854012 -496.205934)
			(xy 39.834072 -496.091566) (xy 39.82207 -495.976094) (xy 39.818063 -495.86007) (xy 1.016 -495.86007)
			(xy 1.016 -507.671578) (xy 1.047496 -507.754382) (xy 1.059942 -507.769876) (xy 1.077482 -507.79257)
			(xy 1.106268 -507.842179) (xy 1.127305 -507.895537) (xy 1.14012 -507.951442) (xy 1.144423 -508.008636)
			(xy 1.14012 -508.06583) (xy 1.127305 -508.121735) (xy 1.106268 -508.175093) (xy 1.077482 -508.224702)
			(xy 1.059942 -508.247396) (xy 1.047496 -508.26289) (xy 1.016 -508.345694) (xy 1.016 -508.96012) (xy 86.877404 -508.96012)
			(xy 86.881424 -508.769469) (xy 86.893478 -508.579156) (xy 86.913544 -508.389521) (xy 86.941587 -508.2009)
			(xy 86.977556 -508.01363) (xy 87.021388 -507.828042) (xy 87.073005 -507.644467) (xy 87.132315 -507.463231)
			(xy 87.199213 -507.284656) (xy 87.273579 -507.109061) (xy 87.355281 -506.936756) (xy 87.444175 -506.768049)
			(xy 87.540101 -506.603239) (xy 87.64289 -506.44262) (xy 87.752359 -506.286477) (xy 87.868313 -506.135088)
			(xy 87.990547 -505.988721) (xy 88.118841 -505.847637) (xy 88.252969 -505.712088) (xy 88.392693 -505.582313)
			(xy 88.537763 -505.458543) (xy 88.687921 -505.341) (xy 88.842902 -505.229891) (xy 89.002429 -505.125414)
			(xy 89.166218 -505.027755) (xy 89.333978 -504.937088) (xy 89.505412 -504.853574) (xy 89.680214 -504.777361)
			(xy 89.858073 -504.708585) (xy 90.038674 -504.647367) (xy 90.221694 -504.593818) (xy 90.40681 -504.548032)
			(xy 90.593691 -504.51009) (xy 90.782006 -504.480061) (xy 90.971419 -504.457996) (xy 91.161593 -504.443937)
			(xy 91.352192 -504.437907) (xy 91.542875 -504.439917) (xy 91.733304 -504.449964) (xy 91.92314 -504.46803)
			(xy 92.112046 -504.494083) (xy 92.299685 -504.528076) (xy 92.485725 -504.569949) (xy 92.669834 -504.619628)
			(xy 92.851685 -504.677024) (xy 93.030955 -504.742035) (xy 93.207325 -504.814546) (xy 93.380481 -504.894427)
			(xy 93.550116 -504.981537) (xy 93.715928 -505.075721) (xy 93.877622 -505.176812) (xy 94.03491 -505.284628)
			(xy 94.187513 -505.39898) (xy 94.335161 -505.519663) (xy 94.477589 -505.646464) (xy 94.614545 -505.779155)
			(xy 94.745786 -505.917503) (xy 94.871078 -506.06126) (xy 94.990198 -506.210171) (xy 95.102934 -506.363972)
			(xy 95.209087 -506.522388) (xy 95.308467 -506.685139) (xy 95.400897 -506.851934) (xy 95.486214 -507.022478)
			(xy 95.564266 -507.196466) (xy 95.634913 -507.373591) (xy 95.698031 -507.553536) (xy 95.753507 -507.735982)
			(xy 95.801242 -507.920605) (xy 95.841152 -508.107075) (xy 95.873165 -508.295063) (xy 95.897225 -508.484233)
			(xy 95.913288 -508.674249) (xy 95.921327 -508.864773) (xy 95.92183 -508.96012) (xy 95.921327 -509.055467)
			(xy 95.913288 -509.245991) (xy 95.897225 -509.436007) (xy 95.873165 -509.625177) (xy 95.841152 -509.813165)
			(xy 95.801242 -509.999635) (xy 95.753507 -510.184258) (xy 95.698031 -510.366704) (xy 95.634913 -510.546649)
			(xy 95.564266 -510.723774) (xy 95.486214 -510.897762) (xy 95.400897 -511.068306) (xy 95.308467 -511.235101)
			(xy 95.209087 -511.397852) (xy 95.102934 -511.556268) (xy 94.990198 -511.710069) (xy 94.871078 -511.85898)
			(xy 94.745786 -512.002737) (xy 94.614545 -512.141085) (xy 94.477589 -512.273776) (xy 94.335161 -512.400577)
			(xy 94.187513 -512.52126) (xy 94.03491 -512.635612) (xy 93.877622 -512.743428) (xy 93.715928 -512.844519)
			(xy 93.550116 -512.938703) (xy 93.380481 -513.025813) (xy 93.207325 -513.105694) (xy 93.030955 -513.178205)
			(xy 92.851685 -513.243216) (xy 92.669834 -513.300612) (xy 92.485725 -513.350291) (xy 92.299685 -513.392164)
			(xy 92.112046 -513.426157) (xy 91.92314 -513.45221) (xy 91.733304 -513.470276) (xy 91.542875 -513.480323)
			(xy 91.352192 -513.482333) (xy 91.161593 -513.476303) (xy 90.971419 -513.462244) (xy 90.782006 -513.440179)
			(xy 90.593691 -513.41015) (xy 90.40681 -513.372208) (xy 90.221694 -513.326422) (xy 90.038674 -513.272873)
			(xy 89.858073 -513.211655) (xy 89.680214 -513.142879) (xy 89.505412 -513.066666) (xy 89.333978 -512.983152)
			(xy 89.166218 -512.892485) (xy 89.002429 -512.794826) (xy 88.842902 -512.690349) (xy 88.687921 -512.57924)
			(xy 88.537763 -512.461697) (xy 88.392693 -512.337927) (xy 88.252969 -512.208152) (xy 88.118841 -512.072603)
			(xy 87.990547 -511.931519) (xy 87.868313 -511.785152) (xy 87.752359 -511.633763) (xy 87.64289 -511.47762)
			(xy 87.540101 -511.317001) (xy 87.444175 -511.152191) (xy 87.355281 -510.983484) (xy 87.273579 -510.811179)
			(xy 87.199213 -510.635584) (xy 87.132315 -510.457009) (xy 87.073005 -510.275773) (xy 87.021388 -510.092198)
			(xy 86.977556 -509.90661) (xy 86.941587 -509.71934) (xy 86.913544 -509.530719) (xy 86.893478 -509.341084)
			(xy 86.881424 -509.150771) (xy 86.877404 -508.96012) (xy 1.016 -508.96012) (xy 1.016 -513.50545)
			(xy 1.016504 -513.52879) (xy 1.024982 -513.574694) (xy 1.041699 -513.618277) (xy 1.066094 -513.658075)
			(xy 1.097346 -513.692748) (xy 1.134405 -513.721132) (xy 1.176024 -513.742271) (xy 1.220803 -513.755455)
			(xy 1.267237 -513.760239) (xy 1.313763 -513.756464) (xy 1.358818 -513.744256) (xy 1.400886 -513.724025)
			(xy 1.438552 -513.696453) (xy 1.47055 -513.662466) (xy 1.483614 -513.643118) (xy 1.51897 -513.589182)
			(xy 1.595424 -513.485306) (xy 1.678157 -513.386358) (xy 1.766854 -513.292718) (xy 1.861173 -513.204744)
			(xy 1.960754 -513.122775) (xy 2.065216 -513.047122) (xy 2.174158 -512.978077) (xy 2.287162 -512.915904)
			(xy 2.403796 -512.860841) (xy 2.523614 -512.813099) (xy 2.646155 -512.77286) (xy 2.770951 -512.74028)
			(xy 2.897523 -512.715482) (xy 3.025387 -512.698563) (xy 3.154053 -512.689586) (xy 3.283028 -512.688586)
			(xy 3.411818 -512.695566) (xy 3.539929 -512.710501) (xy 3.66687 -512.733333) (xy 3.792157 -512.763974)
			(xy 3.915307 -512.802308) (xy 4.03585 -512.848186) (xy 4.153324 -512.901434) (xy 4.267279 -512.961848)
			(xy 4.377278 -513.029195) (xy 4.482901 -513.103219) (xy 4.583741 -513.183635) (xy 4.679413 -513.270135)
			(xy 4.769551 -513.362388) (xy 4.853809 -513.460041) (xy 4.931864 -513.56272) (xy 5.003418 -513.67003)
			(xy 5.068196 -513.781562) (xy 5.12595 -513.896887) (xy 5.176459 -514.015565) (xy 5.219529 -514.13714)
			(xy 5.254996 -514.261146) (xy 5.282723 -514.38711) (xy 5.302604 -514.514547) (xy 5.314563 -514.64297)
			(xy 5.318555 -514.771887) (xy 5.318555 -514.771894) (xy 12.580624 -514.771894) (xy 12.584655 -514.642328)
			(xy 12.596734 -514.513264) (xy 12.616813 -514.3852) (xy 12.644815 -514.258633) (xy 12.680632 -514.13405)
			(xy 12.724124 -514.011936) (xy 12.775124 -513.892762) (xy 12.833435 -513.776989) (xy 12.89883 -513.665065)
			(xy 12.971057 -513.557423) (xy 13.049837 -513.45448) (xy 13.134864 -513.356634) (xy 13.225809 -513.264262)
			(xy 13.322321 -513.177724) (xy 13.424027 -513.097353) (xy 13.530533 -513.023461) (xy 13.641426 -512.956333)
			(xy 13.756278 -512.896229) (xy 13.874645 -512.843382) (xy 13.996068 -512.797995) (xy 14.120078 -512.760246)
			(xy 14.246195 -512.730279) (xy 14.373931 -512.70821) (xy 14.502792 -512.694126) (xy 14.632279 -512.68808)
			(xy 14.761892 -512.690096) (xy 14.891128 -512.700166) (xy 15.019489 -512.718251) (xy 15.146477 -512.744281)
			(xy 15.271601 -512.778156) (xy 15.394377 -512.819744) (xy 15.51433 -512.868885) (xy 15.630995 -512.925388)
			(xy 15.743923 -512.989035) (xy 15.852675 -513.059579) (xy 15.956831 -513.136748) (xy 16.055988 -513.220243)
			(xy 16.149762 -513.309741) (xy 16.237791 -513.404896) (xy 16.319734 -513.505339) (xy 16.395273 -513.610682)
			(xy 16.464118 -513.720518) (xy 16.526001 -513.834422) (xy 16.580682 -513.951952) (xy 16.627952 -514.072655)
			(xy 16.667625 -514.196063) (xy 16.69955 -514.321699) (xy 16.723602 -514.449076) (xy 16.739689 -514.577702)
			(xy 16.747748 -514.70708) (xy 16.748252 -514.771894) (xy 16.747748 -514.836708) (xy 16.739689 -514.966086)
			(xy 16.723602 -515.094712) (xy 16.69955 -515.222089) (xy 16.667625 -515.347725) (xy 16.627952 -515.471133)
			(xy 16.580682 -515.591836) (xy 16.526001 -515.709366) (xy 16.464118 -515.82327) (xy 16.395273 -515.933106)
			(xy 16.319734 -516.038449) (xy 16.237791 -516.138892) (xy 16.149762 -516.234047) (xy 16.055988 -516.323545)
			(xy 15.956831 -516.40704) (xy 15.852675 -516.484209) (xy 15.743923 -516.554753) (xy 15.630995 -516.6184)
			(xy 15.51433 -516.674903) (xy 15.394377 -516.724044) (xy 15.271601 -516.765632) (xy 15.146477 -516.799507)
			(xy 15.019489 -516.825537) (xy 14.891128 -516.843622) (xy 14.761892 -516.853692) (xy 14.632279 -516.855708)
			(xy 14.502792 -516.849662) (xy 14.373931 -516.835578) (xy 14.246195 -516.813509) (xy 14.120078 -516.783542)
			(xy 13.996068 -516.745793) (xy 13.874645 -516.700406) (xy 13.756278 -516.647559) (xy 13.641426 -516.587455)
			(xy 13.530533 -516.520327) (xy 13.424027 -516.446435) (xy 13.322321 -516.366064) (xy 13.225809 -516.279526)
			(xy 13.134864 -516.187154) (xy 13.049837 -516.089308) (xy 12.971057 -515.986365) (xy 12.89883 -515.878723)
			(xy 12.833435 -515.766799) (xy 12.775124 -515.651026) (xy 12.724124 -515.531852) (xy 12.680632 -515.409738)
			(xy 12.644815 -515.285155) (xy 12.616813 -515.158588) (xy 12.596734 -515.030524) (xy 12.584655 -514.90146)
			(xy 12.580624 -514.771894) (xy 5.318555 -514.771894) (xy 5.314564 -514.900804) (xy 5.302605 -515.029227)
			(xy 5.282724 -515.156664) (xy 5.254997 -515.282627) (xy 5.219531 -515.406634) (xy 5.176461 -515.528209)
			(xy 5.125953 -515.646886) (xy 5.068199 -515.762212) (xy 5.003422 -515.873744) (xy 4.931868 -515.981055)
			(xy 4.853813 -516.083734) (xy 4.769556 -516.181387) (xy 4.679418 -516.27364) (xy 4.583746 -516.360141)
			(xy 4.482906 -516.440557) (xy 4.377284 -516.514581) (xy 4.267285 -516.581929) (xy 4.15333 -516.642343)
			(xy 4.035857 -516.695591) (xy 3.915313 -516.74147) (xy 3.792163 -516.779804) (xy 3.666877 -516.810445)
			(xy 3.539935 -516.833278) (xy 3.411824 -516.848213) (xy 3.283035 -516.855194) (xy 3.15406 -516.854195)
			(xy 3.025394 -516.845218) (xy 2.89753 -516.828299) (xy 2.770957 -516.803502) (xy 2.646161 -516.770922)
			(xy 2.52362 -516.730684) (xy 2.403802 -516.682942) (xy 2.287168 -516.627879) (xy 2.174163 -516.565706)
			(xy 2.065222 -516.496662) (xy 1.96076 -516.42101) (xy 1.861178 -516.33904) (xy 1.766858 -516.251067)
			(xy 1.678162 -516.157427) (xy 1.595428 -516.05848) (xy 1.518974 -515.954603) (xy 1.483614 -515.90067)
			(xy 1.470542 -515.881328) (xy 1.438544 -515.847345) (xy 1.400878 -515.819776) (xy 1.358811 -515.799548)
			(xy 1.313758 -515.787342) (xy 1.267234 -515.783567) (xy 1.220802 -515.788352) (xy 1.176025 -515.801534)
			(xy 1.134408 -515.822671) (xy 1.09735 -515.851053) (xy 1.066098 -515.885724) (xy 1.041702 -515.925518)
			(xy 1.024983 -515.969098) (xy 1.016503 -516.014999) (xy 1.016 -516.038338) (xy 1.016 -519.049762)
			(xy 72.864987 -519.049762) (xy 72.868996 -518.846891) (xy 72.881016 -518.644337) (xy 72.90103 -518.442416)
			(xy 72.929005 -518.241443) (xy 72.964898 -518.041733) (xy 73.008652 -517.843596) (xy 73.060201 -517.647343)
			(xy 73.119462 -517.453279) (xy 73.186344 -517.261708) (xy 73.260742 -517.072929) (xy 73.34254 -516.887236)
			(xy 73.43161 -516.70492) (xy 73.527813 -516.526265) (xy 73.631 -516.351551) (xy 73.741008 -516.181049)
			(xy 73.857666 -516.015026) (xy 73.980792 -515.853742) (xy 74.110194 -515.697448) (xy 74.245669 -515.546388)
			(xy 74.387006 -515.400798) (xy 74.533985 -515.260906) (xy 74.686376 -515.12693) (xy 74.843941 -514.999078)
			(xy 75.006434 -514.877552) (xy 75.173601 -514.762539) (xy 75.345181 -514.654221) (xy 75.520906 -514.552766)
			(xy 75.700503 -514.458332) (xy 75.88369 -514.371067) (xy 76.070182 -514.291108) (xy 76.259687 -514.218579)
			(xy 76.451909 -514.153593) (xy 76.646549 -514.096251) (xy 76.843302 -514.046644) (xy 77.041861 -514.004849)
			(xy 77.241917 -513.970931) (xy 77.443156 -513.944943) (xy 77.645265 -513.926925) (xy 77.847928 -513.916906)
			(xy 78.050828 -513.914902) (xy 78.253649 -513.920914) (xy 78.456075 -513.934935) (xy 78.657788 -513.956943)
			(xy 78.858475 -513.986902) (xy 79.057821 -514.024766) (xy 79.255516 -514.070476) (xy 79.45125 -514.12396)
			(xy 79.644719 -514.185136) (xy 79.83562 -514.253907) (xy 80.023655 -514.330167) (xy 80.208531 -514.413795)
			(xy 80.389958 -514.504662) (xy 80.567654 -514.602625) (xy 80.74134 -514.707533) (xy 80.910747 -514.81922)
			(xy 81.075609 -514.937512) (xy 81.235669 -515.062226) (xy 81.390677 -515.193165) (xy 81.540391 -515.330126)
			(xy 81.684577 -515.472895) (xy 81.823011 -515.621249) (xy 81.955475 -515.774956) (xy 82.081764 -515.933776)
			(xy 82.201679 -516.097461) (xy 82.315035 -516.265756) (xy 82.421653 -516.438398) (xy 82.521367 -516.615118)
			(xy 82.614022 -516.795638) (xy 82.699472 -516.979678) (xy 82.777586 -517.166951) (xy 82.848239 -517.357163)
			(xy 82.911323 -517.550018) (xy 82.966739 -517.745215) (xy 83.0144 -517.942448) (xy 83.054231 -518.141411)
			(xy 83.086171 -518.341792) (xy 83.11017 -518.543278) (xy 83.12619 -518.745555) (xy 83.134207 -518.948307)
			(xy 83.134708 -519.049762) (xy 83.134207 -519.151217) (xy 83.12619 -519.353969) (xy 83.11017 -519.556246)
			(xy 83.086171 -519.757732) (xy 83.054231 -519.958113) (xy 83.0144 -520.157076) (xy 82.966739 -520.354309)
			(xy 82.911323 -520.549506) (xy 82.848239 -520.742361) (xy 82.777586 -520.932573) (xy 82.699472 -521.119846)
			(xy 82.614022 -521.303886) (xy 82.521367 -521.484406) (xy 82.421653 -521.661126) (xy 82.315035 -521.833768)
			(xy 82.201679 -522.002063) (xy 82.081764 -522.165748) (xy 81.955475 -522.324568) (xy 81.823011 -522.478275)
			(xy 81.684577 -522.626629) (xy 81.540391 -522.769398) (xy 81.390677 -522.906359) (xy 81.235669 -523.037298)
			(xy 81.075609 -523.162012) (xy 80.910747 -523.280304) (xy 80.74134 -523.391991) (xy 80.567654 -523.496899)
			(xy 80.389958 -523.594862) (xy 80.208531 -523.685729) (xy 80.023655 -523.769357) (xy 79.83562 -523.845617)
			(xy 79.644719 -523.914388) (xy 79.45125 -523.975564) (xy 79.255516 -524.029048) (xy 79.057821 -524.074758)
			(xy 78.858475 -524.112622) (xy 78.657788 -524.142581) (xy 78.456075 -524.164589) (xy 78.253649 -524.17861)
			(xy 78.050828 -524.184622) (xy 77.847928 -524.182618) (xy 77.645265 -524.172599) (xy 77.443156 -524.154581)
			(xy 77.241917 -524.128593) (xy 77.041861 -524.094675) (xy 76.843302 -524.05288) (xy 76.646549 -524.003273)
			(xy 76.451909 -523.945931) (xy 76.259687 -523.880945) (xy 76.070182 -523.808416) (xy 75.88369 -523.728457)
			(xy 75.700503 -523.641192) (xy 75.520906 -523.546758) (xy 75.345181 -523.445303) (xy 75.173601 -523.336985)
			(xy 75.006434 -523.221972) (xy 74.843941 -523.100446) (xy 74.686376 -522.972594) (xy 74.533985 -522.838618)
			(xy 74.387006 -522.698726) (xy 74.245669 -522.553136) (xy 74.110194 -522.402076) (xy 73.980792 -522.245782)
			(xy 73.857666 -522.084498) (xy 73.741008 -521.918475) (xy 73.631 -521.747973) (xy 73.527813 -521.573259)
			(xy 73.43161 -521.394604) (xy 73.34254 -521.212288) (xy 73.260742 -521.026595) (xy 73.186344 -520.837816)
			(xy 73.119462 -520.646245) (xy 73.060201 -520.452181) (xy 73.008652 -520.255928) (xy 72.964898 -520.057791)
			(xy 72.929005 -519.858081) (xy 72.90103 -519.657108) (xy 72.881016 -519.455187) (xy 72.868996 -519.252633)
			(xy 72.864987 -519.049762) (xy 1.016 -519.049762) (xy 1.016 -520.371578) (xy 1.047496 -520.454382)
			(xy 1.059942 -520.469876) (xy 1.077482 -520.49257) (xy 1.106268 -520.542179) (xy 1.127305 -520.595537)
			(xy 1.14012 -520.651442) (xy 1.144423 -520.708636) (xy 1.14012 -520.76583) (xy 1.127305 -520.821735)
			(xy 1.106268 -520.875093) (xy 1.077482 -520.924702) (xy 1.059942 -520.947396) (xy 1.047496 -520.96289)
			(xy 1.016 -521.045694) (xy 1.016 -524.500094) (xy 1.016496 -524.531776) (xy 1.024766 -524.594598)
			(xy 1.041166 -524.655803) (xy 1.065414 -524.714344) (xy 1.097096 -524.769219) (xy 1.13567 -524.819489)
			(xy 1.180475 -524.864294) (xy 1.230745 -524.902868) (xy 1.28562 -524.93455) (xy 1.344161 -524.958798)
			(xy 1.405366 -524.975198) (xy 1.468188 -524.983468) (xy 1.49987 -524.983964) (xy 6.478778 -524.983964)
			(xy 6.494104 -524.9835) (xy 6.523871 -524.976184) (xy 6.551041 -524.961993) (xy 6.562852 -524.952214)
			(xy 6.58388 -524.934272) (xy 6.630136 -524.904011) (xy 6.680275 -524.880743) (xy 6.733248 -524.864955)
			(xy 6.787944 -524.856977) (xy 6.84322 -524.856977) (xy 6.897916 -524.864955) (xy 6.950889 -524.880743)
			(xy 7.001028 -524.904011) (xy 7.047284 -524.934272) (xy 7.068312 -524.952214) (xy 7.080084 -524.962052)
			(xy 7.10726 -524.976271) (xy 7.13705 -524.98357) (xy 7.152386 -524.983964) (xy 19.178778 -524.983964)
			(xy 19.194104 -524.9835) (xy 19.223871 -524.976184) (xy 19.251041 -524.961993) (xy 19.262852 -524.952214)
			(xy 19.28388 -524.934272) (xy 19.330136 -524.904011) (xy 19.380275 -524.880743) (xy 19.433248 -524.864955)
			(xy 19.487944 -524.856977) (xy 19.54322 -524.856977) (xy 19.597916 -524.864955) (xy 19.650889 -524.880743)
			(xy 19.701028 -524.904011) (xy 19.747284 -524.934272) (xy 19.768312 -524.952214) (xy 19.780084 -524.962052)
			(xy 19.80726 -524.976271) (xy 19.83705 -524.98357) (xy 19.852386 -524.983964) (xy 23.50008 -524.983964)
			(xy 23.570659 -524.984449) (xy 23.711596 -524.992364) (xy 23.851867 -525.008169) (xy 23.991032 -525.031814)
			(xy 24.128651 -525.063226) (xy 24.264293 -525.102306) (xy 24.397529 -525.14893) (xy 24.527942 -525.202952)
			(xy 24.65512 -525.264202) (xy 24.778663 -525.332488) (xy 24.898183 -525.407593) (xy 25.013303 -525.489282)
			(xy 25.123662 -525.577298) (xy 25.228911 -525.671364) (xy 25.32872 -525.771184) (xy 25.422775 -525.876443)
			(xy 25.510779 -525.986811) (xy 25.592456 -526.10194) (xy 25.667549 -526.221468) (xy 25.735821 -526.345018)
			(xy 25.797057 -526.472203) (xy 25.851065 -526.602621) (xy 25.897675 -526.735863) (xy 25.93674 -526.871508)
			(xy 25.968138 -527.009131) (xy 25.991769 -527.148298) (xy 26.007559 -527.288571) (xy 26.015458 -527.429509)
			(xy 26.01595 -527.500088) (xy 26.01595 -528.500086) (xy 26.016486 -528.531772) (xy 26.024792 -528.594597)
			(xy 26.041223 -528.655801) (xy 26.065499 -528.714339) (xy 26.097206 -528.769209) (xy 26.135801 -528.819472)
			(xy 26.180623 -528.864271) (xy 26.230908 -528.902839) (xy 26.285794 -528.934516) (xy 26.344345 -528.958761)
			(xy 26.405558 -528.975159) (xy 26.468388 -528.983431) (xy 26.500074 -528.983956) (xy 27.598878 -528.983956)
		)
		(stroke
			(width 0)
			(type solid)
		)
		(fill yes)
		(layer "In3.Cu")
		(net "P12V")
	)
	(gr_arc
		(start 1.500124 -3.999992)
		(mid 0.439376 -4.439368)
		(end 0 -5.500116)
		(stroke
			(width 2.032)
			(type default)
		)
		(layer "In3.Cu")
	)
	(gr_line
		(start 1.500124 -3.999992)
		(end 23.50008 -3.999992)
		(stroke
			(width 2.032)
			(type default)
		)
		(layer "In3.Cu")
	)
	(gr_line
		(start 16.578834 -384.960876)
		(end 16.578834 -384.927094)
		(stroke
			(width 2.54)
			(type default)
		)
		(layer "In3.Cu")
	)
	(gr_line
		(start 16.578834 -384.927094)
		(end 16.64716 -384.858768)
		(stroke
			(width 2.54)
			(type default)
		)
		(layer "In3.Cu")
	)
	(gr_line
		(start 16.578834 -29.360876)
		(end 16.578834 -29.327094)
		(stroke
			(width 2.54)
			(type default)
		)
		(layer "In3.Cu")
	)
	(gr_line
		(start 16.578834 -29.327094)
		(end 16.64716 -29.258768)
		(stroke
			(width 2.54)
			(type default)
		)
		(layer "In3.Cu")
	)
	(gr_line
		(start 16.579088 -473.860876)
		(end 16.579088 -473.827094)
		(stroke
			(width 2.54)
			(type default)
		)
		(layer "In3.Cu")
	)
	(gr_line
		(start 16.579088 -473.827094)
		(end 16.647414 -473.758768)
		(stroke
			(width 2.54)
			(type default)
		)
		(layer "In3.Cu")
	)
	(gr_line
		(start 16.579088 -296.060876)
		(end 16.579088 -296.027094)
		(stroke
			(width 2.54)
			(type default)
		)
		(layer "In3.Cu")
	)
	(gr_line
		(start 16.579088 -296.027094)
		(end 16.647414 -295.958768)
		(stroke
			(width 2.54)
			(type default)
		)
		(layer "In3.Cu")
	)
	(gr_line
		(start 16.579088 -207.160876)
		(end 16.579088 -207.127094)
		(stroke
			(width 2.54)
			(type default)
		)
		(layer "In3.Cu")
	)
	(gr_line
		(start 16.579088 -207.127094)
		(end 16.647414 -207.058768)
		(stroke
			(width 2.54)
			(type default)
		)
		(layer "In3.Cu")
	)
	(gr_line
		(start 16.579088 -118.260876)
		(end 16.579088 -118.227094)
		(stroke
			(width 2.54)
			(type default)
		)
		(layer "In3.Cu")
	)
	(gr_line
		(start 16.579088 -118.227094)
		(end 16.647414 -118.158768)
		(stroke
			(width 2.54)
			(type default)
		)
		(layer "In3.Cu")
	)
	(gr_circle
		(center 16.599662 -384.800094)
		(end 19.329908 -384.800094)
		(stroke
			(width 3.81)
			(type default)
		)
		(fill no)
		(layer "In3.Cu")
	)
	(gr_circle
		(center 16.599662 -384.800094)
		(end 21.480272 -384.800094)
		(stroke
			(width 0.508)
			(type default)
		)
		(fill no)
		(layer "In3.Cu")
	)
	(gr_circle
		(center 16.599662 -29.200094)
		(end 19.329908 -29.200094)
		(stroke
			(width 3.81)
			(type default)
		)
		(fill no)
		(layer "In3.Cu")
	)
	(gr_circle
		(center 16.599662 -29.200094)
		(end 21.480272 -29.200094)
		(stroke
			(width 0.508)
			(type default)
		)
		(fill no)
		(layer "In3.Cu")
	)
	(gr_circle
		(center 16.599916 -473.700094)
		(end 19.330162 -473.700094)
		(stroke
			(width 3.81)
			(type default)
		)
		(fill no)
		(layer "In3.Cu")
	)
	(gr_circle
		(center 16.599916 -473.700094)
		(end 21.480526 -473.700094)
		(stroke
			(width 0.508)
			(type default)
		)
		(fill no)
		(layer "In3.Cu")
	)
	(gr_circle
		(center 16.599916 -473.69984)
		(end 21.791168 -473.69984)
		(stroke
			(width 0.127)
			(type default)
		)
		(fill no)
		(layer "In3.Cu")
	)
	(gr_circle
		(center 16.599916 -384.79984)
		(end 21.791422 -384.79984)
		(stroke
			(width 0.127)
			(type default)
		)
		(fill no)
		(layer "In3.Cu")
	)
	(gr_circle
		(center 16.599916 -295.900094)
		(end 19.330162 -295.900094)
		(stroke
			(width 3.81)
			(type default)
		)
		(fill no)
		(layer "In3.Cu")
	)
	(gr_circle
		(center 16.599916 -295.900094)
		(end 21.480526 -295.900094)
		(stroke
			(width 0.508)
			(type default)
		)
		(fill no)
		(layer "In3.Cu")
	)
	(gr_circle
		(center 16.599916 -295.89984)
		(end 21.791422 -295.89984)
		(stroke
			(width 0.127)
			(type default)
		)
		(fill no)
		(layer "In3.Cu")
	)
	(gr_circle
		(center 16.599916 -207.000094)
		(end 19.330162 -207.000094)
		(stroke
			(width 3.81)
			(type default)
		)
		(fill no)
		(layer "In3.Cu")
	)
	(gr_circle
		(center 16.599916 -207.000094)
		(end 21.480526 -207.000094)
		(stroke
			(width 0.508)
			(type default)
		)
		(fill no)
		(layer "In3.Cu")
	)
	(gr_circle
		(center 16.599916 -206.99984)
		(end 21.791422 -206.99984)
		(stroke
			(width 0.127)
			(type default)
		)
		(fill no)
		(layer "In3.Cu")
	)
	(gr_circle
		(center 16.599916 -118.100094)
		(end 19.330162 -118.100094)
		(stroke
			(width 3.81)
			(type default)
		)
		(fill no)
		(layer "In3.Cu")
	)
	(gr_circle
		(center 16.599916 -118.100094)
		(end 21.480526 -118.100094)
		(stroke
			(width 0.508)
			(type default)
		)
		(fill no)
		(layer "In3.Cu")
	)
	(gr_circle
		(center 16.599916 -118.09984)
		(end 21.791422 -118.09984)
		(stroke
			(width 0.127)
			(type default)
		)
		(fill no)
		(layer "In3.Cu")
	)
	(gr_circle
		(center 16.599916 -29.19984)
		(end 21.79447 -29.19984)
		(stroke
			(width 0.127)
			(type default)
		)
		(fill no)
		(layer "In3.Cu")
	)
	(gr_line
		(start 23.50008 -525.999964)
		(end 1.500124 -525.999964)
		(stroke
			(width 2.032)
			(type default)
		)
		(layer "In3.Cu")
	)
	(gr_arc
		(start 23.50008 -3.999992)
		(mid 24.560648 -3.56069)
		(end 24.99995 -2.500122)
		(stroke
			(width 2.032)
			(type default)
		)
		(layer "In3.Cu")
	)
	(gr_line
		(start 24.99995 -528.500086)
		(end 24.99995 -527.500088)
		(stroke
			(width 2.032)
			(type default)
		)
		(layer "In3.Cu")
	)
	(gr_arc
		(start 24.99995 -528.500086)
		(mid 25.439426 -529.560658)
		(end 26.500074 -529.999956)
		(stroke
			(width 2.032)
			(type default)
		)
		(layer "In3.Cu")
	)
	(gr_arc
		(start 24.99995 -527.500088)
		(mid 24.560738 -526.439356)
		(end 23.50008 -525.999964)
		(stroke
			(width 2.032)
			(type default)
		)
		(layer "In3.Cu")
	)
	(gr_line
		(start 24.99995 -2.500122)
		(end 24.99995 -1.500124)
		(stroke
			(width 2.032)
			(type default)
		)
		(layer "In3.Cu")
	)
	(gr_arc
		(start 26.500074 0)
		(mid 25.439325 -0.439375)
		(end 24.99995 -1.500124)
		(stroke
			(width 2.032)
			(type default)
		)
		(layer "In3.Cu")
	)
	(gr_line
		(start 26.500074 0)
		(end 101.000052 0)
		(stroke
			(width 2.032)
			(type default)
		)
		(layer "In3.Cu")
	)
	(gr_arc
		(start 75.3999 -478.799906)
		(mid 77.999844 -481.39985)
		(end 80.599788 -478.799906)
		(stroke
			(width 2.032)
			(type default)
		)
		(layer "In3.Cu")
	)
	(gr_line
		(start 75.3999 -477.799908)
		(end 75.3999 -478.799906)
		(stroke
			(width 2.032)
			(type default)
		)
		(layer "In3.Cu")
	)
	(gr_line
		(start 77.051154 -479.403918)
		(end 77.051154 -477.167956)
		(stroke
			(width 2.032)
			(type default)
		)
		(layer "In3.Cu")
	)
	(gr_line
		(start 77.051154 -477.167956)
		(end 77.347826 -476.871284)
		(stroke
			(width 2.032)
			(type default)
		)
		(layer "In3.Cu")
	)
	(gr_line
		(start 77.324966 -480.156774)
		(end 77.324966 -479.837496)
		(stroke
			(width 2.032)
			(type default)
		)
		(layer "In3.Cu")
	)
	(gr_line
		(start 77.324966 -479.837496)
		(end 77.89545 -479.267012)
		(stroke
			(width 2.032)
			(type default)
		)
		(layer "In3.Cu")
	)
	(gr_line
		(start 77.347826 -476.871284)
		(end 78.922118 -476.871284)
		(stroke
			(width 2.032)
			(type default)
		)
		(layer "In3.Cu")
	)
	(gr_line
		(start 77.781404 -478.673668)
		(end 77.051154 -479.403918)
		(stroke
			(width 2.032)
			(type default)
		)
		(layer "In3.Cu")
	)
	(gr_line
		(start 77.89545 -479.267012)
		(end 78.123542 -479.267012)
		(stroke
			(width 2.032)
			(type default)
		)
		(layer "In3.Cu")
	)
	(gr_line
		(start 77.979016 -32.460438)
		(end 77.979016 -32.426656)
		(stroke
			(width 2.54)
			(type default)
		)
		(layer "In3.Cu")
	)
	(gr_line
		(start 77.979016 -32.426656)
		(end 78.047342 -32.35833)
		(stroke
			(width 2.54)
			(type default)
		)
		(layer "In3.Cu")
	)
	(gr_line
		(start 77.97927 -519.210544)
		(end 77.97927 -519.176762)
		(stroke
			(width 2.54)
			(type default)
		)
		(layer "In3.Cu")
	)
	(gr_line
		(start 77.97927 -519.176762)
		(end 78.047596 -519.108436)
		(stroke
			(width 2.54)
			(type default)
		)
		(layer "In3.Cu")
	)
	(gr_line
		(start 77.97927 -430.310544)
		(end 77.97927 -430.276762)
		(stroke
			(width 2.54)
			(type default)
		)
		(layer "In3.Cu")
	)
	(gr_line
		(start 77.97927 -430.276762)
		(end 78.047596 -430.208436)
		(stroke
			(width 2.54)
			(type default)
		)
		(layer "In3.Cu")
	)
	(gr_line
		(start 77.97927 -341.410544)
		(end 77.97927 -341.376762)
		(stroke
			(width 2.54)
			(type default)
		)
		(layer "In3.Cu")
	)
	(gr_line
		(start 77.97927 -341.376762)
		(end 78.047596 -341.308436)
		(stroke
			(width 2.54)
			(type default)
		)
		(layer "In3.Cu")
	)
	(gr_line
		(start 77.97927 -210.260438)
		(end 77.97927 -210.226656)
		(stroke
			(width 2.54)
			(type default)
		)
		(layer "In3.Cu")
	)
	(gr_line
		(start 77.97927 -210.226656)
		(end 78.047596 -210.15833)
		(stroke
			(width 2.54)
			(type default)
		)
		(layer "In3.Cu")
	)
	(gr_line
		(start 77.979524 -121.360438)
		(end 77.979524 -121.326656)
		(stroke
			(width 2.54)
			(type default)
		)
		(layer "In3.Cu")
	)
	(gr_line
		(start 77.979524 -121.326656)
		(end 78.04785 -121.25833)
		(stroke
			(width 2.54)
			(type default)
		)
		(layer "In3.Cu")
	)
	(gr_line
		(start 77.98689 -480.156774)
		(end 77.324966 -480.156774)
		(stroke
			(width 2.032)
			(type default)
		)
		(layer "In3.Cu")
	)
	(gr_circle
		(center 77.999844 -32.299656)
		(end 80.73009 -32.299656)
		(stroke
			(width 3.81)
			(type default)
		)
		(fill no)
		(layer "In3.Cu")
	)
	(gr_circle
		(center 77.999844 -32.299656)
		(end 82.880454 -32.299656)
		(stroke
			(width 0.508)
			(type default)
		)
		(fill no)
		(layer "In3.Cu")
	)
	(gr_circle
		(center 78.000098 -519.049762)
		(end 80.730344 -519.049762)
		(stroke
			(width 3.81)
			(type default)
		)
		(fill no)
		(layer "In3.Cu")
	)
	(gr_circle
		(center 78.000098 -519.049762)
		(end 82.880708 -519.049762)
		(stroke
			(width 0.508)
			(type default)
		)
		(fill no)
		(layer "In3.Cu")
	)
	(gr_circle
		(center 78.000098 -430.149762)
		(end 80.730344 -430.149762)
		(stroke
			(width 3.81)
			(type default)
		)
		(fill no)
		(layer "In3.Cu")
	)
	(gr_circle
		(center 78.000098 -430.149762)
		(end 82.880708 -430.149762)
		(stroke
			(width 0.508)
			(type default)
		)
		(fill no)
		(layer "In3.Cu")
	)
	(gr_circle
		(center 78.000098 -341.249762)
		(end 80.730344 -341.249762)
		(stroke
			(width 3.81)
			(type default)
		)
		(fill no)
		(layer "In3.Cu")
	)
	(gr_circle
		(center 78.000098 -341.249762)
		(end 82.880708 -341.249762)
		(stroke
			(width 0.508)
			(type default)
		)
		(fill no)
		(layer "In3.Cu")
	)
	(gr_circle
		(center 78.000098 -210.099656)
		(end 80.730344 -210.099656)
		(stroke
			(width 3.81)
			(type default)
		)
		(fill no)
		(layer "In3.Cu")
	)
	(gr_circle
		(center 78.000098 -210.099656)
		(end 82.880708 -210.099656)
		(stroke
			(width 0.508)
			(type default)
		)
		(fill no)
		(layer "In3.Cu")
	)
	(gr_circle
		(center 78.000352 -121.199656)
		(end 80.730598 -121.199656)
		(stroke
			(width 3.81)
			(type default)
		)
		(fill no)
		(layer "In3.Cu")
	)
	(gr_circle
		(center 78.000352 -121.199656)
		(end 82.880962 -121.199656)
		(stroke
			(width 0.508)
			(type default)
		)
		(fill no)
		(layer "In3.Cu")
	)
	(gr_line
		(start 78.123542 -479.267012)
		(end 78.169262 -479.312732)
		(stroke
			(width 2.032)
			(type default)
		)
		(layer "In3.Cu")
	)
	(gr_line
		(start 78.123542 -478.673668)
		(end 77.781404 -478.673668)
		(stroke
			(width 2.032)
			(type default)
		)
		(layer "In3.Cu")
	)
	(gr_line
		(start 78.123542 -478.673668)
		(end 79.332836 -478.673668)
		(stroke
			(width 2.032)
			(type default)
		)
		(layer "In3.Cu")
	)
	(gr_line
		(start 78.922118 -477.875092)
		(end 78.123542 -478.673668)
		(stroke
			(width 2.032)
			(type default)
		)
		(layer "In3.Cu")
	)
	(gr_line
		(start 78.922118 -476.871284)
		(end 78.922118 -477.875092)
		(stroke
			(width 2.032)
			(type default)
		)
		(layer "In3.Cu")
	)
	(gr_line
		(start 79.332836 -478.673668)
		(end 79.424022 -478.582482)
		(stroke
			(width 2.032)
			(type default)
		)
		(layer "In3.Cu")
	)
	(gr_line
		(start 79.424022 -478.719642)
		(end 77.98689 -480.156774)
		(stroke
			(width 2.032)
			(type default)
		)
		(layer "In3.Cu")
	)
	(gr_line
		(start 79.424022 -478.582482)
		(end 79.424022 -478.719642)
		(stroke
			(width 2.032)
			(type default)
		)
		(layer "In3.Cu")
	)
	(gr_line
		(start 80.599788 -478.799906)
		(end 80.599788 -477.799908)
		(stroke
			(width 2.032)
			(type default)
		)
		(layer "In3.Cu")
	)
	(gr_arc
		(start 80.599788 -477.799908)
		(mid 77.999844 -475.199964)
		(end 75.3999 -477.799908)
		(stroke
			(width 2.032)
			(type default)
		)
		(layer "In3.Cu")
	)
	(gr_line
		(start 101.000052 -529.999956)
		(end 26.500074 -529.999956)
		(stroke
			(width 2.032)
			(type default)
		)
		(layer "In3.Cu")
	)
	(gr_arc
		(start 101.000052 -529.999956)
		(mid 102.41428 -529.414185)
		(end 103.000048 -527.99996)
		(stroke
			(width 2.032)
			(type default)
		)
		(layer "In3.Cu")
	)
	(gr_arc
		(start 103.000048 -1.999996)
		(mid 102.414258 -0.585805)
		(end 101.000052 0)
		(stroke
			(width 2.032)
			(type default)
		)
		(layer "In3.Cu")
	)
	(gr_line
		(start 103.000048 -1.999996)
		(end 103.000048 -527.99996)
		(stroke
			(width 2.032)
			(type default)
		)
		(layer "In3.Cu")
	)
	(gr_line
		(start 0 -524.500094)
		(end 0 -5.500116)
		(stroke
			(width 0.2)
			(type default)
		)
		(layer "In4.Cu")
	)
	(gr_line
		(start 0 -524.500094)
		(end 0 -5.500116)
		(stroke
			(width 2.032)
			(type default)
		)
		(layer "In4.Cu")
	)
	(gr_arc
		(start 0 -524.500094)
		(mid 0.439393 -525.560749)
		(end 1.500124 -525.999964)
		(stroke
			(width 0.2)
			(type default)
		)
		(layer "In4.Cu")
	)
	(gr_arc
		(start 0 -524.500094)
		(mid 0.439393 -525.560749)
		(end 1.500124 -525.999964)
		(stroke
			(width 2.032)
			(type default)
		)
		(layer "In4.Cu")
	)
	(gr_poly
		(pts
			(xy 27.681936 -528.95246) (xy 27.697684 -528.939506) (xy 27.720452 -528.921766) (xy 27.770278 -528.892634)
			(xy 27.823922 -528.871337) (xy 27.880162 -528.858362) (xy 27.937714 -528.854003) (xy 27.995266 -528.858362)
			(xy 28.051506 -528.871337) (xy 28.10515 -528.892634) (xy 28.154976 -528.921766) (xy 28.177744 -528.939506)
			(xy 28.193492 -528.95246) (xy 28.27655 -528.983956) (xy 40.298878 -528.983956) (xy 40.381936 -528.95246)
			(xy 40.397684 -528.939506) (xy 40.420452 -528.921766) (xy 40.470278 -528.892634) (xy 40.523922 -528.871337)
			(xy 40.580162 -528.858362) (xy 40.637714 -528.854003) (xy 40.695266 -528.858362) (xy 40.751506 -528.871337)
			(xy 40.80515 -528.892634) (xy 40.854976 -528.921766) (xy 40.877744 -528.939506) (xy 40.893492 -528.95246)
			(xy 40.97655 -528.983956) (xy 52.998878 -528.983956) (xy 53.081936 -528.95246) (xy 53.097684 -528.939506)
			(xy 53.120452 -528.921766) (xy 53.170278 -528.892634) (xy 53.223922 -528.871337) (xy 53.280162 -528.858362)
			(xy 53.337714 -528.854003) (xy 53.395266 -528.858362) (xy 53.451506 -528.871337) (xy 53.50515 -528.892634)
			(xy 53.554976 -528.921766) (xy 53.577744 -528.939506) (xy 53.593492 -528.95246) (xy 53.67655 -528.983956)
			(xy 65.698878 -528.983956) (xy 65.781936 -528.95246) (xy 65.797684 -528.939506) (xy 65.820452 -528.921766)
			(xy 65.870278 -528.892634) (xy 65.923922 -528.871337) (xy 65.980162 -528.858362) (xy 66.037714 -528.854003)
			(xy 66.095266 -528.858362) (xy 66.151506 -528.871337) (xy 66.20515 -528.892634) (xy 66.254976 -528.921766)
			(xy 66.277744 -528.939506) (xy 66.293492 -528.95246) (xy 66.37655 -528.983956) (xy 78.398878 -528.983956)
			(xy 78.481936 -528.95246) (xy 78.497684 -528.939506) (xy 78.520452 -528.921766) (xy 78.570278 -528.892634)
			(xy 78.623922 -528.871337) (xy 78.680162 -528.858362) (xy 78.737714 -528.854003) (xy 78.795266 -528.858362)
			(xy 78.851506 -528.871337) (xy 78.90515 -528.892634) (xy 78.954976 -528.921766) (xy 78.977744 -528.939506)
			(xy 78.993492 -528.95246) (xy 79.07655 -528.983956) (xy 91.098878 -528.983956) (xy 91.181936 -528.95246)
			(xy 91.197684 -528.939506) (xy 91.220452 -528.921766) (xy 91.270278 -528.892634) (xy 91.323922 -528.871337)
			(xy 91.380162 -528.858362) (xy 91.437714 -528.854003) (xy 91.495266 -528.858362) (xy 91.551506 -528.871337)
			(xy 91.60515 -528.892634) (xy 91.654976 -528.921766) (xy 91.677744 -528.939506) (xy 91.693492 -528.95246)
			(xy 91.77655 -528.983956) (xy 101.000052 -528.983956) (xy 101.045522 -528.983449) (xy 101.136075 -528.975062)
			(xy 101.225467 -528.958355) (xy 101.312937 -528.933471) (xy 101.397737 -528.900622) (xy 101.479144 -528.860089)
			(xy 101.556464 -528.812216) (xy 101.629036 -528.757413) (xy 101.696242 -528.696148) (xy 101.757508 -528.628942)
			(xy 101.812312 -528.55637) (xy 101.860185 -528.479051) (xy 101.900719 -528.397644) (xy 101.933569 -528.312844)
			(xy 101.958454 -528.225375) (xy 101.975161 -528.135983) (xy 101.983549 -528.04543) (xy 101.984048 -527.99996)
			(xy 101.984048 -525.382236) (xy 101.983586 -525.366909) (xy 101.976272 -525.337141) (xy 101.962081 -525.30997)
			(xy 101.952298 -525.298162) (xy 101.934352 -525.277135) (xy 101.904082 -525.230879) (xy 101.880807 -525.180739)
			(xy 101.865012 -525.127764) (xy 101.85703 -525.073064) (xy 101.857026 -525.017784) (xy 101.865002 -524.963083)
			(xy 101.88079 -524.910106) (xy 101.904059 -524.859963) (xy 101.934322 -524.813703) (xy 101.952298 -524.792702)
			(xy 101.962138 -524.780931) (xy 101.976362 -524.753756) (xy 101.983666 -524.723965) (xy 101.984048 -524.708628)
			(xy 101.984048 -512.682236) (xy 101.983586 -512.666909) (xy 101.976272 -512.637141) (xy 101.962081 -512.60997)
			(xy 101.952298 -512.598162) (xy 101.934352 -512.577135) (xy 101.904082 -512.530879) (xy 101.880807 -512.480739)
			(xy 101.865012 -512.427764) (xy 101.85703 -512.373064) (xy 101.857026 -512.317784) (xy 101.865002 -512.263083)
			(xy 101.88079 -512.210106) (xy 101.904059 -512.159963) (xy 101.934322 -512.113703) (xy 101.952298 -512.092702)
			(xy 101.962138 -512.080931) (xy 101.976362 -512.053756) (xy 101.983666 -512.023965) (xy 101.984048 -512.008628)
			(xy 101.984048 -499.982236) (xy 101.983586 -499.966909) (xy 101.976272 -499.937141) (xy 101.962081 -499.90997)
			(xy 101.952298 -499.898162) (xy 101.934352 -499.877135) (xy 101.904082 -499.830879) (xy 101.880807 -499.780739)
			(xy 101.865012 -499.727764) (xy 101.85703 -499.673064) (xy 101.857026 -499.617784) (xy 101.865002 -499.563083)
			(xy 101.88079 -499.510106) (xy 101.904059 -499.459963) (xy 101.934322 -499.413703) (xy 101.952298 -499.392702)
			(xy 101.962138 -499.380931) (xy 101.976362 -499.353756) (xy 101.983666 -499.323965) (xy 101.984048 -499.308628)
			(xy 101.984048 -487.282236) (xy 101.983586 -487.266909) (xy 101.976272 -487.237141) (xy 101.962081 -487.20997)
			(xy 101.952298 -487.198162) (xy 101.934352 -487.177135) (xy 101.904082 -487.130879) (xy 101.880807 -487.080739)
			(xy 101.865012 -487.027764) (xy 101.85703 -486.973064) (xy 101.857026 -486.917784) (xy 101.865002 -486.863083)
			(xy 101.88079 -486.810106) (xy 101.904059 -486.759963) (xy 101.934322 -486.713703) (xy 101.952298 -486.692702)
			(xy 101.962138 -486.680931) (xy 101.976362 -486.653756) (xy 101.983666 -486.623965) (xy 101.984048 -486.608628)
			(xy 101.984048 -474.582236) (xy 101.983586 -474.566909) (xy 101.976272 -474.537141) (xy 101.962081 -474.50997)
			(xy 101.952298 -474.498162) (xy 101.934352 -474.477135) (xy 101.904082 -474.430879) (xy 101.880807 -474.380739)
			(xy 101.865012 -474.327764) (xy 101.85703 -474.273064) (xy 101.857026 -474.217784) (xy 101.865002 -474.163083)
			(xy 101.88079 -474.110106) (xy 101.904059 -474.059963) (xy 101.934322 -474.013703) (xy 101.952298 -473.992702)
			(xy 101.962138 -473.980931) (xy 101.976362 -473.953756) (xy 101.983666 -473.923965) (xy 101.984048 -473.908628)
			(xy 101.984048 -461.882236) (xy 101.983586 -461.866909) (xy 101.976272 -461.837141) (xy 101.962081 -461.80997)
			(xy 101.952298 -461.798162) (xy 101.934352 -461.777135) (xy 101.904082 -461.730879) (xy 101.880807 -461.680739)
			(xy 101.865012 -461.627764) (xy 101.85703 -461.573064) (xy 101.857026 -461.517784) (xy 101.865002 -461.463083)
			(xy 101.88079 -461.410106) (xy 101.904059 -461.359963) (xy 101.934322 -461.313703) (xy 101.952298 -461.292702)
			(xy 101.962138 -461.280931) (xy 101.976362 -461.253756) (xy 101.983666 -461.223965) (xy 101.984048 -461.208628)
			(xy 101.984048 -449.182236) (xy 101.983586 -449.166909) (xy 101.976272 -449.137141) (xy 101.962081 -449.10997)
			(xy 101.952298 -449.098162) (xy 101.934352 -449.077135) (xy 101.904082 -449.030879) (xy 101.880807 -448.980739)
			(xy 101.865012 -448.927764) (xy 101.85703 -448.873064) (xy 101.857026 -448.817784) (xy 101.865002 -448.763083)
			(xy 101.88079 -448.710106) (xy 101.904059 -448.659963) (xy 101.934322 -448.613703) (xy 101.952298 -448.592702)
			(xy 101.962138 -448.580931) (xy 101.976362 -448.553756) (xy 101.983666 -448.523965) (xy 101.984048 -448.508628)
			(xy 101.984048 -436.482236) (xy 101.983586 -436.466909) (xy 101.976272 -436.437141) (xy 101.962081 -436.40997)
			(xy 101.952298 -436.398162) (xy 101.934352 -436.377135) (xy 101.904082 -436.330879) (xy 101.880807 -436.280739)
			(xy 101.865012 -436.227764) (xy 101.85703 -436.173064) (xy 101.857026 -436.117784) (xy 101.865002 -436.063083)
			(xy 101.88079 -436.010106) (xy 101.904059 -435.959963) (xy 101.934322 -435.913703) (xy 101.952298 -435.892702)
			(xy 101.962138 -435.880931) (xy 101.976362 -435.853756) (xy 101.983666 -435.823965) (xy 101.984048 -435.808628)
			(xy 101.984048 -423.782236) (xy 101.983586 -423.766909) (xy 101.976272 -423.737141) (xy 101.962081 -423.70997)
			(xy 101.952298 -423.698162) (xy 101.934352 -423.677135) (xy 101.904082 -423.630879) (xy 101.880807 -423.580739)
			(xy 101.865012 -423.527764) (xy 101.85703 -423.473064) (xy 101.857026 -423.417784) (xy 101.865002 -423.363083)
			(xy 101.88079 -423.310106) (xy 101.904059 -423.259963) (xy 101.934322 -423.213703) (xy 101.952298 -423.192702)
			(xy 101.962138 -423.180931) (xy 101.976362 -423.153756) (xy 101.983666 -423.123965) (xy 101.984048 -423.108628)
			(xy 101.984048 -411.082236) (xy 101.983586 -411.066909) (xy 101.976272 -411.037141) (xy 101.962081 -411.00997)
			(xy 101.952298 -410.998162) (xy 101.934352 -410.977135) (xy 101.904082 -410.930879) (xy 101.880807 -410.880739)
			(xy 101.865012 -410.827764) (xy 101.85703 -410.773064) (xy 101.857026 -410.717784) (xy 101.865002 -410.663083)
			(xy 101.88079 -410.610106) (xy 101.904059 -410.559963) (xy 101.934322 -410.513703) (xy 101.952298 -410.492702)
			(xy 101.962138 -410.480931) (xy 101.976362 -410.453756) (xy 101.983666 -410.423965) (xy 101.984048 -410.408628)
			(xy 101.984048 -398.382236) (xy 101.983586 -398.366909) (xy 101.976272 -398.337141) (xy 101.962081 -398.30997)
			(xy 101.952298 -398.298162) (xy 101.934352 -398.277135) (xy 101.904082 -398.230879) (xy 101.880807 -398.180739)
			(xy 101.865012 -398.127764) (xy 101.85703 -398.073064) (xy 101.857026 -398.017784) (xy 101.865002 -397.963083)
			(xy 101.88079 -397.910106) (xy 101.904059 -397.859963) (xy 101.934322 -397.813703) (xy 101.952298 -397.792702)
			(xy 101.962138 -397.780931) (xy 101.976362 -397.753756) (xy 101.983666 -397.723965) (xy 101.984048 -397.708628)
			(xy 101.984048 -385.682236) (xy 101.983586 -385.666909) (xy 101.976272 -385.637141) (xy 101.962081 -385.60997)
			(xy 101.952298 -385.598162) (xy 101.934352 -385.577135) (xy 101.904082 -385.530879) (xy 101.880807 -385.480739)
			(xy 101.865012 -385.427764) (xy 101.85703 -385.373064) (xy 101.857026 -385.317784) (xy 101.865002 -385.263083)
			(xy 101.88079 -385.210106) (xy 101.904059 -385.159963) (xy 101.934322 -385.113703) (xy 101.952298 -385.092702)
			(xy 101.962138 -385.080931) (xy 101.976362 -385.053756) (xy 101.983666 -385.023965) (xy 101.984048 -385.008628)
			(xy 101.984048 -372.982236) (xy 101.983586 -372.966909) (xy 101.976272 -372.937141) (xy 101.962081 -372.90997)
			(xy 101.952298 -372.898162) (xy 101.934352 -372.877135) (xy 101.904082 -372.830879) (xy 101.880807 -372.780739)
			(xy 101.865012 -372.727764) (xy 101.85703 -372.673064) (xy 101.857026 -372.617784) (xy 101.865002 -372.563083)
			(xy 101.88079 -372.510106) (xy 101.904059 -372.459963) (xy 101.934322 -372.413703) (xy 101.952298 -372.392702)
			(xy 101.962138 -372.380931) (xy 101.976362 -372.353756) (xy 101.983666 -372.323965) (xy 101.984048 -372.308628)
			(xy 101.984048 -360.282236) (xy 101.983586 -360.266909) (xy 101.976272 -360.237141) (xy 101.962081 -360.20997)
			(xy 101.952298 -360.198162) (xy 101.934352 -360.177135) (xy 101.904082 -360.130879) (xy 101.880807 -360.080739)
			(xy 101.865012 -360.027764) (xy 101.85703 -359.973064) (xy 101.857026 -359.917784) (xy 101.865002 -359.863083)
			(xy 101.88079 -359.810106) (xy 101.904059 -359.759963) (xy 101.934322 -359.713703) (xy 101.952298 -359.692702)
			(xy 101.962138 -359.680931) (xy 101.976362 -359.653756) (xy 101.983666 -359.623965) (xy 101.984048 -359.608628)
			(xy 101.984048 -347.582236) (xy 101.983586 -347.566909) (xy 101.976272 -347.537141) (xy 101.962081 -347.50997)
			(xy 101.952298 -347.498162) (xy 101.934352 -347.477135) (xy 101.904082 -347.430879) (xy 101.880807 -347.380739)
			(xy 101.865012 -347.327764) (xy 101.85703 -347.273064) (xy 101.857026 -347.217784) (xy 101.865002 -347.163083)
			(xy 101.88079 -347.110106) (xy 101.904059 -347.059963) (xy 101.934322 -347.013703) (xy 101.952298 -346.992702)
			(xy 101.962138 -346.980931) (xy 101.976362 -346.953756) (xy 101.983666 -346.923965) (xy 101.984048 -346.908628)
			(xy 101.984048 -334.882236) (xy 101.983586 -334.866909) (xy 101.976272 -334.837141) (xy 101.962081 -334.80997)
			(xy 101.952298 -334.798162) (xy 101.934352 -334.777135) (xy 101.904082 -334.730879) (xy 101.880807 -334.680739)
			(xy 101.865012 -334.627764) (xy 101.85703 -334.573064) (xy 101.857026 -334.517784) (xy 101.865002 -334.463083)
			(xy 101.88079 -334.410106) (xy 101.904059 -334.359963) (xy 101.934322 -334.313703) (xy 101.952298 -334.292702)
			(xy 101.962138 -334.280931) (xy 101.976362 -334.253756) (xy 101.983666 -334.223965) (xy 101.984048 -334.208628)
			(xy 101.984048 -322.182236) (xy 101.983586 -322.166909) (xy 101.976272 -322.137141) (xy 101.962081 -322.10997)
			(xy 101.952298 -322.098162) (xy 101.934352 -322.077135) (xy 101.904082 -322.030879) (xy 101.880807 -321.980739)
			(xy 101.865012 -321.927764) (xy 101.85703 -321.873064) (xy 101.857026 -321.817784) (xy 101.865002 -321.763083)
			(xy 101.88079 -321.710106) (xy 101.904059 -321.659963) (xy 101.934322 -321.613703) (xy 101.952298 -321.592702)
			(xy 101.962138 -321.580931) (xy 101.976362 -321.553756) (xy 101.983666 -321.523965) (xy 101.984048 -321.508628)
			(xy 101.984048 -309.482236) (xy 101.983586 -309.466909) (xy 101.976272 -309.437141) (xy 101.962081 -309.40997)
			(xy 101.952298 -309.398162) (xy 101.934352 -309.377135) (xy 101.904082 -309.330879) (xy 101.880807 -309.280739)
			(xy 101.865012 -309.227764) (xy 101.85703 -309.173064) (xy 101.857026 -309.117784) (xy 101.865002 -309.063083)
			(xy 101.88079 -309.010106) (xy 101.904059 -308.959963) (xy 101.934322 -308.913703) (xy 101.952298 -308.892702)
			(xy 101.962138 -308.880931) (xy 101.976362 -308.853756) (xy 101.983666 -308.823965) (xy 101.984048 -308.808628)
			(xy 101.984048 -296.782236) (xy 101.983586 -296.766909) (xy 101.976272 -296.737141) (xy 101.962081 -296.70997)
			(xy 101.952298 -296.698162) (xy 101.934352 -296.677135) (xy 101.904082 -296.630879) (xy 101.880807 -296.580739)
			(xy 101.865012 -296.527764) (xy 101.85703 -296.473064) (xy 101.857026 -296.417784) (xy 101.865002 -296.363083)
			(xy 101.88079 -296.310106) (xy 101.904059 -296.259963) (xy 101.934322 -296.213703) (xy 101.952298 -296.192702)
			(xy 101.962138 -296.180931) (xy 101.976362 -296.153756) (xy 101.983666 -296.123965) (xy 101.984048 -296.108628)
			(xy 101.984048 -284.082236) (xy 101.983586 -284.066909) (xy 101.976272 -284.037141) (xy 101.962081 -284.00997)
			(xy 101.952298 -283.998162) (xy 101.934352 -283.977135) (xy 101.904082 -283.930879) (xy 101.880807 -283.880739)
			(xy 101.865012 -283.827764) (xy 101.85703 -283.773064) (xy 101.857026 -283.717784) (xy 101.865002 -283.663083)
			(xy 101.88079 -283.610106) (xy 101.904059 -283.559963) (xy 101.934322 -283.513703) (xy 101.952298 -283.492702)
			(xy 101.962138 -283.480931) (xy 101.976362 -283.453756) (xy 101.983666 -283.423965) (xy 101.984048 -283.408628)
			(xy 101.984048 -271.382236) (xy 101.983586 -271.366909) (xy 101.976272 -271.337141) (xy 101.962081 -271.30997)
			(xy 101.952298 -271.298162) (xy 101.934352 -271.277135) (xy 101.904082 -271.230879) (xy 101.880807 -271.180739)
			(xy 101.865012 -271.127764) (xy 101.85703 -271.073064) (xy 101.857026 -271.017784) (xy 101.865002 -270.963083)
			(xy 101.88079 -270.910106) (xy 101.904059 -270.859963) (xy 101.934322 -270.813703) (xy 101.952298 -270.792702)
			(xy 101.962138 -270.780931) (xy 101.976362 -270.753756) (xy 101.983666 -270.723965) (xy 101.984048 -270.708628)
			(xy 101.984048 -258.682236) (xy 101.983586 -258.666909) (xy 101.976272 -258.637141) (xy 101.962081 -258.60997)
			(xy 101.952298 -258.598162) (xy 101.934352 -258.577135) (xy 101.904082 -258.530879) (xy 101.880807 -258.480739)
			(xy 101.865012 -258.427764) (xy 101.85703 -258.373064) (xy 101.857026 -258.317784) (xy 101.865002 -258.263083)
			(xy 101.88079 -258.210106) (xy 101.904059 -258.159963) (xy 101.934322 -258.113703) (xy 101.952298 -258.092702)
			(xy 101.962138 -258.080931) (xy 101.976362 -258.053756) (xy 101.983666 -258.023965) (xy 101.984048 -258.008628)
			(xy 101.984048 -245.982236) (xy 101.983586 -245.966909) (xy 101.976272 -245.937141) (xy 101.962081 -245.90997)
			(xy 101.952298 -245.898162) (xy 101.934352 -245.877135) (xy 101.904082 -245.830879) (xy 101.880807 -245.780739)
			(xy 101.865012 -245.727764) (xy 101.85703 -245.673064) (xy 101.857026 -245.617784) (xy 101.865002 -245.563083)
			(xy 101.88079 -245.510106) (xy 101.904059 -245.459963) (xy 101.934322 -245.413703) (xy 101.952298 -245.392702)
			(xy 101.962138 -245.380931) (xy 101.976362 -245.353756) (xy 101.983666 -245.323965) (xy 101.984048 -245.308628)
			(xy 101.984048 -233.282236) (xy 101.983586 -233.266909) (xy 101.976272 -233.237141) (xy 101.962081 -233.20997)
			(xy 101.952298 -233.198162) (xy 101.934352 -233.177135) (xy 101.904082 -233.130879) (xy 101.880807 -233.080739)
			(xy 101.865012 -233.027764) (xy 101.85703 -232.973064) (xy 101.857026 -232.917784) (xy 101.865002 -232.863083)
			(xy 101.88079 -232.810106) (xy 101.904059 -232.759963) (xy 101.934322 -232.713703) (xy 101.952298 -232.692702)
			(xy 101.962138 -232.680931) (xy 101.976362 -232.653756) (xy 101.983666 -232.623965) (xy 101.984048 -232.608628)
			(xy 101.984048 -220.582236) (xy 101.983586 -220.566909) (xy 101.976272 -220.537141) (xy 101.962081 -220.50997)
			(xy 101.952298 -220.498162) (xy 101.934352 -220.477135) (xy 101.904082 -220.430879) (xy 101.880807 -220.380739)
			(xy 101.865012 -220.327764) (xy 101.85703 -220.273064) (xy 101.857026 -220.217784) (xy 101.865002 -220.163083)
			(xy 101.88079 -220.110106) (xy 101.904059 -220.059963) (xy 101.934322 -220.013703) (xy 101.952298 -219.992702)
			(xy 101.962138 -219.980931) (xy 101.976362 -219.953756) (xy 101.983666 -219.923965) (xy 101.984048 -219.908628)
			(xy 101.984048 -207.882236) (xy 101.983586 -207.866909) (xy 101.976272 -207.837141) (xy 101.962081 -207.80997)
			(xy 101.952298 -207.798162) (xy 101.934352 -207.777135) (xy 101.904082 -207.730879) (xy 101.880807 -207.680739)
			(xy 101.865012 -207.627764) (xy 101.85703 -207.573064) (xy 101.857026 -207.517784) (xy 101.865002 -207.463083)
			(xy 101.88079 -207.410106) (xy 101.904059 -207.359963) (xy 101.934322 -207.313703) (xy 101.952298 -207.292702)
			(xy 101.962138 -207.280931) (xy 101.976362 -207.253756) (xy 101.983666 -207.223965) (xy 101.984048 -207.208628)
			(xy 101.984048 -195.182236) (xy 101.983586 -195.166909) (xy 101.976272 -195.137141) (xy 101.962081 -195.10997)
			(xy 101.952298 -195.098162) (xy 101.934352 -195.077135) (xy 101.904082 -195.030879) (xy 101.880807 -194.980739)
			(xy 101.865012 -194.927764) (xy 101.85703 -194.873064) (xy 101.857026 -194.817784) (xy 101.865002 -194.763083)
			(xy 101.88079 -194.710106) (xy 101.904059 -194.659963) (xy 101.934322 -194.613703) (xy 101.952298 -194.592702)
			(xy 101.962138 -194.580931) (xy 101.976362 -194.553756) (xy 101.983666 -194.523965) (xy 101.984048 -194.508628)
			(xy 101.984048 -182.482236) (xy 101.983586 -182.466909) (xy 101.976272 -182.437141) (xy 101.962081 -182.40997)
			(xy 101.952298 -182.398162) (xy 101.934352 -182.377135) (xy 101.904082 -182.330879) (xy 101.880807 -182.280739)
			(xy 101.865012 -182.227764) (xy 101.85703 -182.173064) (xy 101.857026 -182.117784) (xy 101.865002 -182.063083)
			(xy 101.88079 -182.010106) (xy 101.904059 -181.959963) (xy 101.934322 -181.913703) (xy 101.952298 -181.892702)
			(xy 101.962138 -181.880931) (xy 101.976362 -181.853756) (xy 101.983666 -181.823965) (xy 101.984048 -181.808628)
			(xy 101.984048 -169.782236) (xy 101.983586 -169.766909) (xy 101.976272 -169.737141) (xy 101.962081 -169.70997)
			(xy 101.952298 -169.698162) (xy 101.934352 -169.677135) (xy 101.904082 -169.630879) (xy 101.880807 -169.580739)
			(xy 101.865012 -169.527764) (xy 101.85703 -169.473064) (xy 101.857026 -169.417784) (xy 101.865002 -169.363083)
			(xy 101.88079 -169.310106) (xy 101.904059 -169.259963) (xy 101.934322 -169.213703) (xy 101.952298 -169.192702)
			(xy 101.962138 -169.180931) (xy 101.976362 -169.153756) (xy 101.983666 -169.123965) (xy 101.984048 -169.108628)
			(xy 101.984048 -157.082236) (xy 101.983586 -157.066909) (xy 101.976272 -157.037141) (xy 101.962081 -157.00997)
			(xy 101.952298 -156.998162) (xy 101.934352 -156.977135) (xy 101.904082 -156.930879) (xy 101.880807 -156.880739)
			(xy 101.865012 -156.827764) (xy 101.85703 -156.773064) (xy 101.857026 -156.717784) (xy 101.865002 -156.663083)
			(xy 101.88079 -156.610106) (xy 101.904059 -156.559963) (xy 101.934322 -156.513703) (xy 101.952298 -156.492702)
			(xy 101.962138 -156.480931) (xy 101.976362 -156.453756) (xy 101.983666 -156.423965) (xy 101.984048 -156.408628)
			(xy 101.984048 -144.382236) (xy 101.983586 -144.366909) (xy 101.976272 -144.337141) (xy 101.962081 -144.30997)
			(xy 101.952298 -144.298162) (xy 101.934352 -144.277135) (xy 101.904082 -144.230879) (xy 101.880807 -144.180739)
			(xy 101.865012 -144.127764) (xy 101.85703 -144.073064) (xy 101.857026 -144.017784) (xy 101.865002 -143.963083)
			(xy 101.88079 -143.910106) (xy 101.904059 -143.859963) (xy 101.934322 -143.813703) (xy 101.952298 -143.792702)
			(xy 101.962138 -143.780931) (xy 101.976362 -143.753756) (xy 101.983666 -143.723965) (xy 101.984048 -143.708628)
			(xy 101.984048 -131.682236) (xy 101.983586 -131.666909) (xy 101.976272 -131.637141) (xy 101.962081 -131.60997)
			(xy 101.952298 -131.598162) (xy 101.934352 -131.577135) (xy 101.904082 -131.530879) (xy 101.880807 -131.480739)
			(xy 101.865012 -131.427764) (xy 101.85703 -131.373064) (xy 101.857026 -131.317784) (xy 101.865002 -131.263083)
			(xy 101.88079 -131.210106) (xy 101.904059 -131.159963) (xy 101.934322 -131.113703) (xy 101.952298 -131.092702)
			(xy 101.962138 -131.080931) (xy 101.976362 -131.053756) (xy 101.983666 -131.023965) (xy 101.984048 -131.008628)
			(xy 101.984048 -118.982236) (xy 101.983586 -118.966909) (xy 101.976272 -118.937141) (xy 101.962081 -118.90997)
			(xy 101.952298 -118.898162) (xy 101.934352 -118.877135) (xy 101.904082 -118.830879) (xy 101.880807 -118.780739)
			(xy 101.865012 -118.727764) (xy 101.85703 -118.673064) (xy 101.857026 -118.617784) (xy 101.865002 -118.563083)
			(xy 101.88079 -118.510106) (xy 101.904059 -118.459963) (xy 101.934322 -118.413703) (xy 101.952298 -118.392702)
			(xy 101.962138 -118.380931) (xy 101.976362 -118.353756) (xy 101.983666 -118.323965) (xy 101.984048 -118.308628)
			(xy 101.984048 -106.282236) (xy 101.983586 -106.266909) (xy 101.976272 -106.237141) (xy 101.962081 -106.20997)
			(xy 101.952298 -106.198162) (xy 101.934352 -106.177135) (xy 101.904082 -106.130879) (xy 101.880807 -106.080739)
			(xy 101.865012 -106.027764) (xy 101.85703 -105.973064) (xy 101.857026 -105.917784) (xy 101.865002 -105.863083)
			(xy 101.88079 -105.810106) (xy 101.904059 -105.759963) (xy 101.934322 -105.713703) (xy 101.952298 -105.692702)
			(xy 101.962138 -105.680931) (xy 101.976362 -105.653756) (xy 101.983666 -105.623965) (xy 101.984048 -105.608628)
			(xy 101.984048 -93.582236) (xy 101.983586 -93.566909) (xy 101.976272 -93.537141) (xy 101.962081 -93.50997)
			(xy 101.952298 -93.498162) (xy 101.934352 -93.477135) (xy 101.904082 -93.430879) (xy 101.880807 -93.380739)
			(xy 101.865012 -93.327764) (xy 101.85703 -93.273064) (xy 101.857026 -93.217784) (xy 101.865002 -93.163083)
			(xy 101.88079 -93.110106) (xy 101.904059 -93.059963) (xy 101.934322 -93.013703) (xy 101.952298 -92.992702)
			(xy 101.962138 -92.980931) (xy 101.976362 -92.953756) (xy 101.983666 -92.923965) (xy 101.984048 -92.908628)
			(xy 101.984048 -80.882236) (xy 101.983586 -80.866909) (xy 101.976272 -80.837141) (xy 101.962081 -80.80997)
			(xy 101.952298 -80.798162) (xy 101.934352 -80.777135) (xy 101.904082 -80.730879) (xy 101.880807 -80.680739)
			(xy 101.865012 -80.627764) (xy 101.85703 -80.573064) (xy 101.857026 -80.517784) (xy 101.865002 -80.463083)
			(xy 101.88079 -80.410106) (xy 101.904059 -80.359963) (xy 101.934322 -80.313703) (xy 101.952298 -80.292702)
			(xy 101.962138 -80.280931) (xy 101.976362 -80.253756) (xy 101.983666 -80.223965) (xy 101.984048 -80.208628)
			(xy 101.984048 -68.182236) (xy 101.983586 -68.166909) (xy 101.976272 -68.137141) (xy 101.962081 -68.10997)
			(xy 101.952298 -68.098162) (xy 101.934352 -68.077135) (xy 101.904082 -68.030879) (xy 101.880807 -67.980739)
			(xy 101.865012 -67.927764) (xy 101.85703 -67.873064) (xy 101.857026 -67.817784) (xy 101.865002 -67.763083)
			(xy 101.88079 -67.710106) (xy 101.904059 -67.659963) (xy 101.934322 -67.613703) (xy 101.952298 -67.592702)
			(xy 101.962138 -67.580931) (xy 101.976362 -67.553756) (xy 101.983666 -67.523965) (xy 101.984048 -67.508628)
			(xy 101.984048 -55.482236) (xy 101.983586 -55.466909) (xy 101.976272 -55.437141) (xy 101.962081 -55.40997)
			(xy 101.952298 -55.398162) (xy 101.934352 -55.377135) (xy 101.904082 -55.330879) (xy 101.880807 -55.280739)
			(xy 101.865012 -55.227764) (xy 101.85703 -55.173064) (xy 101.857026 -55.117784) (xy 101.865002 -55.063083)
			(xy 101.88079 -55.010106) (xy 101.904059 -54.959963) (xy 101.934322 -54.913703) (xy 101.952298 -54.892702)
			(xy 101.962138 -54.880931) (xy 101.976362 -54.853756) (xy 101.983666 -54.823965) (xy 101.984048 -54.808628)
			(xy 101.984048 -42.782236) (xy 101.983586 -42.766909) (xy 101.976272 -42.737141) (xy 101.962081 -42.70997)
			(xy 101.952298 -42.698162) (xy 101.934352 -42.677135) (xy 101.904082 -42.630879) (xy 101.880807 -42.580739)
			(xy 101.865012 -42.527764) (xy 101.85703 -42.473064) (xy 101.857026 -42.417784) (xy 101.865002 -42.363083)
			(xy 101.88079 -42.310106) (xy 101.904059 -42.259963) (xy 101.934322 -42.213703) (xy 101.952298 -42.192702)
			(xy 101.962138 -42.180931) (xy 101.976362 -42.153756) (xy 101.983666 -42.123965) (xy 101.984048 -42.108628)
			(xy 101.984048 -30.082236) (xy 101.983586 -30.066909) (xy 101.976272 -30.037141) (xy 101.962081 -30.00997)
			(xy 101.952298 -29.998162) (xy 101.934352 -29.977135) (xy 101.904082 -29.930879) (xy 101.880807 -29.880739)
			(xy 101.865012 -29.827764) (xy 101.85703 -29.773064) (xy 101.857026 -29.717784) (xy 101.865002 -29.663083)
			(xy 101.88079 -29.610106) (xy 101.904059 -29.559963) (xy 101.934322 -29.513703) (xy 101.952298 -29.492702)
			(xy 101.962138 -29.480931) (xy 101.976362 -29.453756) (xy 101.983666 -29.423965) (xy 101.984048 -29.408628)
			(xy 101.984048 -17.382236) (xy 101.983586 -17.366909) (xy 101.976272 -17.337141) (xy 101.962081 -17.30997)
			(xy 101.952298 -17.298162) (xy 101.934352 -17.277135) (xy 101.904082 -17.230879) (xy 101.880807 -17.180739)
			(xy 101.865012 -17.127764) (xy 101.85703 -17.073064) (xy 101.857026 -17.017784) (xy 101.865002 -16.963083)
			(xy 101.88079 -16.910106) (xy 101.904059 -16.859963) (xy 101.934322 -16.813703) (xy 101.952298 -16.792702)
			(xy 101.962138 -16.780931) (xy 101.976362 -16.753756) (xy 101.983666 -16.723965) (xy 101.984048 -16.708628)
			(xy 101.984048 -4.682236) (xy 101.983586 -4.666909) (xy 101.976272 -4.637141) (xy 101.962081 -4.60997)
			(xy 101.952298 -4.598162) (xy 101.934352 -4.577135) (xy 101.904082 -4.530879) (xy 101.880807 -4.480739)
			(xy 101.865012 -4.427764) (xy 101.85703 -4.373064) (xy 101.857026 -4.317784) (xy 101.865002 -4.263083)
			(xy 101.88079 -4.210106) (xy 101.904059 -4.159963) (xy 101.934322 -4.113703) (xy 101.952298 -4.092702)
			(xy 101.962138 -4.080931) (xy 101.976362 -4.053756) (xy 101.983666 -4.023965) (xy 101.984048 -4.008628)
			(xy 101.984048 -1.999996) (xy 101.983539 -1.954528) (xy 101.975148 -1.863979) (xy 101.958437 -1.77459)
			(xy 101.93355 -1.687125) (xy 101.900699 -1.60233) (xy 101.860163 -1.520927) (xy 101.81229 -1.443612)
			(xy 101.757486 -1.371044) (xy 101.696221 -1.303842) (xy 101.629016 -1.242581) (xy 101.556445 -1.187781)
			(xy 101.479127 -1.139911) (xy 101.397723 -1.09938) (xy 101.312925 -1.066533) (xy 101.225459 -1.041651)
			(xy 101.13607 -1.024945) (xy 101.04552 -1.016559) (xy 101.000052 -1.016) (xy 95.642938 -1.016) (xy 95.55988 -1.047496)
			(xy 95.544386 -1.059942) (xy 95.521696 -1.077492) (xy 95.472092 -1.106297) (xy 95.418734 -1.127348)
			(xy 95.362825 -1.140172) (xy 95.305626 -1.144479) (xy 95.248427 -1.140172) (xy 95.192518 -1.127348)
			(xy 95.13916 -1.106297) (xy 95.089556 -1.077492) (xy 95.066866 -1.059942) (xy 95.051372 -1.047496)
			(xy 94.968314 -1.016) (xy 82.942938 -1.016) (xy 82.85988 -1.047496) (xy 82.844386 -1.059942) (xy 82.821696 -1.077492)
			(xy 82.772092 -1.106297) (xy 82.718734 -1.127348) (xy 82.662825 -1.140172) (xy 82.605626 -1.144479)
			(xy 82.548427 -1.140172) (xy 82.492518 -1.127348) (xy 82.43916 -1.106297) (xy 82.389556 -1.077492)
			(xy 82.366866 -1.059942) (xy 82.351372 -1.047496) (xy 82.268314 -1.016) (xy 70.242938 -1.016) (xy 70.15988 -1.047496)
			(xy 70.144386 -1.059942) (xy 70.121696 -1.077492) (xy 70.072092 -1.106297) (xy 70.018734 -1.127348)
			(xy 69.962825 -1.140172) (xy 69.905626 -1.144479) (xy 69.848427 -1.140172) (xy 69.792518 -1.127348)
			(xy 69.73916 -1.106297) (xy 69.689556 -1.077492) (xy 69.666866 -1.059942) (xy 69.651372 -1.047496)
			(xy 69.568314 -1.016) (xy 57.542938 -1.016) (xy 57.45988 -1.047496) (xy 57.444386 -1.059942) (xy 57.421696 -1.077492)
			(xy 57.372092 -1.106297) (xy 57.318734 -1.127348) (xy 57.262825 -1.140172) (xy 57.205626 -1.144479)
			(xy 57.148427 -1.140172) (xy 57.092518 -1.127348) (xy 57.03916 -1.106297) (xy 56.989556 -1.077492)
			(xy 56.966866 -1.059942) (xy 56.951372 -1.047496) (xy 56.868314 -1.016) (xy 44.842938 -1.016) (xy 44.75988 -1.047496)
			(xy 44.744386 -1.059942) (xy 44.721696 -1.077492) (xy 44.672092 -1.106297) (xy 44.618734 -1.127348)
			(xy 44.562825 -1.140172) (xy 44.505626 -1.144479) (xy 44.448427 -1.140172) (xy 44.392518 -1.127348)
			(xy 44.33916 -1.106297) (xy 44.289556 -1.077492) (xy 44.266866 -1.059942) (xy 44.251372 -1.047496)
			(xy 44.168314 -1.016) (xy 32.142938 -1.016) (xy 32.05988 -1.047496) (xy 32.044386 -1.059942) (xy 32.021696 -1.077492)
			(xy 31.972092 -1.106297) (xy 31.918734 -1.127348) (xy 31.862825 -1.140172) (xy 31.805626 -1.144479)
			(xy 31.748427 -1.140172) (xy 31.692518 -1.127348) (xy 31.63916 -1.106297) (xy 31.589556 -1.077492)
			(xy 31.566866 -1.059942) (xy 31.551372 -1.047496) (xy 31.468314 -1.016) (xy 26.500074 -1.016) (xy 26.468378 -1.01652)
			(xy 26.40553 -1.024797) (xy 26.3443 -1.041207) (xy 26.285735 -1.065469) (xy 26.230839 -1.097168)
			(xy 26.180549 -1.13576) (xy 26.135727 -1.180587) (xy 26.09714 -1.23088) (xy 26.065447 -1.28578) (xy 26.041191 -1.344347)
			(xy 26.024788 -1.405579) (xy 26.016517 -1.468428) (xy 26.01595 -1.500124) (xy 26.01595 -2.500122)
			(xy 26.015455 -2.570697) (xy 26.007541 -2.711624) (xy 25.991737 -2.851885) (xy 25.968093 -2.99104)
			(xy 25.936685 -3.12865) (xy 25.897609 -3.264283) (xy 25.850991 -3.397511) (xy 25.796975 -3.527916)
			(xy 25.735733 -3.655087) (xy 25.667456 -3.778624) (xy 25.59236 -3.898139) (xy 25.510681 -4.013254)
			(xy 25.422676 -4.123609) (xy 25.328622 -4.228856) (xy 25.228814 -4.328663) (xy 25.123568 -4.422717)
			(xy 25.013213 -4.510723) (xy 24.898097 -4.592401) (xy 24.778582 -4.667497) (xy 24.655045 -4.735774)
			(xy 24.527874 -4.797016) (xy 24.39747 -4.851032) (xy 24.264241 -4.89765) (xy 24.128608 -4.936725)
			(xy 23.990998 -4.968134) (xy 23.851843 -4.991777) (xy 23.711582 -5.007581) (xy 23.570655 -5.015495)
			(xy 23.50008 -5.015992) (xy 19.68881 -5.015992) (xy 19.674381 -5.048069) (xy 19.639436 -5.109113)
			(xy 19.597965 -5.165927) (xy 19.550477 -5.217815) (xy 19.49755 -5.264144) (xy 19.439833 -5.304347)
			(xy 19.37803 -5.337932) (xy 19.312897 -5.36449) (xy 19.24523 -5.383695) (xy 19.175857 -5.395313)
			(xy 19.105626 -5.399201) (xy 19.035395 -5.395313) (xy 18.966022 -5.383695) (xy 18.898355 -5.36449)
			(xy 18.833222 -5.337932) (xy 18.771419 -5.304347) (xy 18.713702 -5.264144) (xy 18.660775 -5.217815)
			(xy 18.613287 -5.165927) (xy 18.571816 -5.109113) (xy 18.536871 -5.048069) (xy 18.522442 -5.015992)
			(xy 6.743446 -5.015992) (xy 6.728061 -5.016462) (xy 6.698187 -5.023837) (xy 6.670945 -5.038144) (xy 6.659118 -5.047996)
			(xy 6.638059 -5.06606) (xy 6.5917 -5.096538) (xy 6.541414 -5.119978) (xy 6.488262 -5.135885) (xy 6.433366 -5.143923)
			(xy 6.377886 -5.143923) (xy 6.32299 -5.135885) (xy 6.269838 -5.119978) (xy 6.219552 -5.096538) (xy 6.173193 -5.06606)
			(xy 6.152134 -5.047996) (xy 6.140341 -5.038093) (xy 6.113091 -5.023766) (xy 6.0832 -5.016399) (xy 6.067806 -5.015992)
			(xy 1.500124 -5.015992) (xy 1.468427 -5.016511) (xy 1.405575 -5.024786) (xy 1.344341 -5.041194) (xy 1.285773 -5.065454)
			(xy 1.230872 -5.097152) (xy 1.180579 -5.135744) (xy 1.135752 -5.18057) (xy 1.09716 -5.230864) (xy 1.065463 -5.285765)
			(xy 1.041203 -5.344333) (xy 1.024795 -5.405567) (xy 1.01652 -5.468419) (xy 1.016 -5.500116) (xy 1.016 -6.91007)
			(xy 39.818063 -6.91007) (xy 39.82207 -6.794046) (xy 39.834072 -6.678574) (xy 39.854012 -6.564206)
			(xy 39.881795 -6.451486) (xy 39.917289 -6.340952) (xy 39.960324 -6.233129) (xy 40.010695 -6.128532)
			(xy 40.068162 -6.02766) (xy 40.132452 -5.930993) (xy 40.203257 -5.838992) (xy 40.280241 -5.752095)
			(xy 40.363037 -5.670716) (xy 40.45125 -5.595243) (xy 40.54446 -5.526036) (xy 40.642223 -5.463424)
			(xy 40.744072 -5.407707) (xy 40.849522 -5.359149) (xy 40.958071 -5.317981) (xy 41.069202 -5.284401)
			(xy 41.182385 -5.258568) (xy 41.29708 -5.240605) (xy 41.412742 -5.230597) (xy 41.528818 -5.228594)
			(xy 41.644756 -5.234603) (xy 41.760003 -5.248596) (xy 41.874009 -5.270507) (xy 41.986233 -5.300232)
			(xy 42.096139 -5.337628) (xy 42.203202 -5.382517) (xy 42.306914 -5.434686) (xy 42.406779 -5.493886)
			(xy 42.502322 -5.559835) (xy 42.593088 -5.632218) (xy 42.678643 -5.710691) (xy 42.758581 -5.794879)
			(xy 42.83252 -5.884381) (xy 42.900108 -5.978772) (xy 42.961022 -6.0776) (xy 43.014974 -6.180396)
			(xy 43.061704 -6.286669) (xy 43.100992 -6.395913) (xy 43.132649 -6.507606) (xy 43.156525 -6.621218)
			(xy 43.172506 -6.736206) (xy 43.180515 -6.852023) (xy 43.181016 -6.91007) (xy 43.180515 -6.968117)
			(xy 43.172506 -7.083934) (xy 43.156525 -7.198922) (xy 43.132649 -7.312534) (xy 43.100992 -7.424227)
			(xy 43.061704 -7.533471) (xy 43.014974 -7.639744) (xy 42.961022 -7.74254) (xy 42.900108 -7.841368)
			(xy 42.83252 -7.935759) (xy 42.758581 -8.025261) (xy 42.678643 -8.109449) (xy 42.593088 -8.187922)
			(xy 42.502604 -8.26008) (xy 93.154506 -8.26008) (xy 93.158522 -8.14381) (xy 93.170549 -8.028095)
			(xy 93.190531 -7.913485) (xy 93.218373 -7.800526) (xy 93.253942 -7.689758) (xy 93.297068 -7.581707)
			(xy 93.347545 -7.476889) (xy 93.405134 -7.375804) (xy 93.46956 -7.278932) (xy 93.540515 -7.186736)
			(xy 93.617662 -7.099655) (xy 93.700633 -7.018104) (xy 93.789033 -6.942472) (xy 93.88244 -6.873118)
			(xy 93.980409 -6.810375) (xy 94.082473 -6.754539) (xy 94.188147 -6.705878) (xy 94.296926 -6.664624)
			(xy 94.408291 -6.630973) (xy 94.521714 -6.605085) (xy 94.636651 -6.587084) (xy 94.752557 -6.577055)
			(xy 94.868879 -6.575047) (xy 94.985062 -6.581069) (xy 95.100553 -6.595092) (xy 95.214801 -6.61705)
			(xy 95.327262 -6.646837) (xy 95.4374 -6.684312) (xy 95.54469 -6.729297) (xy 95.648621 -6.781576)
			(xy 95.748697 -6.840901) (xy 95.844443 -6.906989) (xy 95.9354 -6.979525) (xy 96.021136 -7.058164)
			(xy 96.101243 -7.14253) (xy 96.175339 -7.232222) (xy 96.243069 -7.326812) (xy 96.304113 -7.42585)
			(xy 96.358178 -7.528863) (xy 96.405008 -7.63536) (xy 96.444379 -7.744835) (xy 96.476103 -7.856765)
			(xy 96.500029 -7.970617) (xy 96.516043 -8.085849) (xy 96.52407 -8.201911) (xy 96.524572 -8.26008)
			(xy 96.52407 -8.318249) (xy 96.516043 -8.434311) (xy 96.500029 -8.549543) (xy 96.476103 -8.663395)
			(xy 96.444379 -8.775325) (xy 96.405008 -8.8848) (xy 96.358178 -8.991297) (xy 96.304113 -9.09431)
			(xy 96.243069 -9.193348) (xy 96.175339 -9.287938) (xy 96.101243 -9.37763) (xy 96.021136 -9.461996)
			(xy 95.9354 -9.540635) (xy 95.844443 -9.613171) (xy 95.748697 -9.679259) (xy 95.648621 -9.738584)
			(xy 95.54469 -9.790863) (xy 95.4374 -9.835848) (xy 95.327262 -9.873323) (xy 95.214801 -9.90311) (xy 95.100553 -9.925068)
			(xy 94.985062 -9.939091) (xy 94.868879 -9.945113) (xy 94.752557 -9.943105) (xy 94.636651 -9.933076)
			(xy 94.521714 -9.915075) (xy 94.408291 -9.889187) (xy 94.296926 -9.855536) (xy 94.188147 -9.814282)
			(xy 94.082473 -9.765621) (xy 93.980409 -9.709785) (xy 93.88244 -9.647042) (xy 93.789033 -9.577688)
			(xy 93.700633 -9.502056) (xy 93.617662 -9.420505) (xy 93.540515 -9.333424) (xy 93.46956 -9.241228)
			(xy 93.405134 -9.144356) (xy 93.347545 -9.043271) (xy 93.297068 -8.938453) (xy 93.253942 -8.830402)
			(xy 93.218373 -8.719634) (xy 93.190531 -8.606675) (xy 93.170549 -8.492065) (xy 93.158522 -8.37635)
			(xy 93.154506 -8.26008) (xy 42.502604 -8.26008) (xy 42.502322 -8.260305) (xy 42.406779 -8.326254)
			(xy 42.306914 -8.385454) (xy 42.203202 -8.437623) (xy 42.096139 -8.482512) (xy 41.986233 -8.519908)
			(xy 41.874009 -8.549633) (xy 41.760003 -8.571544) (xy 41.644756 -8.585537) (xy 41.528818 -8.591546)
			(xy 41.412742 -8.589543) (xy 41.29708 -8.579535) (xy 41.182385 -8.561572) (xy 41.069202 -8.535739)
			(xy 40.958071 -8.502159) (xy 40.849522 -8.460991) (xy 40.744072 -8.412433) (xy 40.642223 -8.356716)
			(xy 40.54446 -8.294104) (xy 40.45125 -8.224897) (xy 40.363037 -8.149424) (xy 40.280241 -8.068045)
			(xy 40.203257 -7.981148) (xy 40.132452 -7.889147) (xy 40.068162 -7.79248) (xy 40.010695 -7.691608)
			(xy 39.960324 -7.587011) (xy 39.917289 -7.479188) (xy 39.881795 -7.368654) (xy 39.854012 -7.255934)
			(xy 39.834072 -7.141566) (xy 39.82207 -7.026094) (xy 39.818063 -6.91007) (xy 1.016 -6.91007) (xy 1.016 -12.879578)
			(xy 1.047496 -12.962382) (xy 1.059942 -12.977876) (xy 1.077482 -13.00057) (xy 1.106268 -13.050179)
			(xy 1.127305 -13.103537) (xy 1.14012 -13.159442) (xy 1.144423 -13.216636) (xy 1.14012 -13.27383)
			(xy 1.127305 -13.329735) (xy 1.106268 -13.383093) (xy 1.077482 -13.432702) (xy 1.059942 -13.455396)
			(xy 1.047496 -13.47089) (xy 1.016 -13.553694) (xy 1.016 -13.961618) (xy 1.016505 -13.984958) (xy 1.024982 -14.03086)
			(xy 1.0417 -14.074443) (xy 1.066095 -14.11424) (xy 1.097347 -14.148912) (xy 1.134405 -14.177295)
			(xy 1.176023 -14.198434) (xy 1.220801 -14.211617) (xy 1.267234 -14.216401) (xy 1.31376 -14.212626)
			(xy 1.358814 -14.200418) (xy 1.400881 -14.180188) (xy 1.438547 -14.152616) (xy 1.470544 -14.11863)
			(xy 1.483614 -14.099286) (xy 1.51897 -14.04535) (xy 1.595424 -13.941474) (xy 1.678157 -13.842526)
			(xy 1.766854 -13.748886) (xy 1.861174 -13.660913) (xy 1.960755 -13.578943) (xy 2.065217 -13.50329)
			(xy 2.174159 -13.434245) (xy 2.287163 -13.372072) (xy 2.403797 -13.317009) (xy 2.523615 -13.269267)
			(xy 2.646156 -13.229029) (xy 2.770952 -13.196448) (xy 2.897525 -13.171651) (xy 3.025389 -13.154731)
			(xy 3.154055 -13.145755) (xy 3.28303 -13.144755) (xy 3.411819 -13.151736) (xy 3.539931 -13.166671)
			(xy 3.666872 -13.189503) (xy 3.792159 -13.220144) (xy 3.915309 -13.258477) (xy 4.035852 -13.304356)
			(xy 4.153326 -13.357604) (xy 4.267281 -13.418018) (xy 4.37728 -13.485365) (xy 4.482903 -13.559389)
			(xy 4.583743 -13.639805) (xy 4.679415 -13.726305) (xy 4.769553 -13.818559) (xy 4.853811 -13.916212)
			(xy 4.931866 -14.01889) (xy 5.00342 -14.126201) (xy 5.068198 -14.237733) (xy 5.125952 -14.353059)
			(xy 5.17646 -14.471736) (xy 5.219531 -14.593311) (xy 5.254997 -14.717318) (xy 5.282724 -14.843281)
			(xy 5.302605 -14.970718) (xy 5.314565 -15.099141) (xy 5.318556 -15.228058) (xy 5.318556 -15.228062)
			(xy 12.580624 -15.228062) (xy 12.584655 -15.098496) (xy 12.596734 -14.969432) (xy 12.616813 -14.841368)
			(xy 12.644815 -14.714801) (xy 12.680632 -14.590218) (xy 12.724124 -14.468104) (xy 12.775124 -14.34893)
			(xy 12.833435 -14.233157) (xy 12.89883 -14.121233) (xy 12.971057 -14.013591) (xy 13.049837 -13.910648)
			(xy 13.134864 -13.812802) (xy 13.225809 -13.72043) (xy 13.322321 -13.633892) (xy 13.424027 -13.553521)
			(xy 13.530533 -13.479629) (xy 13.641426 -13.412501) (xy 13.756278 -13.352397) (xy 13.874645 -13.29955)
			(xy 13.996068 -13.254163) (xy 14.120078 -13.216414) (xy 14.246195 -13.186447) (xy 14.373931 -13.164378)
			(xy 14.502792 -13.150294) (xy 14.632279 -13.144248) (xy 14.761892 -13.146264) (xy 14.891128 -13.156334)
			(xy 15.019489 -13.174419) (xy 15.146477 -13.200449) (xy 15.271601 -13.234324) (xy 15.394377 -13.275912)
			(xy 15.51433 -13.325053) (xy 15.630995 -13.381556) (xy 15.743923 -13.445203) (xy 15.852675 -13.515747)
			(xy 15.956831 -13.592916) (xy 16.055988 -13.676411) (xy 16.149762 -13.765909) (xy 16.237791 -13.861064)
			(xy 16.319734 -13.961507) (xy 16.395273 -14.06685) (xy 16.464118 -14.176686) (xy 16.526001 -14.29059)
			(xy 16.580682 -14.40812) (xy 16.627952 -14.528823) (xy 16.667625 -14.652231) (xy 16.69955 -14.777867)
			(xy 16.723602 -14.905244) (xy 16.739689 -15.03387) (xy 16.747748 -15.163248) (xy 16.748252 -15.228062)
			(xy 16.747748 -15.292876) (xy 16.739689 -15.422254) (xy 16.723602 -15.55088) (xy 16.69955 -15.678257)
			(xy 16.667625 -15.803893) (xy 16.627952 -15.927301) (xy 16.580682 -16.048004) (xy 16.526001 -16.165534)
			(xy 16.464118 -16.279438) (xy 16.395273 -16.389274) (xy 16.319734 -16.494617) (xy 16.237791 -16.59506)
			(xy 16.149762 -16.690215) (xy 16.055988 -16.779713) (xy 15.956831 -16.863208) (xy 15.852675 -16.940377)
			(xy 15.743923 -17.010921) (xy 15.630995 -17.074568) (xy 15.51433 -17.131071) (xy 15.394377 -17.180212)
			(xy 15.271601 -17.2218) (xy 15.146477 -17.255675) (xy 15.019489 -17.281705) (xy 14.891128 -17.29979)
			(xy 14.761892 -17.30986) (xy 14.632279 -17.311876) (xy 14.502792 -17.30583) (xy 14.373931 -17.291746)
			(xy 14.246195 -17.269677) (xy 14.120078 -17.23971) (xy 13.996068 -17.201961) (xy 13.874645 -17.156574)
			(xy 13.756278 -17.103727) (xy 13.641426 -17.043623) (xy 13.530533 -16.976495) (xy 13.424027 -16.902603)
			(xy 13.322321 -16.822232) (xy 13.225809 -16.735694) (xy 13.134864 -16.643322) (xy 13.049837 -16.545476)
			(xy 12.971057 -16.442533) (xy 12.89883 -16.334891) (xy 12.833435 -16.222967) (xy 12.775124 -16.107194)
			(xy 12.724124 -15.98802) (xy 12.680632 -15.865906) (xy 12.644815 -15.741323) (xy 12.616813 -15.614756)
			(xy 12.596734 -15.486692) (xy 12.584655 -15.357628) (xy 12.580624 -15.228062) (xy 5.318556 -15.228062)
			(xy 5.314565 -15.356975) (xy 5.302606 -15.485398) (xy 5.282725 -15.612836) (xy 5.254998 -15.738799)
			(xy 5.219532 -15.862806) (xy 5.176462 -15.984381) (xy 5.125953 -16.103058) (xy 5.068199 -16.218384)
			(xy 5.003422 -16.329916) (xy 4.931868 -16.437227) (xy 4.853813 -16.539906) (xy 4.769555 -16.637559)
			(xy 4.679418 -16.729812) (xy 4.583745 -16.816313) (xy 4.482905 -16.896729) (xy 4.377283 -16.970753)
			(xy 4.267284 -17.038101) (xy 4.153329 -17.098514) (xy 4.035855 -17.151763) (xy 3.915312 -17.197642)
			(xy 3.792162 -17.235975) (xy 3.666876 -17.266617) (xy 3.539934 -17.289449) (xy 3.411823 -17.304384)
			(xy 3.283033 -17.311365) (xy 3.154058 -17.310366) (xy 3.025392 -17.301389) (xy 2.897528 -17.284469)
			(xy 2.770955 -17.259672) (xy 2.646159 -17.227092) (xy 2.523618 -17.186854) (xy 2.4038 -17.139112)
			(xy 2.287166 -17.084049) (xy 2.174161 -17.021876) (xy 2.06522 -16.952832) (xy 1.960758 -16.877179)
			(xy 1.861176 -16.79521) (xy 1.766856 -16.707236) (xy 1.67816 -16.613597) (xy 1.595426 -16.514649)
			(xy 1.518972 -16.410773) (xy 1.483614 -16.356838) (xy 1.470543 -16.337496) (xy 1.438545 -16.303511)
			(xy 1.400879 -16.275941) (xy 1.358813 -16.255713) (xy 1.31376 -16.243506) (xy 1.267235 -16.239732)
			(xy 1.220803 -16.244516) (xy 1.176026 -16.257699) (xy 1.134409 -16.278836) (xy 1.097351 -16.307218)
			(xy 1.066099 -16.34189) (xy 1.041704 -16.381685) (xy 1.024985 -16.425266) (xy 1.016506 -16.471167)
			(xy 1.016 -16.494506) (xy 1.016 -20.01012) (xy 86.877404 -20.01012) (xy 86.881424 -19.819469) (xy 86.893478 -19.629156)
			(xy 86.913544 -19.439521) (xy 86.941587 -19.2509) (xy 86.977556 -19.06363) (xy 87.021388 -18.878042)
			(xy 87.073005 -18.694467) (xy 87.132315 -18.513231) (xy 87.199213 -18.334656) (xy 87.273579 -18.159061)
			(xy 87.355281 -17.986756) (xy 87.444175 -17.818049) (xy 87.540101 -17.653239) (xy 87.64289 -17.49262)
			(xy 87.752359 -17.336477) (xy 87.868313 -17.185088) (xy 87.990547 -17.038721) (xy 88.118841 -16.897637)
			(xy 88.252969 -16.762088) (xy 88.392693 -16.632313) (xy 88.537763 -16.508543) (xy 88.687921 -16.391)
			(xy 88.842902 -16.279891) (xy 89.002429 -16.175414) (xy 89.166218 -16.077755) (xy 89.333978 -15.987088)
			(xy 89.505412 -15.903574) (xy 89.680214 -15.827361) (xy 89.858073 -15.758585) (xy 90.038674 -15.697367)
			(xy 90.221694 -15.643818) (xy 90.40681 -15.598032) (xy 90.593691 -15.56009) (xy 90.782006 -15.530061)
			(xy 90.971419 -15.507996) (xy 91.161593 -15.493937) (xy 91.352192 -15.487907) (xy 91.542875 -15.489917)
			(xy 91.733304 -15.499964) (xy 91.92314 -15.51803) (xy 92.112046 -15.544083) (xy 92.299685 -15.578076)
			(xy 92.485725 -15.619949) (xy 92.669834 -15.669628) (xy 92.851685 -15.727024) (xy 93.030955 -15.792035)
			(xy 93.207325 -15.864546) (xy 93.380481 -15.944427) (xy 93.550116 -16.031537) (xy 93.715928 -16.125721)
			(xy 93.877622 -16.226812) (xy 94.03491 -16.334628) (xy 94.187513 -16.44898) (xy 94.335161 -16.569663)
			(xy 94.477589 -16.696464) (xy 94.614545 -16.829155) (xy 94.745786 -16.967503) (xy 94.871078 -17.11126)
			(xy 94.990198 -17.260171) (xy 95.102934 -17.413972) (xy 95.209087 -17.572388) (xy 95.308467 -17.735139)
			(xy 95.400897 -17.901934) (xy 95.486214 -18.072478) (xy 95.564266 -18.246466) (xy 95.634913 -18.423591)
			(xy 95.698031 -18.603536) (xy 95.753507 -18.785982) (xy 95.801242 -18.970605) (xy 95.841152 -19.157075)
			(xy 95.873165 -19.345063) (xy 95.897225 -19.534233) (xy 95.913288 -19.724249) (xy 95.921327 -19.914773)
			(xy 95.92183 -20.01012) (xy 95.921327 -20.105467) (xy 95.913288 -20.295991) (xy 95.897225 -20.486007)
			(xy 95.873165 -20.675177) (xy 95.841152 -20.863165) (xy 95.801242 -21.049635) (xy 95.753507 -21.234258)
			(xy 95.698031 -21.416704) (xy 95.634913 -21.596649) (xy 95.564266 -21.773774) (xy 95.486214 -21.947762)
			(xy 95.400897 -22.118306) (xy 95.308467 -22.285101) (xy 95.209087 -22.447852) (xy 95.102934 -22.606268)
			(xy 94.990198 -22.760069) (xy 94.871078 -22.90898) (xy 94.745786 -23.052737) (xy 94.614545 -23.191085)
			(xy 94.477589 -23.323776) (xy 94.335161 -23.450577) (xy 94.187513 -23.57126) (xy 94.03491 -23.685612)
			(xy 93.877622 -23.793428) (xy 93.715928 -23.894519) (xy 93.550116 -23.988703) (xy 93.380481 -24.075813)
			(xy 93.207325 -24.155694) (xy 93.030955 -24.228205) (xy 92.851685 -24.293216) (xy 92.669834 -24.350612)
			(xy 92.485725 -24.400291) (xy 92.299685 -24.442164) (xy 92.112046 -24.476157) (xy 91.92314 -24.50221)
			(xy 91.733304 -24.520276) (xy 91.542875 -24.530323) (xy 91.352192 -24.532333) (xy 91.161593 -24.526303)
			(xy 90.971419 -24.512244) (xy 90.782006 -24.490179) (xy 90.593691 -24.46015) (xy 90.40681 -24.422208)
			(xy 90.221694 -24.376422) (xy 90.038674 -24.322873) (xy 89.858073 -24.261655) (xy 89.680214 -24.192879)
			(xy 89.505412 -24.116666) (xy 89.333978 -24.033152) (xy 89.166218 -23.942485) (xy 89.002429 -23.844826)
			(xy 88.842902 -23.740349) (xy 88.687921 -23.62924) (xy 88.537763 -23.511697) (xy 88.392693 -23.387927)
			(xy 88.252969 -23.258152) (xy 88.118841 -23.122603) (xy 87.990547 -22.981519) (xy 87.868313 -22.835152)
			(xy 87.752359 -22.683763) (xy 87.64289 -22.52762) (xy 87.540101 -22.367001) (xy 87.444175 -22.202191)
			(xy 87.355281 -22.033484) (xy 87.273579 -21.861179) (xy 87.199213 -21.685584) (xy 87.132315 -21.507009)
			(xy 87.073005 -21.325773) (xy 87.021388 -21.142198) (xy 86.977556 -20.95661) (xy 86.941587 -20.76934)
			(xy 86.913544 -20.580719) (xy 86.893478 -20.391084) (xy 86.881424 -20.200771) (xy 86.877404 -20.01012)
			(xy 1.016 -20.01012) (xy 1.016 -25.071578) (xy 1.047496 -25.154382) (xy 1.059942 -25.169876) (xy 1.077482 -25.19257)
			(xy 1.106268 -25.242179) (xy 1.127305 -25.295537) (xy 1.14012 -25.351442) (xy 1.144423 -25.408636)
			(xy 1.14012 -25.46583) (xy 1.127305 -25.521735) (xy 1.106268 -25.575093) (xy 1.077482 -25.624702)
			(xy 1.059942 -25.647396) (xy 1.047496 -25.66289) (xy 1.016 -25.745694) (xy 1.016 -29.19984) (xy 11.343394 -29.19984)
			(xy 11.347396 -28.994751) (xy 11.359397 -28.789974) (xy 11.379379 -28.585822) (xy 11.40731 -28.382604)
			(xy 11.443149 -28.180632) (xy 11.486841 -27.980211) (xy 11.53832 -27.781647) (xy 11.597506 -27.585243)
			(xy 11.66431 -27.391298) (xy 11.73863 -27.200107) (xy 11.820354 -27.011962) (xy 11.909355 -26.827148)
			(xy 12.0055 -26.645947) (xy 12.108641 -26.468635) (xy 12.218622 -26.295483) (xy 12.335274 -26.126753)
			(xy 12.458421 -25.962704) (xy 12.587875 -25.803583) (xy 12.723439 -25.649635) (xy 12.864906 -25.501094)
			(xy 13.01206 -25.358184) (xy 13.164678 -25.221125) (xy 13.322528 -25.090125) (xy 13.485368 -24.965384)
			(xy 13.652952 -24.84709) (xy 13.825023 -24.735426) (xy 14.00132 -24.630559) (xy 14.181574 -24.532651)
			(xy 14.365511 -24.441851) (xy 14.55285 -24.358296) (xy 14.743307 -24.282114) (xy 14.936591 -24.213421)
			(xy 15.132408 -24.152321) (xy 15.33046 -24.098908) (xy 15.530445 -24.053262) (xy 15.732059 -24.015455)
			(xy 15.934994 -23.985542) (xy 16.138942 -23.963569) (xy 16.343591 -23.949571) (xy 16.548632 -23.943568)
			(xy 16.75375 -23.945569) (xy 16.958634 -23.955572) (xy 17.162971 -23.973561) (xy 17.366452 -23.999508)
			(xy 17.568765 -24.033375) (xy 17.769602 -24.075109) (xy 17.968659 -24.124648) (xy 18.165631 -24.181915)
			(xy 18.360218 -24.246824) (xy 18.552125 -24.319276) (xy 18.741059 -24.399159) (xy 18.926733 -24.486354)
			(xy 19.108863 -24.580726) (xy 19.287172 -24.682132) (xy 19.461389 -24.790418) (xy 19.631249 -24.905419)
			(xy 19.796492 -25.02696) (xy 19.956868 -25.154855) (xy 20.112131 -25.28891) (xy 20.262046 -25.428921)
			(xy 20.406384 -25.574674) (xy 20.544926 -25.725948) (xy 20.67746 -25.882512) (xy 20.803784 -26.044128)
			(xy 20.923707 -26.210549) (xy 21.037045 -26.381523) (xy 21.143626 -26.556788) (xy 21.243288 -26.736078)
			(xy 21.335879 -26.91912) (xy 21.421258 -27.105636) (xy 21.499294 -27.29534) (xy 21.56987 -27.487945)
			(xy 21.632877 -27.683157) (xy 21.68822 -27.880678) (xy 21.735814 -28.080208) (xy 21.775588 -28.281443)
			(xy 21.807479 -28.484077) (xy 21.83144 -28.687801) (xy 21.847435 -28.892304) (xy 21.855438 -29.097276)
			(xy 21.855938 -29.19984) (xy 21.855438 -29.302404) (xy 21.847435 -29.507376) (xy 21.83144 -29.711879)
			(xy 21.807479 -29.915603) (xy 21.775588 -30.118237) (xy 21.735814 -30.319472) (xy 21.68822 -30.519002)
			(xy 21.632877 -30.716523) (xy 21.56987 -30.911735) (xy 21.499294 -31.10434) (xy 21.421258 -31.294044)
			(xy 21.335879 -31.48056) (xy 21.243288 -31.663602) (xy 21.143626 -31.842892) (xy 21.037045 -32.018157)
			(xy 20.923707 -32.189131) (xy 20.844063 -32.299656) (xy 72.856858 -32.299656) (xy 72.860873 -32.096474)
			(xy 72.872912 -31.893609) (xy 72.892956 -31.691379) (xy 72.920974 -31.490098) (xy 72.956922 -31.290081)
			(xy 73.000744 -31.09164) (xy 73.052371 -30.895086) (xy 73.111723 -30.700725) (xy 73.178708 -30.50886)
			(xy 73.25322 -30.319791) (xy 73.335143 -30.133814) (xy 73.42435 -29.951218) (xy 73.520701 -29.772289)
			(xy 73.624045 -29.597307) (xy 73.734222 -29.426544) (xy 73.851059 -29.260266) (xy 73.974374 -29.098735)
			(xy 74.103974 -28.942201) (xy 74.239657 -28.79091) (xy 74.381212 -28.645097) (xy 74.528416 -28.50499)
			(xy 74.68104 -28.370808) (xy 74.838847 -28.24276) (xy 75.001589 -28.121047) (xy 75.169012 -28.005859)
			(xy 75.340855 -27.897374) (xy 75.51685 -27.795763) (xy 75.696722 -27.701185) (xy 75.88019 -27.613786)
			(xy 76.066968 -27.533704) (xy 76.256764 -27.461064) (xy 76.449281 -27.395978) (xy 76.644219 -27.338549)
			(xy 76.841274 -27.288866) (xy 77.040138 -27.247006) (xy 77.2405 -27.213036) (xy 77.442048 -27.187008)
			(xy 77.644467 -27.168963) (xy 77.84744 -27.158929) (xy 78.050652 -27.156921) (xy 78.253784 -27.162943)
			(xy 78.45652 -27.176986) (xy 78.658543 -27.199027) (xy 78.859537 -27.229032) (xy 79.059189 -27.266954)
			(xy 79.257187 -27.312734) (xy 79.453222 -27.3663) (xy 79.646987 -27.42757) (xy 79.838181 -27.496446)
			(xy 80.026504 -27.572823) (xy 80.211663 -27.656579) (xy 80.393369 -27.747586) (xy 80.571337 -27.845699)
			(xy 80.74529 -27.950768) (xy 80.914957 -28.062626) (xy 81.080071 -28.1811) (xy 81.240377 -28.306005)
			(xy 81.395623 -28.437145) (xy 81.545566 -28.574316) (xy 81.689974 -28.717304) (xy 81.828619 -28.865885)
			(xy 81.961287 -29.019828) (xy 82.087769 -29.178891) (xy 82.207869 -29.342828) (xy 82.321398 -29.511381)
			(xy 82.428179 -29.684288) (xy 82.528046 -29.861278) (xy 82.620843 -30.042075) (xy 82.706425 -30.226398)
			(xy 82.784658 -30.413957) (xy 82.85542 -30.604461) (xy 82.918601 -30.797612) (xy 82.974101 -30.993108)
			(xy 83.021835 -31.190644) (xy 83.061728 -31.389912) (xy 83.093717 -31.5906) (xy 83.117753 -31.792395)
			(xy 83.133798 -31.994982) (xy 83.141826 -32.198045) (xy 83.142328 -32.299656) (xy 83.141826 -32.401267)
			(xy 83.133798 -32.60433) (xy 83.117753 -32.806917) (xy 83.093717 -33.008712) (xy 83.061728 -33.2094)
			(xy 83.021835 -33.408668) (xy 82.974101 -33.606204) (xy 82.918601 -33.8017) (xy 82.85542 -33.994851)
			(xy 82.784658 -34.185355) (xy 82.706425 -34.372914) (xy 82.620843 -34.557237) (xy 82.528046 -34.738034)
			(xy 82.428179 -34.915024) (xy 82.321398 -35.087931) (xy 82.207869 -35.256484) (xy 82.087769 -35.420421)
			(xy 81.961287 -35.579484) (xy 81.828619 -35.733427) (xy 81.689974 -35.882008) (xy 81.545566 -36.024996)
			(xy 81.395623 -36.162167) (xy 81.240377 -36.293307) (xy 81.080071 -36.418212) (xy 80.914957 -36.536686)
			(xy 80.74529 -36.648544) (xy 80.571337 -36.753613) (xy 80.393369 -36.851726) (xy 80.211663 -36.942733)
			(xy 80.026504 -37.026489) (xy 79.838181 -37.102866) (xy 79.646987 -37.171742) (xy 79.453222 -37.233012)
			(xy 79.257187 -37.286578) (xy 79.059189 -37.332358) (xy 78.859537 -37.37028) (xy 78.658543 -37.400285)
			(xy 78.45652 -37.422326) (xy 78.253784 -37.436369) (xy 78.050652 -37.442391) (xy 77.84744 -37.440383)
			(xy 77.644467 -37.430349) (xy 77.442048 -37.412304) (xy 77.2405 -37.386276) (xy 77.040138 -37.352306)
			(xy 76.841274 -37.310446) (xy 76.644219 -37.260763) (xy 76.449281 -37.203334) (xy 76.256764 -37.138248)
			(xy 76.066968 -37.065608) (xy 75.88019 -36.985526) (xy 75.696722 -36.898127) (xy 75.51685 -36.803549)
			(xy 75.340855 -36.701938) (xy 75.169012 -36.593453) (xy 75.001589 -36.478265) (xy 74.838847 -36.356552)
			(xy 74.68104 -36.228504) (xy 74.528416 -36.094322) (xy 74.381212 -35.954215) (xy 74.239657 -35.808402)
			(xy 74.103974 -35.657111) (xy 73.974374 -35.500577) (xy 73.851059 -35.339046) (xy 73.734222 -35.172768)
			(xy 73.624045 -35.002005) (xy 73.520701 -34.827023) (xy 73.42435 -34.648094) (xy 73.335143 -34.465498)
			(xy 73.25322 -34.279521) (xy 73.178708 -34.090452) (xy 73.111723 -33.898587) (xy 73.052371 -33.704226)
			(xy 73.000744 -33.507672) (xy 72.956922 -33.309231) (xy 72.920974 -33.109214) (xy 72.892956 -32.907933)
			(xy 72.872912 -32.705703) (xy 72.860873 -32.502838) (xy 72.856858 -32.299656) (xy 20.844063 -32.299656)
			(xy 20.803784 -32.355552) (xy 20.67746 -32.517168) (xy 20.544926 -32.673732) (xy 20.406384 -32.825006)
			(xy 20.262046 -32.970759) (xy 20.112131 -33.11077) (xy 19.956868 -33.244825) (xy 19.796492 -33.37272)
			(xy 19.631249 -33.494261) (xy 19.461389 -33.609262) (xy 19.287172 -33.717548) (xy 19.108863 -33.818954)
			(xy 18.926733 -33.913326) (xy 18.741059 -34.000521) (xy 18.552125 -34.080404) (xy 18.360218 -34.152856)
			(xy 18.165631 -34.217765) (xy 17.968659 -34.275032) (xy 17.769602 -34.324571) (xy 17.568765 -34.366305)
			(xy 17.366452 -34.400172) (xy 17.162971 -34.426119) (xy 16.958634 -34.444108) (xy 16.75375 -34.454111)
			(xy 16.548632 -34.456112) (xy 16.343591 -34.450109) (xy 16.138942 -34.436111) (xy 15.934994 -34.414138)
			(xy 15.732059 -34.384225) (xy 15.530445 -34.346418) (xy 15.33046 -34.300772) (xy 15.132408 -34.247359)
			(xy 14.936591 -34.186259) (xy 14.743307 -34.117566) (xy 14.55285 -34.041384) (xy 14.365511 -33.957829)
			(xy 14.181574 -33.867029) (xy 14.00132 -33.769121) (xy 13.825023 -33.664254) (xy 13.652952 -33.55259)
			(xy 13.485368 -33.434296) (xy 13.322528 -33.309555) (xy 13.164678 -33.178555) (xy 13.01206 -33.041496)
			(xy 12.864906 -32.898586) (xy 12.723439 -32.750045) (xy 12.587875 -32.596097) (xy 12.458421 -32.436976)
			(xy 12.335274 -32.272927) (xy 12.218622 -32.104197) (xy 12.108641 -31.931045) (xy 12.0055 -31.753733)
			(xy 11.909355 -31.572532) (xy 11.820354 -31.387718) (xy 11.73863 -31.199573) (xy 11.66431 -31.008382)
			(xy 11.597506 -30.814437) (xy 11.53832 -30.618033) (xy 11.486841 -30.419469) (xy 11.443149 -30.219048)
			(xy 11.40731 -30.017076) (xy 11.379379 -29.813858) (xy 11.359397 -29.609706) (xy 11.347396 -29.404929)
			(xy 11.343394 -29.19984) (xy 1.016 -29.19984) (xy 1.016 -37.771578) (xy 1.047496 -37.854382) (xy 1.059942 -37.869876)
			(xy 1.077482 -37.89257) (xy 1.106268 -37.942179) (xy 1.127305 -37.995537) (xy 1.14012 -38.051442)
			(xy 1.144423 -38.108636) (xy 1.14012 -38.16583) (xy 1.127305 -38.221735) (xy 1.106268 -38.275093)
			(xy 1.077482 -38.324702) (xy 1.059942 -38.347396) (xy 1.047496 -38.36289) (xy 1.016 -38.445694) (xy 1.016 -44.95546)
			(xy 1.016504 -44.9788) (xy 1.024982 -45.024704) (xy 1.041699 -45.068287) (xy 1.066094 -45.108085)
			(xy 1.097346 -45.142758) (xy 1.134405 -45.171142) (xy 1.176024 -45.192281) (xy 1.220803 -45.205465)
			(xy 1.267237 -45.210249) (xy 1.313763 -45.206474) (xy 1.358818 -45.194266) (xy 1.400886 -45.174035)
			(xy 1.438552 -45.146463) (xy 1.47055 -45.112476) (xy 1.483614 -45.093128) (xy 1.51897 -45.039192)
			(xy 1.595424 -44.935316) (xy 1.678157 -44.836368) (xy 1.766854 -44.742728) (xy 1.861173 -44.654754)
			(xy 1.960754 -44.572785) (xy 2.065216 -44.497132) (xy 2.174158 -44.428087) (xy 2.287162 -44.365914)
			(xy 2.403796 -44.310851) (xy 2.523614 -44.263109) (xy 2.646155 -44.22287) (xy 2.770951 -44.19029)
			(xy 2.897523 -44.165492) (xy 3.025387 -44.148573) (xy 3.154053 -44.139596) (xy 3.283028 -44.138596)
			(xy 3.411818 -44.145576) (xy 3.539929 -44.160511) (xy 3.66687 -44.183343) (xy 3.792157 -44.213984)
			(xy 3.915307 -44.252318) (xy 4.03585 -44.298196) (xy 4.153324 -44.351444) (xy 4.267279 -44.411858)
			(xy 4.377278 -44.479205) (xy 4.482901 -44.553229) (xy 4.583741 -44.633645) (xy 4.679413 -44.720145)
			(xy 4.769551 -44.812398) (xy 4.853809 -44.910051) (xy 4.931864 -45.01273) (xy 5.003418 -45.12004)
			(xy 5.068196 -45.231572) (xy 5.12595 -45.346897) (xy 5.176459 -45.465575) (xy 5.219529 -45.58715)
			(xy 5.254996 -45.711156) (xy 5.282723 -45.83712) (xy 5.302604 -45.964557) (xy 5.314563 -46.09298)
			(xy 5.318555 -46.221897) (xy 5.318555 -46.221904) (xy 12.580624 -46.221904) (xy 12.584655 -46.092338)
			(xy 12.596734 -45.963274) (xy 12.616813 -45.83521) (xy 12.644815 -45.708643) (xy 12.680632 -45.58406)
			(xy 12.724124 -45.461946) (xy 12.775124 -45.342772) (xy 12.833435 -45.226999) (xy 12.89883 -45.115075)
			(xy 12.971057 -45.007433) (xy 13.049837 -44.90449) (xy 13.134864 -44.806644) (xy 13.225809 -44.714272)
			(xy 13.322321 -44.627734) (xy 13.424027 -44.547363) (xy 13.530533 -44.473471) (xy 13.641426 -44.406343)
			(xy 13.756278 -44.346239) (xy 13.874645 -44.293392) (xy 13.996068 -44.248005) (xy 14.120078 -44.210256)
			(xy 14.246195 -44.180289) (xy 14.373931 -44.15822) (xy 14.502792 -44.144136) (xy 14.632279 -44.13809)
			(xy 14.761892 -44.140106) (xy 14.891128 -44.150176) (xy 15.019489 -44.168261) (xy 15.146477 -44.194291)
			(xy 15.271601 -44.228166) (xy 15.394377 -44.269754) (xy 15.51433 -44.318895) (xy 15.630995 -44.375398)
			(xy 15.743923 -44.439045) (xy 15.852675 -44.509589) (xy 15.956831 -44.586758) (xy 16.055988 -44.670253)
			(xy 16.149762 -44.759751) (xy 16.237791 -44.854906) (xy 16.319734 -44.955349) (xy 16.395273 -45.060692)
			(xy 16.464118 -45.170528) (xy 16.526001 -45.284432) (xy 16.580682 -45.401962) (xy 16.627952 -45.522665)
			(xy 16.667625 -45.646073) (xy 16.69955 -45.771709) (xy 16.723602 -45.899086) (xy 16.739689 -46.027712)
			(xy 16.747748 -46.15709) (xy 16.748252 -46.221904) (xy 16.747748 -46.286718) (xy 16.739689 -46.416096)
			(xy 16.723602 -46.544722) (xy 16.69955 -46.672099) (xy 16.667625 -46.797735) (xy 16.627952 -46.921143)
			(xy 16.580682 -47.041846) (xy 16.526001 -47.159376) (xy 16.464118 -47.27328) (xy 16.395273 -47.383116)
			(xy 16.319734 -47.488459) (xy 16.237791 -47.588902) (xy 16.149762 -47.684057) (xy 16.055988 -47.773555)
			(xy 15.956831 -47.85705) (xy 15.852675 -47.934219) (xy 15.743923 -48.004763) (xy 15.630995 -48.06841)
			(xy 15.51433 -48.124913) (xy 15.394377 -48.174054) (xy 15.271601 -48.215642) (xy 15.146477 -48.249517)
			(xy 15.019489 -48.275547) (xy 14.891128 -48.293632) (xy 14.761892 -48.303702) (xy 14.632279 -48.305718)
			(xy 14.502792 -48.299672) (xy 14.373931 -48.285588) (xy 14.246195 -48.263519) (xy 14.120078 -48.233552)
			(xy 13.996068 -48.195803) (xy 13.874645 -48.150416) (xy 13.756278 -48.097569) (xy 13.641426 -48.037465)
			(xy 13.530533 -47.970337) (xy 13.424027 -47.896445) (xy 13.322321 -47.816074) (xy 13.225809 -47.729536)
			(xy 13.134864 -47.637164) (xy 13.049837 -47.539318) (xy 12.971057 -47.436375) (xy 12.89883 -47.328733)
			(xy 12.833435 -47.216809) (xy 12.775124 -47.101036) (xy 12.724124 -46.981862) (xy 12.680632 -46.859748)
			(xy 12.644815 -46.735165) (xy 12.616813 -46.608598) (xy 12.596734 -46.480534) (xy 12.584655 -46.35147)
			(xy 12.580624 -46.221904) (xy 5.318555 -46.221904) (xy 5.314564 -46.350814) (xy 5.302605 -46.479237)
			(xy 5.282724 -46.606674) (xy 5.254997 -46.732637) (xy 5.219531 -46.856644) (xy 5.176461 -46.978219)
			(xy 5.125953 -47.096896) (xy 5.068199 -47.212222) (xy 5.003422 -47.323754) (xy 4.931868 -47.431065)
			(xy 4.853813 -47.533744) (xy 4.769556 -47.631397) (xy 4.679418 -47.72365) (xy 4.583746 -47.810151)
			(xy 4.482906 -47.890567) (xy 4.377284 -47.964591) (xy 4.267285 -48.031939) (xy 4.15333 -48.092353)
			(xy 4.035857 -48.145601) (xy 3.915313 -48.19148) (xy 3.792163 -48.229814) (xy 3.666877 -48.260455)
			(xy 3.539935 -48.283288) (xy 3.411824 -48.298223) (xy 3.283035 -48.305204) (xy 3.15406 -48.304205)
			(xy 3.025394 -48.295228) (xy 2.89753 -48.278309) (xy 2.770957 -48.253512) (xy 2.646161 -48.220932)
			(xy 2.52362 -48.180694) (xy 2.403802 -48.132952) (xy 2.287168 -48.077889) (xy 2.174163 -48.015716)
			(xy 2.065222 -47.946672) (xy 1.96076 -47.87102) (xy 1.861178 -47.78905) (xy 1.766858 -47.701077)
			(xy 1.678162 -47.607437) (xy 1.595428 -47.50849) (xy 1.518974 -47.404613) (xy 1.483614 -47.35068)
			(xy 1.470543 -47.331338) (xy 1.438545 -47.297353) (xy 1.40088 -47.269783) (xy 1.358813 -47.249554)
			(xy 1.31376 -47.237347) (xy 1.267235 -47.233573) (xy 1.220803 -47.238357) (xy 1.176026 -47.25154)
			(xy 1.134409 -47.272678) (xy 1.097351 -47.301059) (xy 1.066099 -47.335731) (xy 1.041704 -47.375527)
			(xy 1.024986 -47.419108) (xy 1.016507 -47.465009) (xy 1.016 -47.488348) (xy 1.016 -50.471578) (xy 1.047496 -50.554382)
			(xy 1.059942 -50.569876) (xy 1.077482 -50.59257) (xy 1.106268 -50.642179) (xy 1.127305 -50.695537)
			(xy 1.14012 -50.751442) (xy 1.144423 -50.808636) (xy 1.14012 -50.86583) (xy 1.127305 -50.921735)
			(xy 1.106268 -50.975093) (xy 1.077482 -51.024702) (xy 1.059942 -51.047396) (xy 1.047496 -51.06289)
			(xy 1.016 -51.145694) (xy 1.016 -51.36007) (xy 39.818063 -51.36007) (xy 39.82207 -51.244046) (xy 39.834072 -51.128574)
			(xy 39.854012 -51.014206) (xy 39.881795 -50.901486) (xy 39.917289 -50.790952) (xy 39.960324 -50.683129)
			(xy 40.010695 -50.578532) (xy 40.068162 -50.47766) (xy 40.132452 -50.380993) (xy 40.203257 -50.288992)
			(xy 40.280241 -50.202095) (xy 40.363037 -50.120716) (xy 40.45125 -50.045243) (xy 40.54446 -49.976036)
			(xy 40.642223 -49.913424) (xy 40.744072 -49.857707) (xy 40.849522 -49.809149) (xy 40.958071 -49.767981)
			(xy 41.069202 -49.734401) (xy 41.182385 -49.708568) (xy 41.29708 -49.690605) (xy 41.412742 -49.680597)
			(xy 41.528818 -49.678594) (xy 41.644756 -49.684603) (xy 41.760003 -49.698596) (xy 41.874009 -49.720507)
			(xy 41.986233 -49.750232) (xy 42.096139 -49.787628) (xy 42.203202 -49.832517) (xy 42.306914 -49.884686)
			(xy 42.406779 -49.943886) (xy 42.502322 -50.009835) (xy 42.593088 -50.082218) (xy 42.678643 -50.160691)
			(xy 42.758581 -50.244879) (xy 42.83252 -50.334381) (xy 42.900108 -50.428772) (xy 42.961022 -50.5276)
			(xy 43.014974 -50.630396) (xy 43.061704 -50.736669) (xy 43.100992 -50.845913) (xy 43.132649 -50.957606)
			(xy 43.156525 -51.071218) (xy 43.172506 -51.186206) (xy 43.180515 -51.302023) (xy 43.181016 -51.36007)
			(xy 43.180515 -51.418117) (xy 43.172506 -51.533934) (xy 43.156525 -51.648922) (xy 43.132649 -51.762534)
			(xy 43.100992 -51.874227) (xy 43.061704 -51.983471) (xy 43.014974 -52.089744) (xy 42.961022 -52.19254)
			(xy 42.900108 -52.291368) (xy 42.83252 -52.385759) (xy 42.758581 -52.475261) (xy 42.678643 -52.559449)
			(xy 42.593088 -52.637922) (xy 42.502604 -52.71008) (xy 93.154506 -52.71008) (xy 93.158522 -52.59381)
			(xy 93.170549 -52.478095) (xy 93.190531 -52.363485) (xy 93.218373 -52.250526) (xy 93.253942 -52.139758)
			(xy 93.297068 -52.031707) (xy 93.347545 -51.926889) (xy 93.405134 -51.825804) (xy 93.46956 -51.728932)
			(xy 93.540515 -51.636736) (xy 93.617662 -51.549655) (xy 93.700633 -51.468104) (xy 93.789033 -51.392472)
			(xy 93.88244 -51.323118) (xy 93.980409 -51.260375) (xy 94.082473 -51.204539) (xy 94.188147 -51.155878)
			(xy 94.296926 -51.114624) (xy 94.408291 -51.080973) (xy 94.521714 -51.055085) (xy 94.636651 -51.037084)
			(xy 94.752557 -51.027055) (xy 94.868879 -51.025047) (xy 94.985062 -51.031069) (xy 95.100553 -51.045092)
			(xy 95.214801 -51.06705) (xy 95.327262 -51.096837) (xy 95.4374 -51.134312) (xy 95.54469 -51.179297)
			(xy 95.648621 -51.231576) (xy 95.748697 -51.290901) (xy 95.844443 -51.356989) (xy 95.9354 -51.429525)
			(xy 96.021136 -51.508164) (xy 96.101243 -51.59253) (xy 96.175339 -51.682222) (xy 96.243069 -51.776812)
			(xy 96.304113 -51.87585) (xy 96.358178 -51.978863) (xy 96.405008 -52.08536) (xy 96.444379 -52.194835)
			(xy 96.476103 -52.306765) (xy 96.500029 -52.420617) (xy 96.516043 -52.535849) (xy 96.52407 -52.651911)
			(xy 96.524572 -52.71008) (xy 96.52407 -52.768249) (xy 96.516043 -52.884311) (xy 96.500029 -52.999543)
			(xy 96.476103 -53.113395) (xy 96.444379 -53.225325) (xy 96.405008 -53.3348) (xy 96.358178 -53.441297)
			(xy 96.304113 -53.54431) (xy 96.243069 -53.643348) (xy 96.175339 -53.737938) (xy 96.101243 -53.82763)
			(xy 96.021136 -53.911996) (xy 95.9354 -53.990635) (xy 95.844443 -54.063171) (xy 95.748697 -54.129259)
			(xy 95.648621 -54.188584) (xy 95.54469 -54.240863) (xy 95.4374 -54.285848) (xy 95.327262 -54.323323)
			(xy 95.214801 -54.35311) (xy 95.100553 -54.375068) (xy 94.985062 -54.389091) (xy 94.868879 -54.395113)
			(xy 94.752557 -54.393105) (xy 94.636651 -54.383076) (xy 94.521714 -54.365075) (xy 94.408291 -54.339187)
			(xy 94.296926 -54.305536) (xy 94.188147 -54.264282) (xy 94.082473 -54.215621) (xy 93.980409 -54.159785)
			(xy 93.88244 -54.097042) (xy 93.789033 -54.027688) (xy 93.700633 -53.952056) (xy 93.617662 -53.870505)
			(xy 93.540515 -53.783424) (xy 93.46956 -53.691228) (xy 93.405134 -53.594356) (xy 93.347545 -53.493271)
			(xy 93.297068 -53.388453) (xy 93.253942 -53.280402) (xy 93.218373 -53.169634) (xy 93.190531 -53.056675)
			(xy 93.170549 -52.942065) (xy 93.158522 -52.82635) (xy 93.154506 -52.71008) (xy 42.502604 -52.71008)
			(xy 42.502322 -52.710305) (xy 42.406779 -52.776254) (xy 42.306914 -52.835454) (xy 42.203202 -52.887623)
			(xy 42.096139 -52.932512) (xy 41.986233 -52.969908) (xy 41.874009 -52.999633) (xy 41.760003 -53.021544)
			(xy 41.644756 -53.035537) (xy 41.528818 -53.041546) (xy 41.412742 -53.039543) (xy 41.29708 -53.029535)
			(xy 41.182385 -53.011572) (xy 41.069202 -52.985739) (xy 40.958071 -52.952159) (xy 40.849522 -52.910991)
			(xy 40.744072 -52.862433) (xy 40.642223 -52.806716) (xy 40.54446 -52.744104) (xy 40.45125 -52.674897)
			(xy 40.363037 -52.599424) (xy 40.280241 -52.518045) (xy 40.203257 -52.431148) (xy 40.132452 -52.339147)
			(xy 40.068162 -52.24248) (xy 40.010695 -52.141608) (xy 39.960324 -52.037011) (xy 39.917289 -51.929188)
			(xy 39.881795 -51.818654) (xy 39.854012 -51.705934) (xy 39.834072 -51.591566) (xy 39.82207 -51.476094)
			(xy 39.818063 -51.36007) (xy 1.016 -51.36007) (xy 1.016 -63.171578) (xy 1.047496 -63.254382) (xy 1.059942 -63.269876)
			(xy 1.077482 -63.29257) (xy 1.106268 -63.342179) (xy 1.127305 -63.395537) (xy 1.14012 -63.451442)
			(xy 1.144423 -63.508636) (xy 1.14012 -63.56583) (xy 1.127305 -63.621735) (xy 1.106268 -63.675093)
			(xy 1.077482 -63.724702) (xy 1.059942 -63.747396) (xy 1.047496 -63.76289) (xy 1.016 -63.845694) (xy 1.016 -64.46012)
			(xy 86.877404 -64.46012) (xy 86.881424 -64.269469) (xy 86.893478 -64.079156) (xy 86.913544 -63.889521)
			(xy 86.941587 -63.7009) (xy 86.977556 -63.51363) (xy 87.021388 -63.328042) (xy 87.073005 -63.144467)
			(xy 87.132315 -62.963231) (xy 87.199213 -62.784656) (xy 87.273579 -62.609061) (xy 87.355281 -62.436756)
			(xy 87.444175 -62.268049) (xy 87.540101 -62.103239) (xy 87.64289 -61.94262) (xy 87.752359 -61.786477)
			(xy 87.868313 -61.635088) (xy 87.990547 -61.488721) (xy 88.118841 -61.347637) (xy 88.252969 -61.212088)
			(xy 88.392693 -61.082313) (xy 88.537763 -60.958543) (xy 88.687921 -60.841) (xy 88.842902 -60.729891)
			(xy 89.002429 -60.625414) (xy 89.166218 -60.527755) (xy 89.333978 -60.437088) (xy 89.505412 -60.353574)
			(xy 89.680214 -60.277361) (xy 89.858073 -60.208585) (xy 90.038674 -60.147367) (xy 90.221694 -60.093818)
			(xy 90.40681 -60.048032) (xy 90.593691 -60.01009) (xy 90.782006 -59.980061) (xy 90.971419 -59.957996)
			(xy 91.161593 -59.943937) (xy 91.352192 -59.937907) (xy 91.542875 -59.939917) (xy 91.733304 -59.949964)
			(xy 91.92314 -59.96803) (xy 92.112046 -59.994083) (xy 92.299685 -60.028076) (xy 92.485725 -60.069949)
			(xy 92.669834 -60.119628) (xy 92.851685 -60.177024) (xy 93.030955 -60.242035) (xy 93.207325 -60.314546)
			(xy 93.380481 -60.394427) (xy 93.550116 -60.481537) (xy 93.715928 -60.575721) (xy 93.877622 -60.676812)
			(xy 94.03491 -60.784628) (xy 94.187513 -60.89898) (xy 94.335161 -61.019663) (xy 94.477589 -61.146464)
			(xy 94.614545 -61.279155) (xy 94.745786 -61.417503) (xy 94.871078 -61.56126) (xy 94.990198 -61.710171)
			(xy 95.102934 -61.863972) (xy 95.209087 -62.022388) (xy 95.308467 -62.185139) (xy 95.400897 -62.351934)
			(xy 95.486214 -62.522478) (xy 95.564266 -62.696466) (xy 95.634913 -62.873591) (xy 95.698031 -63.053536)
			(xy 95.753507 -63.235982) (xy 95.801242 -63.420605) (xy 95.841152 -63.607075) (xy 95.873165 -63.795063)
			(xy 95.897225 -63.984233) (xy 95.913288 -64.174249) (xy 95.921327 -64.364773) (xy 95.92183 -64.46012)
			(xy 95.921327 -64.555467) (xy 95.913288 -64.745991) (xy 95.897225 -64.936007) (xy 95.873165 -65.125177)
			(xy 95.841152 -65.313165) (xy 95.801242 -65.499635) (xy 95.753507 -65.684258) (xy 95.698031 -65.866704)
			(xy 95.634913 -66.046649) (xy 95.564266 -66.223774) (xy 95.486214 -66.397762) (xy 95.400897 -66.568306)
			(xy 95.308467 -66.735101) (xy 95.209087 -66.897852) (xy 95.102934 -67.056268) (xy 94.990198 -67.210069)
			(xy 94.871078 -67.35898) (xy 94.745786 -67.502737) (xy 94.614545 -67.641085) (xy 94.477589 -67.773776)
			(xy 94.335161 -67.900577) (xy 94.187513 -68.02126) (xy 94.03491 -68.135612) (xy 93.877622 -68.243428)
			(xy 93.715928 -68.344519) (xy 93.550116 -68.438703) (xy 93.380481 -68.525813) (xy 93.207325 -68.605694)
			(xy 93.030955 -68.678205) (xy 92.851685 -68.743216) (xy 92.669834 -68.800612) (xy 92.485725 -68.850291)
			(xy 92.299685 -68.892164) (xy 92.112046 -68.926157) (xy 91.92314 -68.95221) (xy 91.733304 -68.970276)
			(xy 91.542875 -68.980323) (xy 91.352192 -68.982333) (xy 91.161593 -68.976303) (xy 90.971419 -68.962244)
			(xy 90.782006 -68.940179) (xy 90.593691 -68.91015) (xy 90.40681 -68.872208) (xy 90.221694 -68.826422)
			(xy 90.038674 -68.772873) (xy 89.858073 -68.711655) (xy 89.680214 -68.642879) (xy 89.505412 -68.566666)
			(xy 89.333978 -68.483152) (xy 89.166218 -68.392485) (xy 89.002429 -68.294826) (xy 88.842902 -68.190349)
			(xy 88.687921 -68.07924) (xy 88.537763 -67.961697) (xy 88.392693 -67.837927) (xy 88.252969 -67.708152)
			(xy 88.118841 -67.572603) (xy 87.990547 -67.431519) (xy 87.868313 -67.285152) (xy 87.752359 -67.133763)
			(xy 87.64289 -66.97762) (xy 87.540101 -66.817001) (xy 87.444175 -66.652191) (xy 87.355281 -66.483484)
			(xy 87.273579 -66.311179) (xy 87.199213 -66.135584) (xy 87.132315 -65.957009) (xy 87.073005 -65.775773)
			(xy 87.021388 -65.592198) (xy 86.977556 -65.40661) (xy 86.941587 -65.21934) (xy 86.913544 -65.030719)
			(xy 86.893478 -64.841084) (xy 86.881424 -64.650771) (xy 86.877404 -64.46012) (xy 1.016 -64.46012)
			(xy 1.016 -67.01155) (xy 1.016504 -67.03489) (xy 1.024982 -67.080794) (xy 1.041699 -67.124377) (xy 1.066094 -67.164175)
			(xy 1.097346 -67.198848) (xy 1.134405 -67.227232) (xy 1.176024 -67.248371) (xy 1.220803 -67.261555)
			(xy 1.267237 -67.266339) (xy 1.313763 -67.262564) (xy 1.358818 -67.250356) (xy 1.400886 -67.230125)
			(xy 1.438552 -67.202553) (xy 1.47055 -67.168566) (xy 1.483614 -67.149218) (xy 1.51897 -67.095282)
			(xy 1.595424 -66.991406) (xy 1.678157 -66.892458) (xy 1.766854 -66.798818) (xy 1.861173 -66.710844)
			(xy 1.960754 -66.628875) (xy 2.065216 -66.553222) (xy 2.174158 -66.484177) (xy 2.287162 -66.422004)
			(xy 2.403796 -66.366941) (xy 2.523614 -66.319199) (xy 2.646155 -66.27896) (xy 2.770951 -66.24638)
			(xy 2.897523 -66.221582) (xy 3.025387 -66.204663) (xy 3.154053 -66.195686) (xy 3.283028 -66.194686)
			(xy 3.411818 -66.201666) (xy 3.539929 -66.216601) (xy 3.66687 -66.239433) (xy 3.792157 -66.270074)
			(xy 3.915307 -66.308408) (xy 4.03585 -66.354286) (xy 4.153324 -66.407534) (xy 4.267279 -66.467948)
			(xy 4.377278 -66.535295) (xy 4.482901 -66.609319) (xy 4.583741 -66.689735) (xy 4.679413 -66.776235)
			(xy 4.769551 -66.868488) (xy 4.853809 -66.966141) (xy 4.931864 -67.06882) (xy 5.003418 -67.17613)
			(xy 5.068196 -67.287662) (xy 5.12595 -67.402987) (xy 5.176459 -67.521665) (xy 5.219529 -67.64324)
			(xy 5.254996 -67.767246) (xy 5.282723 -67.89321) (xy 5.302604 -68.020647) (xy 5.314563 -68.14907)
			(xy 5.318555 -68.277987) (xy 5.318555 -68.277994) (xy 12.580624 -68.277994) (xy 12.584655 -68.148428)
			(xy 12.596734 -68.019364) (xy 12.616813 -67.8913) (xy 12.644815 -67.764733) (xy 12.680632 -67.64015)
			(xy 12.724124 -67.518036) (xy 12.775124 -67.398862) (xy 12.833435 -67.283089) (xy 12.89883 -67.171165)
			(xy 12.971057 -67.063523) (xy 13.049837 -66.96058) (xy 13.134864 -66.862734) (xy 13.225809 -66.770362)
			(xy 13.322321 -66.683824) (xy 13.424027 -66.603453) (xy 13.530533 -66.529561) (xy 13.641426 -66.462433)
			(xy 13.756278 -66.402329) (xy 13.874645 -66.349482) (xy 13.996068 -66.304095) (xy 14.120078 -66.266346)
			(xy 14.246195 -66.236379) (xy 14.373931 -66.21431) (xy 14.502792 -66.200226) (xy 14.632279 -66.19418)
			(xy 14.761892 -66.196196) (xy 14.891128 -66.206266) (xy 15.019489 -66.224351) (xy 15.146477 -66.250381)
			(xy 15.271601 -66.284256) (xy 15.394377 -66.325844) (xy 15.51433 -66.374985) (xy 15.630995 -66.431488)
			(xy 15.743923 -66.495135) (xy 15.852675 -66.565679) (xy 15.956831 -66.642848) (xy 16.055988 -66.726343)
			(xy 16.149762 -66.815841) (xy 16.237791 -66.910996) (xy 16.319734 -67.011439) (xy 16.395273 -67.116782)
			(xy 16.464118 -67.226618) (xy 16.526001 -67.340522) (xy 16.580682 -67.458052) (xy 16.627952 -67.578755)
			(xy 16.667625 -67.702163) (xy 16.69955 -67.827799) (xy 16.723602 -67.955176) (xy 16.739689 -68.083802)
			(xy 16.747748 -68.21318) (xy 16.748252 -68.277994) (xy 16.747748 -68.342808) (xy 16.739689 -68.472186)
			(xy 16.723602 -68.600812) (xy 16.69955 -68.728189) (xy 16.667625 -68.853825) (xy 16.627952 -68.977233)
			(xy 16.580682 -69.097936) (xy 16.526001 -69.215466) (xy 16.464118 -69.32937) (xy 16.395273 -69.439206)
			(xy 16.319734 -69.544549) (xy 16.237791 -69.644992) (xy 16.149762 -69.740147) (xy 16.055988 -69.829645)
			(xy 15.956831 -69.91314) (xy 15.852675 -69.990309) (xy 15.743923 -70.060853) (xy 15.630995 -70.1245)
			(xy 15.51433 -70.181003) (xy 15.394377 -70.230144) (xy 15.271601 -70.271732) (xy 15.146477 -70.305607)
			(xy 15.019489 -70.331637) (xy 14.891128 -70.349722) (xy 14.761892 -70.359792) (xy 14.632279 -70.361808)
			(xy 14.502792 -70.355762) (xy 14.373931 -70.341678) (xy 14.246195 -70.319609) (xy 14.120078 -70.289642)
			(xy 13.996068 -70.251893) (xy 13.874645 -70.206506) (xy 13.756278 -70.153659) (xy 13.641426 -70.093555)
			(xy 13.530533 -70.026427) (xy 13.424027 -69.952535) (xy 13.322321 -69.872164) (xy 13.225809 -69.785626)
			(xy 13.134864 -69.693254) (xy 13.049837 -69.595408) (xy 12.971057 -69.492465) (xy 12.89883 -69.384823)
			(xy 12.833435 -69.272899) (xy 12.775124 -69.157126) (xy 12.724124 -69.037952) (xy 12.680632 -68.915838)
			(xy 12.644815 -68.791255) (xy 12.616813 -68.664688) (xy 12.596734 -68.536624) (xy 12.584655 -68.40756)
			(xy 12.580624 -68.277994) (xy 5.318555 -68.277994) (xy 5.314564 -68.406904) (xy 5.302605 -68.535327)
			(xy 5.282724 -68.662764) (xy 5.254997 -68.788727) (xy 5.219531 -68.912734) (xy 5.176461 -69.034309)
			(xy 5.125953 -69.152986) (xy 5.068199 -69.268312) (xy 5.003422 -69.379844) (xy 4.931868 -69.487155)
			(xy 4.853813 -69.589834) (xy 4.769556 -69.687487) (xy 4.679418 -69.77974) (xy 4.583746 -69.866241)
			(xy 4.482906 -69.946657) (xy 4.377284 -70.020681) (xy 4.267285 -70.088029) (xy 4.15333 -70.148443)
			(xy 4.035857 -70.201691) (xy 3.915313 -70.24757) (xy 3.792163 -70.285904) (xy 3.666877 -70.316545)
			(xy 3.539935 -70.339378) (xy 3.411824 -70.354313) (xy 3.283035 -70.361294) (xy 3.15406 -70.360295)
			(xy 3.025394 -70.351318) (xy 2.89753 -70.334399) (xy 2.770957 -70.309602) (xy 2.646161 -70.277022)
			(xy 2.52362 -70.236784) (xy 2.403802 -70.189042) (xy 2.287168 -70.133979) (xy 2.174163 -70.071806)
			(xy 2.065222 -70.002762) (xy 1.96076 -69.92711) (xy 1.861178 -69.84514) (xy 1.766858 -69.757167)
			(xy 1.678162 -69.663527) (xy 1.595428 -69.56458) (xy 1.518974 -69.460703) (xy 1.483614 -69.40677)
			(xy 1.470542 -69.387428) (xy 1.438544 -69.353445) (xy 1.400878 -69.325876) (xy 1.358811 -69.305648)
			(xy 1.313758 -69.293442) (xy 1.267234 -69.289667) (xy 1.220802 -69.294452) (xy 1.176025 -69.307634)
			(xy 1.134408 -69.328771) (xy 1.09735 -69.357153) (xy 1.066098 -69.391824) (xy 1.041702 -69.431618)
			(xy 1.024983 -69.475198) (xy 1.016503 -69.521099) (xy 1.016 -69.544438) (xy 1.016 -75.871578) (xy 1.047496 -75.954382)
			(xy 1.059942 -75.969876) (xy 1.077482 -75.99257) (xy 1.106268 -76.042179) (xy 1.127305 -76.095537)
			(xy 1.14012 -76.151442) (xy 1.144423 -76.208636) (xy 1.14012 -76.26583) (xy 1.127305 -76.321735)
			(xy 1.106268 -76.375093) (xy 1.077482 -76.424702) (xy 1.059942 -76.447396) (xy 1.047496 -76.46289)
			(xy 1.016 -76.545694) (xy 1.016 -78.378673) (xy 74.888081 -78.378673) (xy 74.888081 -78.220963) (xy 74.896069 -78.063456)
			(xy 74.912025 -77.906556) (xy 74.935906 -77.750665) (xy 74.967653 -77.596184) (xy 75.007183 -77.443509)
			(xy 75.054395 -77.293033) (xy 75.109169 -77.14514) (xy 75.171362 -77.000212) (xy 75.240817 -76.85862)
			(xy 75.317353 -76.720727) (xy 75.400776 -76.586888) (xy 75.49087 -76.457446) (xy 75.587405 -76.332733)
			(xy 75.690133 -76.21307) (xy 75.798789 -76.098763) (xy 75.913096 -75.990107) (xy 76.032759 -75.887379)
			(xy 76.157472 -75.790844) (xy 76.286914 -75.70075) (xy 76.420753 -75.617327) (xy 76.558646 -75.540791)
			(xy 76.700238 -75.471336) (xy 76.845166 -75.409143) (xy 76.993059 -75.354369) (xy 77.143535 -75.307157)
			(xy 77.29621 -75.267627) (xy 77.450691 -75.23588) (xy 77.606582 -75.211999) (xy 77.763482 -75.196043)
			(xy 77.920989 -75.188055) (xy 78.078699 -75.188055) (xy 78.236206 -75.196043) (xy 78.393106 -75.211999)
			(xy 78.548997 -75.23588) (xy 78.703478 -75.267627) (xy 78.856153 -75.307157) (xy 79.006629 -75.354369)
			(xy 79.154522 -75.409143) (xy 79.29945 -75.471336) (xy 79.441042 -75.540791) (xy 79.578935 -75.617327)
			(xy 79.712774 -75.70075) (xy 79.842216 -75.790844) (xy 79.966929 -75.887379) (xy 80.086592 -75.990107)
			(xy 80.200899 -76.098763) (xy 80.309555 -76.21307) (xy 80.412283 -76.332733) (xy 80.508818 -76.457446)
			(xy 80.598912 -76.586888) (xy 80.682335 -76.720727) (xy 80.758871 -76.85862) (xy 80.828326 -77.000212)
			(xy 80.890519 -77.14514) (xy 80.945293 -77.293033) (xy 80.992505 -77.443509) (xy 81.032035 -77.596184)
			(xy 81.063782 -77.750665) (xy 81.087663 -77.906556) (xy 81.103619 -78.063456) (xy 81.111607 -78.220963)
			(xy 81.112106 -78.299818) (xy 81.111607 -78.378673) (xy 81.103619 -78.53618) (xy 81.087663 -78.69308)
			(xy 81.063782 -78.848971) (xy 81.032035 -79.003452) (xy 80.992505 -79.156127) (xy 80.945293 -79.306603)
			(xy 80.890519 -79.454496) (xy 80.828326 -79.599424) (xy 80.758871 -79.741016) (xy 80.682335 -79.878909)
			(xy 80.598912 -80.012748) (xy 80.508818 -80.14219) (xy 80.412283 -80.266903) (xy 80.309555 -80.386566)
			(xy 80.200899 -80.500873) (xy 80.086592 -80.609529) (xy 79.966929 -80.712257) (xy 79.842216 -80.808792)
			(xy 79.712774 -80.898886) (xy 79.578935 -80.982309) (xy 79.441042 -81.058845) (xy 79.29945 -81.1283)
			(xy 79.154522 -81.190493) (xy 79.006629 -81.245267) (xy 78.856153 -81.292479) (xy 78.703478 -81.332009)
			(xy 78.548997 -81.363756) (xy 78.393106 -81.387637) (xy 78.236206 -81.403593) (xy 78.078699 -81.411581)
			(xy 77.920989 -81.411581) (xy 77.763482 -81.403593) (xy 77.606582 -81.387637) (xy 77.450691 -81.363756)
			(xy 77.29621 -81.332009) (xy 77.143535 -81.292479) (xy 76.993059 -81.245267) (xy 76.845166 -81.190493)
			(xy 76.700238 -81.1283) (xy 76.558646 -81.058845) (xy 76.420753 -80.982309) (xy 76.286914 -80.898886)
			(xy 76.157472 -80.808792) (xy 76.032759 -80.712257) (xy 75.913096 -80.609529) (xy 75.798789 -80.500873)
			(xy 75.690133 -80.386566) (xy 75.587405 -80.266903) (xy 75.49087 -80.14219) (xy 75.400776 -80.012748)
			(xy 75.317353 -79.878909) (xy 75.240817 -79.741016) (xy 75.171362 -79.599424) (xy 75.109169 -79.454496)
			(xy 75.054395 -79.306603) (xy 75.007183 -79.156127) (xy 74.967653 -79.003452) (xy 74.935906 -78.848971)
			(xy 74.912025 -78.69308) (xy 74.896069 -78.53618) (xy 74.888081 -78.378673) (xy 1.016 -78.378673)
			(xy 1.016 -88.571578) (xy 1.047496 -88.654382) (xy 1.059942 -88.669876) (xy 1.077482 -88.69257) (xy 1.106268 -88.742179)
			(xy 1.127305 -88.795537) (xy 1.14012 -88.851442) (xy 1.144423 -88.908636) (xy 1.14012 -88.96583)
			(xy 1.127305 -89.021735) (xy 1.106268 -89.075093) (xy 1.077482 -89.124702) (xy 1.059942 -89.147396)
			(xy 1.047496 -89.16289) (xy 1.016 -89.245694) (xy 1.016 -95.81007) (xy 39.818063 -95.81007) (xy 39.82207 -95.694046)
			(xy 39.834072 -95.578574) (xy 39.854012 -95.464206) (xy 39.881795 -95.351486) (xy 39.917289 -95.240952)
			(xy 39.960324 -95.133129) (xy 40.010695 -95.028532) (xy 40.068162 -94.92766) (xy 40.132452 -94.830993)
			(xy 40.203257 -94.738992) (xy 40.280241 -94.652095) (xy 40.363037 -94.570716) (xy 40.45125 -94.495243)
			(xy 40.54446 -94.426036) (xy 40.642223 -94.363424) (xy 40.744072 -94.307707) (xy 40.849522 -94.259149)
			(xy 40.958071 -94.217981) (xy 41.069202 -94.184401) (xy 41.182385 -94.158568) (xy 41.29708 -94.140605)
			(xy 41.412742 -94.130597) (xy 41.528818 -94.128594) (xy 41.644756 -94.134603) (xy 41.760003 -94.148596)
			(xy 41.874009 -94.170507) (xy 41.986233 -94.200232) (xy 42.096139 -94.237628) (xy 42.203202 -94.282517)
			(xy 42.306914 -94.334686) (xy 42.406779 -94.393886) (xy 42.502322 -94.459835) (xy 42.593088 -94.532218)
			(xy 42.678643 -94.610691) (xy 42.758581 -94.694879) (xy 42.83252 -94.784381) (xy 42.900108 -94.878772)
			(xy 42.961022 -94.9776) (xy 43.014974 -95.080396) (xy 43.061704 -95.186669) (xy 43.100992 -95.295913)
			(xy 43.132649 -95.407606) (xy 43.156525 -95.521218) (xy 43.172506 -95.636206) (xy 43.180515 -95.752023)
			(xy 43.181016 -95.81007) (xy 43.180515 -95.868117) (xy 43.172506 -95.983934) (xy 43.156525 -96.098922)
			(xy 43.132649 -96.212534) (xy 43.100992 -96.324227) (xy 43.061704 -96.433471) (xy 43.014974 -96.539744)
			(xy 42.961022 -96.64254) (xy 42.900108 -96.741368) (xy 42.83252 -96.835759) (xy 42.758581 -96.925261)
			(xy 42.678643 -97.009449) (xy 42.593088 -97.087922) (xy 42.502604 -97.16008) (xy 93.154506 -97.16008)
			(xy 93.158522 -97.04381) (xy 93.170549 -96.928095) (xy 93.190531 -96.813485) (xy 93.218373 -96.700526)
			(xy 93.253942 -96.589758) (xy 93.297068 -96.481707) (xy 93.347545 -96.376889) (xy 93.405134 -96.275804)
			(xy 93.46956 -96.178932) (xy 93.540515 -96.086736) (xy 93.617662 -95.999655) (xy 93.700633 -95.918104)
			(xy 93.789033 -95.842472) (xy 93.88244 -95.773118) (xy 93.980409 -95.710375) (xy 94.082473 -95.654539)
			(xy 94.188147 -95.605878) (xy 94.296926 -95.564624) (xy 94.408291 -95.530973) (xy 94.521714 -95.505085)
			(xy 94.636651 -95.487084) (xy 94.752557 -95.477055) (xy 94.868879 -95.475047) (xy 94.985062 -95.481069)
			(xy 95.100553 -95.495092) (xy 95.214801 -95.51705) (xy 95.327262 -95.546837) (xy 95.4374 -95.584312)
			(xy 95.54469 -95.629297) (xy 95.648621 -95.681576) (xy 95.748697 -95.740901) (xy 95.844443 -95.806989)
			(xy 95.9354 -95.879525) (xy 96.021136 -95.958164) (xy 96.101243 -96.04253) (xy 96.175339 -96.132222)
			(xy 96.243069 -96.226812) (xy 96.304113 -96.32585) (xy 96.358178 -96.428863) (xy 96.405008 -96.53536)
			(xy 96.444379 -96.644835) (xy 96.476103 -96.756765) (xy 96.500029 -96.870617) (xy 96.516043 -96.985849)
			(xy 96.52407 -97.101911) (xy 96.524572 -97.16008) (xy 96.52407 -97.218249) (xy 96.516043 -97.334311)
			(xy 96.500029 -97.449543) (xy 96.476103 -97.563395) (xy 96.444379 -97.675325) (xy 96.405008 -97.7848)
			(xy 96.358178 -97.891297) (xy 96.304113 -97.99431) (xy 96.243069 -98.093348) (xy 96.175339 -98.187938)
			(xy 96.101243 -98.27763) (xy 96.021136 -98.361996) (xy 95.9354 -98.440635) (xy 95.844443 -98.513171)
			(xy 95.748697 -98.579259) (xy 95.648621 -98.638584) (xy 95.54469 -98.690863) (xy 95.4374 -98.735848)
			(xy 95.327262 -98.773323) (xy 95.214801 -98.80311) (xy 95.100553 -98.825068) (xy 94.985062 -98.839091)
			(xy 94.868879 -98.845113) (xy 94.752557 -98.843105) (xy 94.636651 -98.833076) (xy 94.521714 -98.815075)
			(xy 94.408291 -98.789187) (xy 94.296926 -98.755536) (xy 94.188147 -98.714282) (xy 94.082473 -98.665621)
			(xy 93.980409 -98.609785) (xy 93.88244 -98.547042) (xy 93.789033 -98.477688) (xy 93.700633 -98.402056)
			(xy 93.617662 -98.320505) (xy 93.540515 -98.233424) (xy 93.46956 -98.141228) (xy 93.405134 -98.044356)
			(xy 93.347545 -97.943271) (xy 93.297068 -97.838453) (xy 93.253942 -97.730402) (xy 93.218373 -97.619634)
			(xy 93.190531 -97.506675) (xy 93.170549 -97.392065) (xy 93.158522 -97.27635) (xy 93.154506 -97.16008)
			(xy 42.502604 -97.16008) (xy 42.502322 -97.160305) (xy 42.406779 -97.226254) (xy 42.306914 -97.285454)
			(xy 42.203202 -97.337623) (xy 42.096139 -97.382512) (xy 41.986233 -97.419908) (xy 41.874009 -97.449633)
			(xy 41.760003 -97.471544) (xy 41.644756 -97.485537) (xy 41.528818 -97.491546) (xy 41.412742 -97.489543)
			(xy 41.29708 -97.479535) (xy 41.182385 -97.461572) (xy 41.069202 -97.435739) (xy 40.958071 -97.402159)
			(xy 40.849522 -97.360991) (xy 40.744072 -97.312433) (xy 40.642223 -97.256716) (xy 40.54446 -97.194104)
			(xy 40.45125 -97.124897) (xy 40.363037 -97.049424) (xy 40.280241 -96.968045) (xy 40.203257 -96.881148)
			(xy 40.132452 -96.789147) (xy 40.068162 -96.69248) (xy 40.010695 -96.591608) (xy 39.960324 -96.487011)
			(xy 39.917289 -96.379188) (xy 39.881795 -96.268654) (xy 39.854012 -96.155934) (xy 39.834072 -96.041566)
			(xy 39.82207 -95.926094) (xy 39.818063 -95.81007) (xy 1.016 -95.81007) (xy 1.016 -98.005392) (xy 1.016505 -98.028732)
			(xy 1.024982 -98.074635) (xy 1.0417 -98.118218) (xy 1.066095 -98.158016) (xy 1.097347 -98.192689)
			(xy 1.134405 -98.221072) (xy 1.176024 -98.242211) (xy 1.220803 -98.255395) (xy 1.267236 -98.260179)
			(xy 1.313763 -98.256404) (xy 1.358817 -98.244196) (xy 1.400885 -98.223966) (xy 1.438551 -98.196394)
			(xy 1.470549 -98.162407) (xy 1.483614 -98.14306) (xy 1.51897 -98.089124) (xy 1.595424 -97.985248)
			(xy 1.678158 -97.8863) (xy 1.766855 -97.79266) (xy 1.861175 -97.704687) (xy 1.960757 -97.622717)
			(xy 2.065219 -97.547065) (xy 2.174161 -97.47802) (xy 2.287166 -97.415847) (xy 2.403801 -97.360784)
			(xy 2.523618 -97.313042) (xy 2.64616 -97.272804) (xy 2.770956 -97.240224) (xy 2.897529 -97.215427)
			(xy 3.025394 -97.198508) (xy 3.15406 -97.189531) (xy 3.283035 -97.188531) (xy 3.411825 -97.195513)
			(xy 3.539936 -97.210448) (xy 3.666878 -97.23328) (xy 3.792164 -97.263922) (xy 3.915315 -97.302256)
			(xy 4.035858 -97.348135) (xy 4.153332 -97.401383) (xy 4.267287 -97.461797) (xy 4.377286 -97.529145)
			(xy 4.482909 -97.603169) (xy 4.583749 -97.683586) (xy 4.679421 -97.770086) (xy 4.769559 -97.86234)
			(xy 4.853817 -97.959994) (xy 4.931872 -98.062673) (xy 5.003425 -98.169984) (xy 5.068203 -98.281516)
			(xy 5.125957 -98.396842) (xy 5.176465 -98.51552) (xy 5.219535 -98.637095) (xy 5.255001 -98.761102)
			(xy 5.282728 -98.887065) (xy 5.302609 -99.014503) (xy 5.314568 -99.142926) (xy 5.318559 -99.271836)
			(xy 12.580624 -99.271836) (xy 12.584655 -99.14227) (xy 12.596734 -99.013206) (xy 12.616813 -98.885142)
			(xy 12.644815 -98.758575) (xy 12.680632 -98.633992) (xy 12.724124 -98.511878) (xy 12.775124 -98.392704)
			(xy 12.833435 -98.276931) (xy 12.89883 -98.165007) (xy 12.971057 -98.057365) (xy 13.049837 -97.954422)
			(xy 13.134864 -97.856576) (xy 13.225809 -97.764204) (xy 13.322321 -97.677666) (xy 13.424027 -97.597295)
			(xy 13.530533 -97.523403) (xy 13.641426 -97.456275) (xy 13.756278 -97.396171) (xy 13.874645 -97.343324)
			(xy 13.996068 -97.297937) (xy 14.120078 -97.260188) (xy 14.246195 -97.230221) (xy 14.373931 -97.208152)
			(xy 14.502792 -97.194068) (xy 14.632279 -97.188022) (xy 14.761892 -97.190038) (xy 14.891128 -97.200108)
			(xy 15.019489 -97.218193) (xy 15.146477 -97.244223) (xy 15.271601 -97.278098) (xy 15.394377 -97.319686)
			(xy 15.51433 -97.368827) (xy 15.630995 -97.42533) (xy 15.743923 -97.488977) (xy 15.852675 -97.559521)
			(xy 15.956831 -97.63669) (xy 16.055988 -97.720185) (xy 16.149762 -97.809683) (xy 16.237791 -97.904838)
			(xy 16.319734 -98.005281) (xy 16.395273 -98.110624) (xy 16.464118 -98.22046) (xy 16.526001 -98.334364)
			(xy 16.580682 -98.451894) (xy 16.627952 -98.572597) (xy 16.667625 -98.696005) (xy 16.69955 -98.821641)
			(xy 16.723602 -98.949018) (xy 16.739689 -99.077644) (xy 16.747748 -99.207022) (xy 16.748252 -99.271836)
			(xy 16.747748 -99.33665) (xy 16.739689 -99.466028) (xy 16.723602 -99.594654) (xy 16.69955 -99.722031)
			(xy 16.667625 -99.847667) (xy 16.627952 -99.971075) (xy 16.580682 -100.091778) (xy 16.526001 -100.209308)
			(xy 16.464118 -100.323212) (xy 16.395273 -100.433048) (xy 16.319734 -100.538391) (xy 16.237791 -100.638834)
			(xy 16.149762 -100.733989) (xy 16.055988 -100.823487) (xy 15.956831 -100.906982) (xy 15.852675 -100.984151)
			(xy 15.743923 -101.054695) (xy 15.630995 -101.118342) (xy 15.51433 -101.174845) (xy 15.394377 -101.223986)
			(xy 15.271601 -101.265574) (xy 15.146477 -101.299449) (xy 15.019489 -101.325479) (xy 14.891128 -101.343564)
			(xy 14.761892 -101.353634) (xy 14.632279 -101.35565) (xy 14.502792 -101.349604) (xy 14.373931 -101.33552)
			(xy 14.246195 -101.313451) (xy 14.120078 -101.283484) (xy 13.996068 -101.245735) (xy 13.874645 -101.200348)
			(xy 13.756278 -101.147501) (xy 13.641426 -101.087397) (xy 13.530533 -101.020269) (xy 13.424027 -100.946377)
			(xy 13.322321 -100.866006) (xy 13.225809 -100.779468) (xy 13.134864 -100.687096) (xy 13.049837 -100.58925)
			(xy 12.971057 -100.486307) (xy 12.89883 -100.378665) (xy 12.833435 -100.266741) (xy 12.775124 -100.150968)
			(xy 12.724124 -100.031794) (xy 12.680632 -99.90968) (xy 12.644815 -99.785097) (xy 12.616813 -99.65853)
			(xy 12.596734 -99.530466) (xy 12.584655 -99.401402) (xy 12.580624 -99.271836) (xy 5.318559 -99.271836)
			(xy 5.318559 -99.271843) (xy 5.314568 -99.400761) (xy 5.302608 -99.529184) (xy 5.282727 -99.656621)
			(xy 5.255 -99.782585) (xy 5.219533 -99.906591) (xy 5.176463 -100.028167) (xy 5.125954 -100.146844)
			(xy 5.0682 -100.26217) (xy 5.003422 -100.373702) (xy 4.931868 -100.481013) (xy 4.853812 -100.583692)
			(xy 4.769554 -100.681345) (xy 4.679416 -100.773598) (xy 4.583744 -100.860099) (xy 4.482903 -100.940515)
			(xy 4.377281 -101.014538) (xy 4.267281 -101.081886) (xy 4.153326 -101.1423) (xy 4.035852 -101.195548)
			(xy 3.915309 -101.241426) (xy 3.792158 -101.27976) (xy 3.666871 -101.310401) (xy 3.539929 -101.333233)
			(xy 3.411818 -101.348168) (xy 3.283028 -101.355149) (xy 3.154053 -101.354149) (xy 3.025387 -101.345172)
			(xy 2.897523 -101.328252) (xy 2.77095 -101.303454) (xy 2.646154 -101.270874) (xy 2.523612 -101.230636)
			(xy 2.403795 -101.182893) (xy 2.28716 -101.12783) (xy 2.174155 -101.065657) (xy 2.065214 -100.996611)
			(xy 1.960752 -100.920959) (xy 1.86117 -100.838989) (xy 1.766851 -100.751015) (xy 1.678154 -100.657375)
			(xy 1.59542 -100.558427) (xy 1.518966 -100.45455) (xy 1.483614 -100.400612) (xy 1.470543 -100.38127)
			(xy 1.438545 -100.347285) (xy 1.40088 -100.319714) (xy 1.358813 -100.299486) (xy 1.31376 -100.287278)
			(xy 1.267235 -100.283504) (xy 1.220804 -100.288288) (xy 1.176026 -100.301471) (xy 1.134409 -100.322609)
			(xy 1.097351 -100.350991) (xy 1.066099 -100.385663) (xy 1.041704 -100.425458) (xy 1.024987 -100.469039)
			(xy 1.016508 -100.514941) (xy 1.016 -100.53828) (xy 1.016 -101.271578) (xy 1.047496 -101.354382)
			(xy 1.059942 -101.369876) (xy 1.077482 -101.39257) (xy 1.106268 -101.442179) (xy 1.127305 -101.495537)
			(xy 1.14012 -101.551442) (xy 1.144423 -101.608636) (xy 1.14012 -101.66583) (xy 1.127305 -101.721735)
			(xy 1.106268 -101.775093) (xy 1.077482 -101.824702) (xy 1.059942 -101.847396) (xy 1.047496 -101.86289)
			(xy 1.016 -101.945694) (xy 1.016 -108.909866) (xy 86.877404 -108.909866) (xy 86.881424 -108.719215)
			(xy 86.893478 -108.528902) (xy 86.913544 -108.339267) (xy 86.941587 -108.150646) (xy 86.977556 -107.963376)
			(xy 87.021388 -107.777788) (xy 87.073005 -107.594213) (xy 87.132315 -107.412977) (xy 87.199213 -107.234402)
			(xy 87.273579 -107.058807) (xy 87.355281 -106.886502) (xy 87.444175 -106.717795) (xy 87.540101 -106.552985)
			(xy 87.64289 -106.392366) (xy 87.752359 -106.236223) (xy 87.868313 -106.084834) (xy 87.990547 -105.938467)
			(xy 88.118841 -105.797383) (xy 88.252969 -105.661834) (xy 88.392693 -105.532059) (xy 88.537763 -105.408289)
			(xy 88.687921 -105.290746) (xy 88.842902 -105.179637) (xy 89.002429 -105.07516) (xy 89.166218 -104.977501)
			(xy 89.333978 -104.886834) (xy 89.505412 -104.80332) (xy 89.680214 -104.727107) (xy 89.858073 -104.658331)
			(xy 90.038674 -104.597113) (xy 90.221694 -104.543564) (xy 90.40681 -104.497778) (xy 90.593691 -104.459836)
			(xy 90.782006 -104.429807) (xy 90.971419 -104.407742) (xy 91.161593 -104.393683) (xy 91.352192 -104.387653)
			(xy 91.542875 -104.389663) (xy 91.733304 -104.39971) (xy 91.92314 -104.417776) (xy 92.112046 -104.443829)
			(xy 92.299685 -104.477822) (xy 92.485725 -104.519695) (xy 92.669834 -104.569374) (xy 92.851685 -104.62677)
			(xy 93.030955 -104.691781) (xy 93.207325 -104.764292) (xy 93.380481 -104.844173) (xy 93.550116 -104.931283)
			(xy 93.715928 -105.025467) (xy 93.877622 -105.126558) (xy 94.03491 -105.234374) (xy 94.187513 -105.348726)
			(xy 94.335161 -105.469409) (xy 94.477589 -105.59621) (xy 94.614545 -105.728901) (xy 94.745786 -105.867249)
			(xy 94.871078 -106.011006) (xy 94.990198 -106.159917) (xy 95.102934 -106.313718) (xy 95.209087 -106.472134)
			(xy 95.308467 -106.634885) (xy 95.400897 -106.80168) (xy 95.486214 -106.972224) (xy 95.564266 -107.146212)
			(xy 95.634913 -107.323337) (xy 95.698031 -107.503282) (xy 95.753507 -107.685728) (xy 95.801242 -107.870351)
			(xy 95.841152 -108.056821) (xy 95.873165 -108.244809) (xy 95.897225 -108.433979) (xy 95.913288 -108.623995)
			(xy 95.921327 -108.814519) (xy 95.92183 -108.909866) (xy 95.921327 -109.005213) (xy 95.913288 -109.195737)
			(xy 95.897225 -109.385753) (xy 95.873165 -109.574923) (xy 95.841152 -109.762911) (xy 95.801242 -109.949381)
			(xy 95.753507 -110.134004) (xy 95.698031 -110.31645) (xy 95.634913 -110.496395) (xy 95.564266 -110.67352)
			(xy 95.486214 -110.847508) (xy 95.400897 -111.018052) (xy 95.308467 -111.184847) (xy 95.209087 -111.347598)
			(xy 95.102934 -111.506014) (xy 94.990198 -111.659815) (xy 94.871078 -111.808726) (xy 94.745786 -111.952483)
			(xy 94.614545 -112.090831) (xy 94.477589 -112.223522) (xy 94.335161 -112.350323) (xy 94.187513 -112.471006)
			(xy 94.03491 -112.585358) (xy 93.877622 -112.693174) (xy 93.715928 -112.794265) (xy 93.550116 -112.888449)
			(xy 93.380481 -112.975559) (xy 93.207325 -113.05544) (xy 93.030955 -113.127951) (xy 92.851685 -113.192962)
			(xy 92.669834 -113.250358) (xy 92.485725 -113.300037) (xy 92.299685 -113.34191) (xy 92.112046 -113.375903)
			(xy 91.92314 -113.401956) (xy 91.733304 -113.420022) (xy 91.542875 -113.430069) (xy 91.352192 -113.432079)
			(xy 91.161593 -113.426049) (xy 90.971419 -113.41199) (xy 90.782006 -113.389925) (xy 90.593691 -113.359896)
			(xy 90.40681 -113.321954) (xy 90.221694 -113.276168) (xy 90.038674 -113.222619) (xy 89.858073 -113.161401)
			(xy 89.680214 -113.092625) (xy 89.505412 -113.016412) (xy 89.333978 -112.932898) (xy 89.166218 -112.842231)
			(xy 89.002429 -112.744572) (xy 88.842902 -112.640095) (xy 88.687921 -112.528986) (xy 88.537763 -112.411443)
			(xy 88.392693 -112.287673) (xy 88.252969 -112.157898) (xy 88.118841 -112.022349) (xy 87.990547 -111.881265)
			(xy 87.868313 -111.734898) (xy 87.752359 -111.583509) (xy 87.64289 -111.427366) (xy 87.540101 -111.266747)
			(xy 87.444175 -111.101937) (xy 87.355281 -110.93323) (xy 87.273579 -110.760925) (xy 87.199213 -110.58533)
			(xy 87.132315 -110.406755) (xy 87.073005 -110.225519) (xy 87.021388 -110.041944) (xy 86.977556 -109.856356)
			(xy 86.941587 -109.669086) (xy 86.913544 -109.480465) (xy 86.893478 -109.29083) (xy 86.881424 -109.100517)
			(xy 86.877404 -108.909866) (xy 1.016 -108.909866) (xy 1.016 -113.971578) (xy 1.047496 -114.054382)
			(xy 1.059942 -114.069876) (xy 1.077482 -114.09257) (xy 1.106268 -114.142179) (xy 1.127305 -114.195537)
			(xy 1.14012 -114.251442) (xy 1.144423 -114.308636) (xy 1.14012 -114.36583) (xy 1.127305 -114.421735)
			(xy 1.106268 -114.475093) (xy 1.077482 -114.524702) (xy 1.059942 -114.547396) (xy 1.047496 -114.56289)
			(xy 1.016 -114.645694) (xy 1.016 -118.09984) (xy 11.34441 -118.09984) (xy 11.348411 -117.894791)
			(xy 11.36041 -117.690054) (xy 11.380388 -117.485941) (xy 11.408314 -117.282762) (xy 11.444146 -117.080829)
			(xy 11.48783 -116.880446) (xy 11.539298 -116.681921) (xy 11.598473 -116.485555) (xy 11.665264 -116.291648)
			(xy 11.73957 -116.100494) (xy 11.821277 -115.912384) (xy 11.910262 -115.727606) (xy 12.006388 -115.54644)
			(xy 12.109509 -115.369163) (xy 12.219469 -115.196044) (xy 12.336099 -115.027347) (xy 12.459222 -114.863329)
			(xy 12.588651 -114.70424) (xy 12.724188 -114.550322) (xy 12.865627 -114.401808) (xy 13.012754 -114.258927)
			(xy 13.165342 -114.121894) (xy 13.323161 -113.99092) (xy 13.48597 -113.866202) (xy 13.653521 -113.747932)
			(xy 13.825559 -113.636288) (xy 14.001822 -113.531442) (xy 14.182041 -113.433553) (xy 14.365942 -113.34277)
			(xy 14.553246 -113.259232) (xy 14.743666 -113.183064) (xy 14.936912 -113.114384) (xy 15.132692 -113.053296)
			(xy 15.330705 -112.999894) (xy 15.530652 -112.954257) (xy 15.732226 -112.916457) (xy 15.935122 -112.886549)
			(xy 16.139031 -112.864581) (xy 16.343641 -112.850586) (xy 16.548641 -112.844584) (xy 16.75372 -112.846585)
			(xy 16.958564 -112.856585) (xy 17.162863 -112.874571) (xy 17.366304 -112.900513) (xy 17.568577 -112.934374)
			(xy 17.769376 -112.9761) (xy 17.968394 -113.025629) (xy 18.165328 -113.082885) (xy 18.359878 -113.147782)
			(xy 18.551748 -113.220219) (xy 18.740645 -113.300087) (xy 18.926283 -113.387265) (xy 19.108378 -113.481619)
			(xy 19.286653 -113.583006) (xy 19.460836 -113.691271) (xy 19.630663 -113.806249) (xy 19.795875 -113.927767)
			(xy 19.956219 -114.055637) (xy 20.111453 -114.189666) (xy 20.261339 -114.32965) (xy 20.405649 -114.475375)
			(xy 20.544163 -114.62662) (xy 20.676672 -114.783153) (xy 20.802972 -114.944738) (xy 20.922871 -115.111127)
			(xy 21.036188 -115.282067) (xy 21.142748 -115.457299) (xy 21.242391 -115.636554) (xy 21.334964 -115.819561)
			(xy 21.420326 -116.00604) (xy 21.498347 -116.195708) (xy 21.56891 -116.388276) (xy 21.631905 -116.58345)
			(xy 21.687237 -116.780933) (xy 21.734822 -116.980424) (xy 21.774587 -117.181621) (xy 21.806472 -117.384215)
			(xy 21.830429 -117.5879) (xy 21.84642 -117.792364) (xy 21.854422 -117.997296) (xy 21.854922 -118.09984)
			(xy 21.854422 -118.202384) (xy 21.84642 -118.407316) (xy 21.830429 -118.61178) (xy 21.806472 -118.815465)
			(xy 21.774587 -119.018059) (xy 21.734822 -119.219256) (xy 21.687237 -119.418747) (xy 21.631905 -119.61623)
			(xy 21.56891 -119.811404) (xy 21.498347 -120.003972) (xy 21.420326 -120.19364) (xy 21.334964 -120.380119)
			(xy 21.242391 -120.563126) (xy 21.142748 -120.742381) (xy 21.036188 -120.917613) (xy 20.922871 -121.088553)
			(xy 20.842811 -121.199656) (xy 72.857366 -121.199656) (xy 72.861381 -120.996474) (xy 72.87342 -120.793609)
			(xy 72.893464 -120.591379) (xy 72.921482 -120.390098) (xy 72.95743 -120.190081) (xy 73.001252 -119.99164)
			(xy 73.052879 -119.795086) (xy 73.112231 -119.600725) (xy 73.179216 -119.40886) (xy 73.253728 -119.219791)
			(xy 73.335651 -119.033814) (xy 73.424858 -118.851218) (xy 73.521209 -118.672289) (xy 73.624553 -118.497307)
			(xy 73.73473 -118.326544) (xy 73.851567 -118.160266) (xy 73.974882 -117.998735) (xy 74.104482 -117.842201)
			(xy 74.240165 -117.69091) (xy 74.38172 -117.545097) (xy 74.528924 -117.40499) (xy 74.681548 -117.270808)
			(xy 74.839355 -117.14276) (xy 75.002097 -117.021047) (xy 75.16952 -116.905859) (xy 75.341363 -116.797374)
			(xy 75.517358 -116.695763) (xy 75.69723 -116.601185) (xy 75.880698 -116.513786) (xy 76.067476 -116.433704)
			(xy 76.257272 -116.361064) (xy 76.449789 -116.295978) (xy 76.644727 -116.238549) (xy 76.841782 -116.188866)
			(xy 77.040646 -116.147006) (xy 77.241008 -116.113036) (xy 77.442556 -116.087008) (xy 77.644975 -116.068963)
			(xy 77.847948 -116.058929) (xy 78.05116 -116.056921) (xy 78.254292 -116.062943) (xy 78.457028 -116.076986)
			(xy 78.659051 -116.099027) (xy 78.860045 -116.129032) (xy 79.059697 -116.166954) (xy 79.257695 -116.212734)
			(xy 79.45373 -116.2663) (xy 79.647495 -116.32757) (xy 79.838689 -116.396446) (xy 80.027012 -116.472823)
			(xy 80.212171 -116.556579) (xy 80.393877 -116.647586) (xy 80.571845 -116.745699) (xy 80.745798 -116.850768)
			(xy 80.915465 -116.962626) (xy 81.080579 -117.0811) (xy 81.240885 -117.206005) (xy 81.396131 -117.337145)
			(xy 81.546074 -117.474316) (xy 81.690482 -117.617304) (xy 81.829127 -117.765885) (xy 81.961795 -117.919828)
			(xy 82.088277 -118.078891) (xy 82.208377 -118.242828) (xy 82.321906 -118.411381) (xy 82.428687 -118.584288)
			(xy 82.528554 -118.761278) (xy 82.621351 -118.942075) (xy 82.706933 -119.126398) (xy 82.785166 -119.313957)
			(xy 82.855928 -119.504461) (xy 82.919109 -119.697612) (xy 82.974609 -119.893108) (xy 83.022343 -120.090644)
			(xy 83.062236 -120.289912) (xy 83.094225 -120.4906) (xy 83.118261 -120.692395) (xy 83.134306 -120.894982)
			(xy 83.142334 -121.098045) (xy 83.142836 -121.199656) (xy 83.142334 -121.301267) (xy 83.134306 -121.50433)
			(xy 83.118261 -121.706917) (xy 83.094225 -121.908712) (xy 83.062236 -122.1094) (xy 83.022343 -122.308668)
			(xy 82.974609 -122.506204) (xy 82.919109 -122.7017) (xy 82.855928 -122.894851) (xy 82.785166 -123.085355)
			(xy 82.706933 -123.272914) (xy 82.621351 -123.457237) (xy 82.528554 -123.638034) (xy 82.428687 -123.815024)
			(xy 82.321906 -123.987931) (xy 82.208377 -124.156484) (xy 82.088277 -124.320421) (xy 81.961795 -124.479484)
			(xy 81.829127 -124.633427) (xy 81.690482 -124.782008) (xy 81.546074 -124.924996) (xy 81.396131 -125.062167)
			(xy 81.240885 -125.193307) (xy 81.080579 -125.318212) (xy 80.915465 -125.436686) (xy 80.745798 -125.548544)
			(xy 80.571845 -125.653613) (xy 80.393877 -125.751726) (xy 80.212171 -125.842733) (xy 80.027012 -125.926489)
			(xy 79.838689 -126.002866) (xy 79.647495 -126.071742) (xy 79.45373 -126.133012) (xy 79.257695 -126.186578)
			(xy 79.059697 -126.232358) (xy 78.860045 -126.27028) (xy 78.659051 -126.300285) (xy 78.457028 -126.322326)
			(xy 78.254292 -126.336369) (xy 78.05116 -126.342391) (xy 77.847948 -126.340383) (xy 77.644975 -126.330349)
			(xy 77.442556 -126.312304) (xy 77.241008 -126.286276) (xy 77.040646 -126.252306) (xy 76.841782 -126.210446)
			(xy 76.644727 -126.160763) (xy 76.449789 -126.103334) (xy 76.257272 -126.038248) (xy 76.067476 -125.965608)
			(xy 75.880698 -125.885526) (xy 75.69723 -125.798127) (xy 75.517358 -125.703549) (xy 75.341363 -125.601938)
			(xy 75.16952 -125.493453) (xy 75.002097 -125.378265) (xy 74.839355 -125.256552) (xy 74.681548 -125.128504)
			(xy 74.528924 -124.994322) (xy 74.38172 -124.854215) (xy 74.240165 -124.708402) (xy 74.104482 -124.557111)
			(xy 73.974882 -124.400577) (xy 73.851567 -124.239046) (xy 73.73473 -124.072768) (xy 73.624553 -123.902005)
			(xy 73.521209 -123.727023) (xy 73.424858 -123.548094) (xy 73.335651 -123.365498) (xy 73.253728 -123.179521)
			(xy 73.179216 -122.990452) (xy 73.112231 -122.798587) (xy 73.052879 -122.604226) (xy 73.001252 -122.407672)
			(xy 72.95743 -122.209231) (xy 72.921482 -122.009214) (xy 72.893464 -121.807933) (xy 72.87342 -121.605703)
			(xy 72.861381 -121.402838) (xy 72.857366 -121.199656) (xy 20.842811 -121.199656) (xy 20.802972 -121.254942)
			(xy 20.676672 -121.416527) (xy 20.544163 -121.57306) (xy 20.405649 -121.724305) (xy 20.261339 -121.87003)
			(xy 20.111453 -122.010014) (xy 19.956219 -122.144043) (xy 19.795875 -122.271913) (xy 19.630663 -122.393431)
			(xy 19.460836 -122.508409) (xy 19.286653 -122.616674) (xy 19.108378 -122.718061) (xy 18.926283 -122.812415)
			(xy 18.740645 -122.899593) (xy 18.551748 -122.979461) (xy 18.359878 -123.051898) (xy 18.165328 -123.116795)
			(xy 17.968394 -123.174051) (xy 17.769376 -123.22358) (xy 17.568577 -123.265306) (xy 17.366304 -123.299167)
			(xy 17.162863 -123.325109) (xy 16.958564 -123.343095) (xy 16.75372 -123.353095) (xy 16.548641 -123.355096)
			(xy 16.343641 -123.349094) (xy 16.139031 -123.335099) (xy 15.935122 -123.313131) (xy 15.732226 -123.283223)
			(xy 15.530652 -123.245423) (xy 15.330705 -123.199786) (xy 15.132692 -123.146384) (xy 14.936912 -123.085296)
			(xy 14.743666 -123.016616) (xy 14.553246 -122.940448) (xy 14.365942 -122.85691) (xy 14.182041 -122.766127)
			(xy 14.001822 -122.668238) (xy 13.825559 -122.563392) (xy 13.653521 -122.451748) (xy 13.48597 -122.333478)
			(xy 13.323161 -122.20876) (xy 13.165342 -122.077786) (xy 13.012754 -121.940753) (xy 12.865627 -121.797872)
			(xy 12.724188 -121.649358) (xy 12.588651 -121.49544) (xy 12.459222 -121.336351) (xy 12.336099 -121.172333)
			(xy 12.219469 -121.003636) (xy 12.109509 -120.830517) (xy 12.006388 -120.65324) (xy 11.910262 -120.472074)
			(xy 11.821277 -120.287296) (xy 11.73957 -120.099186) (xy 11.665264 -119.908032) (xy 11.598473 -119.714125)
			(xy 11.539298 -119.517759) (xy 11.48783 -119.319234) (xy 11.444146 -119.118851) (xy 11.408314 -118.916918)
			(xy 11.380388 -118.713739) (xy 11.36041 -118.509626) (xy 11.348411 -118.304889) (xy 11.34441 -118.09984)
			(xy 1.016 -118.09984) (xy 1.016 -126.671578) (xy 1.047496 -126.754382) (xy 1.059942 -126.769876)
			(xy 1.077482 -126.79257) (xy 1.106268 -126.842179) (xy 1.127305 -126.895537) (xy 1.14012 -126.951442)
			(xy 1.144423 -127.008636) (xy 1.14012 -127.06583) (xy 1.127305 -127.121735) (xy 1.106268 -127.175093)
			(xy 1.077482 -127.224702) (xy 1.059942 -127.247396) (xy 1.047496 -127.26289) (xy 1.016 -127.345694)
			(xy 1.016 -138.163122) (xy 1.547863 -138.163122) (xy 1.547863 -138.036986) (xy 1.555783 -137.911098)
			(xy 1.571593 -137.785956) (xy 1.595228 -137.662053) (xy 1.626597 -137.53988) (xy 1.665575 -137.419917)
			(xy 1.712009 -137.302638) (xy 1.765716 -137.188506) (xy 1.826483 -137.077971) (xy 1.89407 -136.971471)
			(xy 1.968211 -136.869424) (xy 2.048614 -136.772234) (xy 2.13496 -136.680284) (xy 2.22691 -136.593938)
			(xy 2.3241 -136.513535) (xy 2.426147 -136.439394) (xy 2.532647 -136.371807) (xy 2.643182 -136.31104)
			(xy 2.757314 -136.257333) (xy 2.874593 -136.210899) (xy 2.994556 -136.171921) (xy 3.116729 -136.140552)
			(xy 3.240632 -136.116917) (xy 3.365774 -136.101107) (xy 3.491662 -136.093187) (xy 3.617798 -136.093187)
			(xy 3.743686 -136.101107) (xy 3.868828 -136.116917) (xy 3.992731 -136.140552) (xy 4.114904 -136.171921)
			(xy 4.234867 -136.210899) (xy 4.352146 -136.257333) (xy 4.466278 -136.31104) (xy 4.576813 -136.371807)
			(xy 4.683313 -136.439394) (xy 4.78536 -136.513535) (xy 4.88255 -136.593938) (xy 4.9745 -136.680284)
			(xy 5.060846 -136.772234) (xy 5.141249 -136.869424) (xy 5.21539 -136.971471) (xy 5.282977 -137.077971)
			(xy 5.343744 -137.188506) (xy 5.397451 -137.302638) (xy 5.443885 -137.419917) (xy 5.482863 -137.53988)
			(xy 5.514232 -137.662053) (xy 5.537867 -137.785956) (xy 5.553677 -137.911098) (xy 5.561597 -138.036986)
			(xy 5.562092 -138.100054) (xy 5.561597 -138.163122) (xy 12.977863 -138.163122) (xy 12.977863 -138.036986)
			(xy 12.985783 -137.911098) (xy 13.001593 -137.785956) (xy 13.025228 -137.662053) (xy 13.056597 -137.53988)
			(xy 13.095575 -137.419917) (xy 13.142009 -137.302638) (xy 13.195716 -137.188506) (xy 13.256483 -137.077971)
			(xy 13.32407 -136.971471) (xy 13.398211 -136.869424) (xy 13.478614 -136.772234) (xy 13.56496 -136.680284)
			(xy 13.65691 -136.593938) (xy 13.7541 -136.513535) (xy 13.856147 -136.439394) (xy 13.962647 -136.371807)
			(xy 14.073182 -136.31104) (xy 14.187314 -136.257333) (xy 14.304593 -136.210899) (xy 14.424556 -136.171921)
			(xy 14.546729 -136.140552) (xy 14.670632 -136.116917) (xy 14.795774 -136.101107) (xy 14.921662 -136.093187)
			(xy 15.047798 -136.093187) (xy 15.173686 -136.101107) (xy 15.298828 -136.116917) (xy 15.422731 -136.140552)
			(xy 15.544904 -136.171921) (xy 15.664867 -136.210899) (xy 15.782146 -136.257333) (xy 15.896278 -136.31104)
			(xy 16.006813 -136.371807) (xy 16.113313 -136.439394) (xy 16.21536 -136.513535) (xy 16.31255 -136.593938)
			(xy 16.4045 -136.680284) (xy 16.490846 -136.772234) (xy 16.571249 -136.869424) (xy 16.64539 -136.971471)
			(xy 16.712977 -137.077971) (xy 16.773744 -137.188506) (xy 16.827451 -137.302638) (xy 16.873885 -137.419917)
			(xy 16.912863 -137.53988) (xy 16.944232 -137.662053) (xy 16.967867 -137.785956) (xy 16.983677 -137.911098)
			(xy 16.991597 -138.036986) (xy 16.992092 -138.100054) (xy 16.991597 -138.163122) (xy 16.983677 -138.28901)
			(xy 16.967867 -138.414152) (xy 16.944232 -138.538055) (xy 16.912863 -138.660228) (xy 16.873885 -138.780191)
			(xy 16.827451 -138.89747) (xy 16.773744 -139.011602) (xy 16.712977 -139.122137) (xy 16.64539 -139.228637)
			(xy 16.571249 -139.330684) (xy 16.490846 -139.427874) (xy 16.4045 -139.519824) (xy 16.31255 -139.60617)
			(xy 16.21536 -139.686573) (xy 16.113313 -139.760714) (xy 16.006813 -139.828301) (xy 15.896278 -139.889068)
			(xy 15.782146 -139.942775) (xy 15.664867 -139.989209) (xy 15.544904 -140.028187) (xy 15.422731 -140.059556)
			(xy 15.298828 -140.083191) (xy 15.173686 -140.099001) (xy 15.047798 -140.106921) (xy 14.921662 -140.106921)
			(xy 14.795774 -140.099001) (xy 14.670632 -140.083191) (xy 14.546729 -140.059556) (xy 14.424556 -140.028187)
			(xy 14.304593 -139.989209) (xy 14.187314 -139.942775) (xy 14.073182 -139.889068) (xy 13.962647 -139.828301)
			(xy 13.856147 -139.760714) (xy 13.7541 -139.686573) (xy 13.65691 -139.60617) (xy 13.56496 -139.519824)
			(xy 13.478614 -139.427874) (xy 13.398211 -139.330684) (xy 13.32407 -139.228637) (xy 13.256483 -139.122137)
			(xy 13.195716 -139.011602) (xy 13.142009 -138.89747) (xy 13.095575 -138.780191) (xy 13.056597 -138.660228)
			(xy 13.025228 -138.538055) (xy 13.001593 -138.414152) (xy 12.985783 -138.28901) (xy 12.977863 -138.163122)
			(xy 5.561597 -138.163122) (xy 5.553677 -138.28901) (xy 5.537867 -138.414152) (xy 5.514232 -138.538055)
			(xy 5.482863 -138.660228) (xy 5.443885 -138.780191) (xy 5.397451 -138.89747) (xy 5.343744 -139.011602)
			(xy 5.282977 -139.122137) (xy 5.21539 -139.228637) (xy 5.141249 -139.330684) (xy 5.060846 -139.427874)
			(xy 4.9745 -139.519824) (xy 4.88255 -139.60617) (xy 4.78536 -139.686573) (xy 4.683313 -139.760714)
			(xy 4.576813 -139.828301) (xy 4.466278 -139.889068) (xy 4.352146 -139.942775) (xy 4.234867 -139.989209)
			(xy 4.114904 -140.028187) (xy 3.992731 -140.059556) (xy 3.868828 -140.083191) (xy 3.743686 -140.099001)
			(xy 3.617798 -140.106921) (xy 3.491662 -140.106921) (xy 3.365774 -140.099001) (xy 3.240632 -140.083191)
			(xy 3.116729 -140.059556) (xy 2.994556 -140.028187) (xy 2.874593 -139.989209) (xy 2.757314 -139.942775)
			(xy 2.643182 -139.889068) (xy 2.532647 -139.828301) (xy 2.426147 -139.760714) (xy 2.3241 -139.686573)
			(xy 2.22691 -139.60617) (xy 2.13496 -139.519824) (xy 2.048614 -139.427874) (xy 1.968211 -139.330684)
			(xy 1.89407 -139.228637) (xy 1.826483 -139.122137) (xy 1.765716 -139.011602) (xy 1.712009 -138.89747)
			(xy 1.665575 -138.780191) (xy 1.626597 -138.660228) (xy 1.595228 -138.538055) (xy 1.571593 -138.414152)
			(xy 1.555783 -138.28901) (xy 1.547863 -138.163122) (xy 1.016 -138.163122) (xy 1.016 -139.371578)
			(xy 1.047496 -139.454382) (xy 1.059942 -139.469876) (xy 1.077482 -139.49257) (xy 1.106268 -139.542179)
			(xy 1.127305 -139.595537) (xy 1.14012 -139.651442) (xy 1.144423 -139.708636) (xy 1.14012 -139.76583)
			(xy 1.127305 -139.821735) (xy 1.106268 -139.875093) (xy 1.077482 -139.924702) (xy 1.059942 -139.947396)
			(xy 1.047496 -139.96289) (xy 1.016 -140.045694) (xy 1.016 -140.26007) (xy 39.818317 -140.26007) (xy 39.822324 -140.144046)
			(xy 39.834326 -140.028574) (xy 39.854266 -139.914206) (xy 39.882049 -139.801486) (xy 39.917543 -139.690952)
			(xy 39.960578 -139.583129) (xy 40.010949 -139.478532) (xy 40.068416 -139.37766) (xy 40.132706 -139.280993)
			(xy 40.203511 -139.188992) (xy 40.280495 -139.102095) (xy 40.363291 -139.020716) (xy 40.451504 -138.945243)
			(xy 40.544714 -138.876036) (xy 40.642477 -138.813424) (xy 40.744326 -138.757707) (xy 40.849776 -138.709149)
			(xy 40.958325 -138.667981) (xy 41.069456 -138.634401) (xy 41.182639 -138.608568) (xy 41.297334 -138.590605)
			(xy 41.412996 -138.580597) (xy 41.529072 -138.578594) (xy 41.64501 -138.584603) (xy 41.760257 -138.598596)
			(xy 41.874263 -138.620507) (xy 41.986487 -138.650232) (xy 42.096393 -138.687628) (xy 42.203456 -138.732517)
			(xy 42.307168 -138.784686) (xy 42.407033 -138.843886) (xy 42.502576 -138.909835) (xy 42.593342 -138.982218)
			(xy 42.678897 -139.060691) (xy 42.758835 -139.144879) (xy 42.832774 -139.234381) (xy 42.900362 -139.328772)
			(xy 42.961276 -139.4276) (xy 43.015228 -139.530396) (xy 43.061958 -139.636669) (xy 43.101246 -139.745913)
			(xy 43.132903 -139.857606) (xy 43.156779 -139.971218) (xy 43.17276 -140.086206) (xy 43.180769 -140.202023)
			(xy 43.18127 -140.26007) (xy 43.180769 -140.318117) (xy 43.17276 -140.433934) (xy 43.156779 -140.548922)
			(xy 43.132903 -140.662534) (xy 43.101246 -140.774227) (xy 43.061958 -140.883471) (xy 43.015228 -140.989744)
			(xy 42.961276 -141.09254) (xy 42.900362 -141.191368) (xy 42.832774 -141.285759) (xy 42.758835 -141.375261)
			(xy 42.678897 -141.459449) (xy 42.593342 -141.537922) (xy 42.502858 -141.61008) (xy 93.15476 -141.61008)
			(xy 93.158776 -141.49381) (xy 93.170803 -141.378095) (xy 93.190785 -141.263485) (xy 93.218627 -141.150526)
			(xy 93.254196 -141.039758) (xy 93.297322 -140.931707) (xy 93.347799 -140.826889) (xy 93.405388 -140.725804)
			(xy 93.469814 -140.628932) (xy 93.540769 -140.536736) (xy 93.617916 -140.449655) (xy 93.700887 -140.368104)
			(xy 93.789287 -140.292472) (xy 93.882694 -140.223118) (xy 93.980663 -140.160375) (xy 94.082727 -140.104539)
			(xy 94.188401 -140.055878) (xy 94.29718 -140.014624) (xy 94.408545 -139.980973) (xy 94.521968 -139.955085)
			(xy 94.636905 -139.937084) (xy 94.752811 -139.927055) (xy 94.869133 -139.925047) (xy 94.985316 -139.931069)
			(xy 95.100807 -139.945092) (xy 95.215055 -139.96705) (xy 95.327516 -139.996837) (xy 95.437654 -140.034312)
			(xy 95.544944 -140.079297) (xy 95.648875 -140.131576) (xy 95.748951 -140.190901) (xy 95.844697 -140.256989)
			(xy 95.935654 -140.329525) (xy 96.02139 -140.408164) (xy 96.101497 -140.49253) (xy 96.175593 -140.582222)
			(xy 96.243323 -140.676812) (xy 96.304367 -140.77585) (xy 96.358432 -140.878863) (xy 96.405262 -140.98536)
			(xy 96.444633 -141.094835) (xy 96.476357 -141.206765) (xy 96.500283 -141.320617) (xy 96.516297 -141.435849)
			(xy 96.524324 -141.551911) (xy 96.524826 -141.61008) (xy 96.524324 -141.668249) (xy 96.516297 -141.784311)
			(xy 96.500283 -141.899543) (xy 96.476357 -142.013395) (xy 96.444633 -142.125325) (xy 96.405262 -142.2348)
			(xy 96.358432 -142.341297) (xy 96.304367 -142.44431) (xy 96.243323 -142.543348) (xy 96.175593 -142.637938)
			(xy 96.101497 -142.72763) (xy 96.02139 -142.811996) (xy 95.935654 -142.890635) (xy 95.844697 -142.963171)
			(xy 95.748951 -143.029259) (xy 95.648875 -143.088584) (xy 95.544944 -143.140863) (xy 95.437654 -143.185848)
			(xy 95.327516 -143.223323) (xy 95.215055 -143.25311) (xy 95.100807 -143.275068) (xy 94.985316 -143.289091)
			(xy 94.869133 -143.295113) (xy 94.752811 -143.293105) (xy 94.636905 -143.283076) (xy 94.521968 -143.265075)
			(xy 94.408545 -143.239187) (xy 94.29718 -143.205536) (xy 94.188401 -143.164282) (xy 94.082727 -143.115621)
			(xy 93.980663 -143.059785) (xy 93.882694 -142.997042) (xy 93.789287 -142.927688) (xy 93.700887 -142.852056)
			(xy 93.617916 -142.770505) (xy 93.540769 -142.683424) (xy 93.469814 -142.591228) (xy 93.405388 -142.494356)
			(xy 93.347799 -142.393271) (xy 93.297322 -142.288453) (xy 93.254196 -142.180402) (xy 93.218627 -142.069634)
			(xy 93.190785 -141.956675) (xy 93.170803 -141.842065) (xy 93.158776 -141.72635) (xy 93.15476 -141.61008)
			(xy 42.502858 -141.61008) (xy 42.502576 -141.610305) (xy 42.407033 -141.676254) (xy 42.307168 -141.735454)
			(xy 42.203456 -141.787623) (xy 42.096393 -141.832512) (xy 41.986487 -141.869908) (xy 41.874263 -141.899633)
			(xy 41.760257 -141.921544) (xy 41.64501 -141.935537) (xy 41.529072 -141.941546) (xy 41.412996 -141.939543)
			(xy 41.297334 -141.929535) (xy 41.182639 -141.911572) (xy 41.069456 -141.885739) (xy 40.958325 -141.852159)
			(xy 40.849776 -141.810991) (xy 40.744326 -141.762433) (xy 40.642477 -141.706716) (xy 40.544714 -141.644104)
			(xy 40.451504 -141.574897) (xy 40.363291 -141.499424) (xy 40.280495 -141.418045) (xy 40.203511 -141.331148)
			(xy 40.132706 -141.239147) (xy 40.068416 -141.14248) (xy 40.010949 -141.041608) (xy 39.960578 -140.937011)
			(xy 39.917543 -140.829188) (xy 39.882049 -140.718654) (xy 39.854266 -140.605934) (xy 39.834326 -140.491566)
			(xy 39.822324 -140.376094) (xy 39.818317 -140.26007) (xy 1.016 -140.26007) (xy 1.016 -152.071578)
			(xy 1.047496 -152.154382) (xy 1.059942 -152.169876) (xy 1.077482 -152.19257) (xy 1.106268 -152.242179)
			(xy 1.127305 -152.295537) (xy 1.14012 -152.351442) (xy 1.144423 -152.408636) (xy 1.14012 -152.46583)
			(xy 1.127305 -152.521735) (xy 1.106268 -152.575093) (xy 1.077482 -152.624702) (xy 1.059942 -152.647396)
			(xy 1.047496 -152.66289) (xy 1.016 -152.745694) (xy 1.016 -153.359866) (xy 86.877404 -153.359866)
			(xy 86.881424 -153.169215) (xy 86.893478 -152.978902) (xy 86.913544 -152.789267) (xy 86.941587 -152.600646)
			(xy 86.977556 -152.413376) (xy 87.021388 -152.227788) (xy 87.073005 -152.044213) (xy 87.132315 -151.862977)
			(xy 87.199213 -151.684402) (xy 87.273579 -151.508807) (xy 87.355281 -151.336502) (xy 87.444175 -151.167795)
			(xy 87.540101 -151.002985) (xy 87.64289 -150.842366) (xy 87.752359 -150.686223) (xy 87.868313 -150.534834)
			(xy 87.990547 -150.388467) (xy 88.118841 -150.247383) (xy 88.252969 -150.111834) (xy 88.392693 -149.982059)
			(xy 88.537763 -149.858289) (xy 88.687921 -149.740746) (xy 88.842902 -149.629637) (xy 89.002429 -149.52516)
			(xy 89.166218 -149.427501) (xy 89.333978 -149.336834) (xy 89.505412 -149.25332) (xy 89.680214 -149.177107)
			(xy 89.858073 -149.108331) (xy 90.038674 -149.047113) (xy 90.221694 -148.993564) (xy 90.40681 -148.947778)
			(xy 90.593691 -148.909836) (xy 90.782006 -148.879807) (xy 90.971419 -148.857742) (xy 91.161593 -148.843683)
			(xy 91.352192 -148.837653) (xy 91.542875 -148.839663) (xy 91.733304 -148.84971) (xy 91.92314 -148.867776)
			(xy 92.112046 -148.893829) (xy 92.299685 -148.927822) (xy 92.485725 -148.969695) (xy 92.669834 -149.019374)
			(xy 92.851685 -149.07677) (xy 93.030955 -149.141781) (xy 93.207325 -149.214292) (xy 93.380481 -149.294173)
			(xy 93.550116 -149.381283) (xy 93.715928 -149.475467) (xy 93.877622 -149.576558) (xy 94.03491 -149.684374)
			(xy 94.187513 -149.798726) (xy 94.335161 -149.919409) (xy 94.477589 -150.04621) (xy 94.614545 -150.178901)
			(xy 94.745786 -150.317249) (xy 94.871078 -150.461006) (xy 94.990198 -150.609917) (xy 95.102934 -150.763718)
			(xy 95.209087 -150.922134) (xy 95.308467 -151.084885) (xy 95.400897 -151.25168) (xy 95.486214 -151.422224)
			(xy 95.564266 -151.596212) (xy 95.634913 -151.773337) (xy 95.698031 -151.953282) (xy 95.753507 -152.135728)
			(xy 95.801242 -152.320351) (xy 95.841152 -152.506821) (xy 95.873165 -152.694809) (xy 95.897225 -152.883979)
			(xy 95.913288 -153.073995) (xy 95.921327 -153.264519) (xy 95.92183 -153.359866) (xy 95.921327 -153.455213)
			(xy 95.913288 -153.645737) (xy 95.897225 -153.835753) (xy 95.873165 -154.024923) (xy 95.841152 -154.212911)
			(xy 95.801242 -154.399381) (xy 95.753507 -154.584004) (xy 95.698031 -154.76645) (xy 95.634913 -154.946395)
			(xy 95.564266 -155.12352) (xy 95.486214 -155.297508) (xy 95.400897 -155.468052) (xy 95.308467 -155.634847)
			(xy 95.209087 -155.797598) (xy 95.102934 -155.956014) (xy 94.990198 -156.109815) (xy 94.871078 -156.258726)
			(xy 94.745786 -156.402483) (xy 94.614545 -156.540831) (xy 94.477589 -156.673522) (xy 94.335161 -156.800323)
			(xy 94.187513 -156.921006) (xy 94.03491 -157.035358) (xy 93.877622 -157.143174) (xy 93.715928 -157.244265)
			(xy 93.550116 -157.338449) (xy 93.380481 -157.425559) (xy 93.207325 -157.50544) (xy 93.030955 -157.577951)
			(xy 92.851685 -157.642962) (xy 92.669834 -157.700358) (xy 92.485725 -157.750037) (xy 92.299685 -157.79191)
			(xy 92.112046 -157.825903) (xy 91.92314 -157.851956) (xy 91.733304 -157.870022) (xy 91.542875 -157.880069)
			(xy 91.352192 -157.882079) (xy 91.161593 -157.876049) (xy 90.971419 -157.86199) (xy 90.782006 -157.839925)
			(xy 90.593691 -157.809896) (xy 90.40681 -157.771954) (xy 90.221694 -157.726168) (xy 90.038674 -157.672619)
			(xy 89.858073 -157.611401) (xy 89.680214 -157.542625) (xy 89.505412 -157.466412) (xy 89.333978 -157.382898)
			(xy 89.166218 -157.292231) (xy 89.002429 -157.194572) (xy 88.842902 -157.090095) (xy 88.687921 -156.978986)
			(xy 88.537763 -156.861443) (xy 88.392693 -156.737673) (xy 88.252969 -156.607898) (xy 88.118841 -156.472349)
			(xy 87.990547 -156.331265) (xy 87.868313 -156.184898) (xy 87.752359 -156.033509) (xy 87.64289 -155.877366)
			(xy 87.540101 -155.716747) (xy 87.444175 -155.551937) (xy 87.355281 -155.38323) (xy 87.273579 -155.210925)
			(xy 87.199213 -155.03533) (xy 87.132315 -154.856755) (xy 87.073005 -154.675519) (xy 87.021388 -154.491944)
			(xy 86.977556 -154.306356) (xy 86.941587 -154.119086) (xy 86.913544 -153.930465) (xy 86.893478 -153.74083)
			(xy 86.881424 -153.550517) (xy 86.877404 -153.359866) (xy 1.016 -153.359866) (xy 1.016 -164.771578)
			(xy 1.047496 -164.854382) (xy 1.059942 -164.869876) (xy 1.077482 -164.89257) (xy 1.106268 -164.942179)
			(xy 1.127305 -164.995537) (xy 1.14012 -165.051442) (xy 1.144423 -165.108636) (xy 1.14012 -165.16583)
			(xy 1.127305 -165.221735) (xy 1.106268 -165.275093) (xy 1.077482 -165.324702) (xy 1.059942 -165.347396)
			(xy 1.047496 -165.36289) (xy 1.016 -165.445694) (xy 1.016 -177.471578) (xy 1.047496 -177.554382)
			(xy 1.059942 -177.569876) (xy 1.077482 -177.59257) (xy 1.106268 -177.642179) (xy 1.127305 -177.695537)
			(xy 1.14012 -177.751442) (xy 1.144423 -177.808636) (xy 1.14012 -177.86583) (xy 1.127305 -177.921735)
			(xy 1.106268 -177.975093) (xy 1.077482 -178.024702) (xy 1.059942 -178.047396) (xy 1.047496 -178.06289)
			(xy 1.016 -178.145694) (xy 1.016 -184.71007) (xy 39.818317 -184.71007) (xy 39.822324 -184.594046)
			(xy 39.834326 -184.478574) (xy 39.854266 -184.364206) (xy 39.882049 -184.251486) (xy 39.917543 -184.140952)
			(xy 39.960578 -184.033129) (xy 40.010949 -183.928532) (xy 40.068416 -183.82766) (xy 40.132706 -183.730993)
			(xy 40.203511 -183.638992) (xy 40.280495 -183.552095) (xy 40.363291 -183.470716) (xy 40.451504 -183.395243)
			(xy 40.544714 -183.326036) (xy 40.642477 -183.263424) (xy 40.744326 -183.207707) (xy 40.849776 -183.159149)
			(xy 40.958325 -183.117981) (xy 41.069456 -183.084401) (xy 41.182639 -183.058568) (xy 41.297334 -183.040605)
			(xy 41.412996 -183.030597) (xy 41.529072 -183.028594) (xy 41.64501 -183.034603) (xy 41.760257 -183.048596)
			(xy 41.874263 -183.070507) (xy 41.986487 -183.100232) (xy 42.096393 -183.137628) (xy 42.203456 -183.182517)
			(xy 42.307168 -183.234686) (xy 42.407033 -183.293886) (xy 42.502576 -183.359835) (xy 42.593342 -183.432218)
			(xy 42.678897 -183.510691) (xy 42.758835 -183.594879) (xy 42.832774 -183.684381) (xy 42.900362 -183.778772)
			(xy 42.961276 -183.8776) (xy 43.015228 -183.980396) (xy 43.061958 -184.086669) (xy 43.101246 -184.195913)
			(xy 43.132903 -184.307606) (xy 43.156779 -184.421218) (xy 43.17276 -184.536206) (xy 43.180769 -184.652023)
			(xy 43.18127 -184.71007) (xy 43.180769 -184.768117) (xy 43.17276 -184.883934) (xy 43.156779 -184.998922)
			(xy 43.132903 -185.112534) (xy 43.101246 -185.224227) (xy 43.061958 -185.333471) (xy 43.015228 -185.439744)
			(xy 42.961276 -185.54254) (xy 42.900362 -185.641368) (xy 42.832774 -185.735759) (xy 42.758835 -185.825261)
			(xy 42.678897 -185.909449) (xy 42.593342 -185.987922) (xy 42.502858 -186.06008) (xy 93.15476 -186.06008)
			(xy 93.158776 -185.94381) (xy 93.170803 -185.828095) (xy 93.190785 -185.713485) (xy 93.218627 -185.600526)
			(xy 93.254196 -185.489758) (xy 93.297322 -185.381707) (xy 93.347799 -185.276889) (xy 93.405388 -185.175804)
			(xy 93.469814 -185.078932) (xy 93.540769 -184.986736) (xy 93.617916 -184.899655) (xy 93.700887 -184.818104)
			(xy 93.789287 -184.742472) (xy 93.882694 -184.673118) (xy 93.980663 -184.610375) (xy 94.082727 -184.554539)
			(xy 94.188401 -184.505878) (xy 94.29718 -184.464624) (xy 94.408545 -184.430973) (xy 94.521968 -184.405085)
			(xy 94.636905 -184.387084) (xy 94.752811 -184.377055) (xy 94.869133 -184.375047) (xy 94.985316 -184.381069)
			(xy 95.100807 -184.395092) (xy 95.215055 -184.41705) (xy 95.327516 -184.446837) (xy 95.437654 -184.484312)
			(xy 95.544944 -184.529297) (xy 95.648875 -184.581576) (xy 95.748951 -184.640901) (xy 95.844697 -184.706989)
			(xy 95.935654 -184.779525) (xy 96.02139 -184.858164) (xy 96.101497 -184.94253) (xy 96.175593 -185.032222)
			(xy 96.243323 -185.126812) (xy 96.304367 -185.22585) (xy 96.358432 -185.328863) (xy 96.405262 -185.43536)
			(xy 96.444633 -185.544835) (xy 96.476357 -185.656765) (xy 96.500283 -185.770617) (xy 96.516297 -185.885849)
			(xy 96.524324 -186.001911) (xy 96.524826 -186.06008) (xy 96.524324 -186.118249) (xy 96.516297 -186.234311)
			(xy 96.500283 -186.349543) (xy 96.476357 -186.463395) (xy 96.444633 -186.575325) (xy 96.405262 -186.6848)
			(xy 96.358432 -186.791297) (xy 96.304367 -186.89431) (xy 96.243323 -186.993348) (xy 96.175593 -187.087938)
			(xy 96.101497 -187.17763) (xy 96.02139 -187.261996) (xy 95.935654 -187.340635) (xy 95.844697 -187.413171)
			(xy 95.748951 -187.479259) (xy 95.648875 -187.538584) (xy 95.544944 -187.590863) (xy 95.437654 -187.635848)
			(xy 95.327516 -187.673323) (xy 95.215055 -187.70311) (xy 95.100807 -187.725068) (xy 94.985316 -187.739091)
			(xy 94.869133 -187.745113) (xy 94.752811 -187.743105) (xy 94.636905 -187.733076) (xy 94.521968 -187.715075)
			(xy 94.408545 -187.689187) (xy 94.29718 -187.655536) (xy 94.188401 -187.614282) (xy 94.082727 -187.565621)
			(xy 93.980663 -187.509785) (xy 93.882694 -187.447042) (xy 93.789287 -187.377688) (xy 93.700887 -187.302056)
			(xy 93.617916 -187.220505) (xy 93.540769 -187.133424) (xy 93.469814 -187.041228) (xy 93.405388 -186.944356)
			(xy 93.347799 -186.843271) (xy 93.297322 -186.738453) (xy 93.254196 -186.630402) (xy 93.218627 -186.519634)
			(xy 93.190785 -186.406675) (xy 93.170803 -186.292065) (xy 93.158776 -186.17635) (xy 93.15476 -186.06008)
			(xy 42.502858 -186.06008) (xy 42.502576 -186.060305) (xy 42.407033 -186.126254) (xy 42.307168 -186.185454)
			(xy 42.203456 -186.237623) (xy 42.096393 -186.282512) (xy 41.986487 -186.319908) (xy 41.874263 -186.349633)
			(xy 41.760257 -186.371544) (xy 41.64501 -186.385537) (xy 41.529072 -186.391546) (xy 41.412996 -186.389543)
			(xy 41.297334 -186.379535) (xy 41.182639 -186.361572) (xy 41.069456 -186.335739) (xy 40.958325 -186.302159)
			(xy 40.849776 -186.260991) (xy 40.744326 -186.212433) (xy 40.642477 -186.156716) (xy 40.544714 -186.094104)
			(xy 40.451504 -186.024897) (xy 40.363291 -185.949424) (xy 40.280495 -185.868045) (xy 40.203511 -185.781148)
			(xy 40.132706 -185.689147) (xy 40.068416 -185.59248) (xy 40.010949 -185.491608) (xy 39.960578 -185.387011)
			(xy 39.917543 -185.279188) (xy 39.882049 -185.168654) (xy 39.854266 -185.055934) (xy 39.834326 -184.941566)
			(xy 39.822324 -184.826094) (xy 39.818317 -184.71007) (xy 1.016 -184.71007) (xy 1.016 -190.171578)
			(xy 1.047496 -190.254382) (xy 1.059942 -190.269876) (xy 1.077482 -190.29257) (xy 1.106268 -190.342179)
			(xy 1.127305 -190.395537) (xy 1.14012 -190.451442) (xy 1.144423 -190.508636) (xy 1.14012 -190.56583)
			(xy 1.127305 -190.621735) (xy 1.106268 -190.675093) (xy 1.077482 -190.724702) (xy 1.059942 -190.747396)
			(xy 1.047496 -190.76289) (xy 1.016 -190.845694) (xy 1.016 -197.81012) (xy 86.877404 -197.81012) (xy 86.881424 -197.619469)
			(xy 86.893478 -197.429156) (xy 86.913544 -197.239521) (xy 86.941587 -197.0509) (xy 86.977556 -196.86363)
			(xy 87.021388 -196.678042) (xy 87.073005 -196.494467) (xy 87.132315 -196.313231) (xy 87.199213 -196.134656)
			(xy 87.273579 -195.959061) (xy 87.355281 -195.786756) (xy 87.444175 -195.618049) (xy 87.540101 -195.453239)
			(xy 87.64289 -195.29262) (xy 87.752359 -195.136477) (xy 87.868313 -194.985088) (xy 87.990547 -194.838721)
			(xy 88.118841 -194.697637) (xy 88.252969 -194.562088) (xy 88.392693 -194.432313) (xy 88.537763 -194.308543)
			(xy 88.687921 -194.191) (xy 88.842902 -194.079891) (xy 89.002429 -193.975414) (xy 89.166218 -193.877755)
			(xy 89.333978 -193.787088) (xy 89.505412 -193.703574) (xy 89.680214 -193.627361) (xy 89.858073 -193.558585)
			(xy 90.038674 -193.497367) (xy 90.221694 -193.443818) (xy 90.40681 -193.398032) (xy 90.593691 -193.36009)
			(xy 90.782006 -193.330061) (xy 90.971419 -193.307996) (xy 91.161593 -193.293937) (xy 91.352192 -193.287907)
			(xy 91.542875 -193.289917) (xy 91.733304 -193.299964) (xy 91.92314 -193.31803) (xy 92.112046 -193.344083)
			(xy 92.299685 -193.378076) (xy 92.485725 -193.419949) (xy 92.669834 -193.469628) (xy 92.851685 -193.527024)
			(xy 93.030955 -193.592035) (xy 93.207325 -193.664546) (xy 93.380481 -193.744427) (xy 93.550116 -193.831537)
			(xy 93.715928 -193.925721) (xy 93.877622 -194.026812) (xy 94.03491 -194.134628) (xy 94.187513 -194.24898)
			(xy 94.335161 -194.369663) (xy 94.477589 -194.496464) (xy 94.614545 -194.629155) (xy 94.745786 -194.767503)
			(xy 94.871078 -194.91126) (xy 94.990198 -195.060171) (xy 95.102934 -195.213972) (xy 95.209087 -195.372388)
			(xy 95.308467 -195.535139) (xy 95.400897 -195.701934) (xy 95.486214 -195.872478) (xy 95.564266 -196.046466)
			(xy 95.634913 -196.223591) (xy 95.698031 -196.403536) (xy 95.753507 -196.585982) (xy 95.801242 -196.770605)
			(xy 95.841152 -196.957075) (xy 95.873165 -197.145063) (xy 95.897225 -197.334233) (xy 95.913288 -197.524249)
			(xy 95.921327 -197.714773) (xy 95.92183 -197.81012) (xy 95.921327 -197.905467) (xy 95.913288 -198.095991)
			(xy 95.897225 -198.286007) (xy 95.873165 -198.475177) (xy 95.841152 -198.663165) (xy 95.801242 -198.849635)
			(xy 95.753507 -199.034258) (xy 95.698031 -199.216704) (xy 95.634913 -199.396649) (xy 95.564266 -199.573774)
			(xy 95.486214 -199.747762) (xy 95.400897 -199.918306) (xy 95.308467 -200.085101) (xy 95.209087 -200.247852)
			(xy 95.102934 -200.406268) (xy 94.990198 -200.560069) (xy 94.871078 -200.70898) (xy 94.745786 -200.852737)
			(xy 94.614545 -200.991085) (xy 94.477589 -201.123776) (xy 94.335161 -201.250577) (xy 94.187513 -201.37126)
			(xy 94.03491 -201.485612) (xy 93.877622 -201.593428) (xy 93.715928 -201.694519) (xy 93.550116 -201.788703)
			(xy 93.380481 -201.875813) (xy 93.207325 -201.955694) (xy 93.030955 -202.028205) (xy 92.851685 -202.093216)
			(xy 92.669834 -202.150612) (xy 92.485725 -202.200291) (xy 92.299685 -202.242164) (xy 92.112046 -202.276157)
			(xy 91.92314 -202.30221) (xy 91.733304 -202.320276) (xy 91.542875 -202.330323) (xy 91.352192 -202.332333)
			(xy 91.161593 -202.326303) (xy 90.971419 -202.312244) (xy 90.782006 -202.290179) (xy 90.593691 -202.26015)
			(xy 90.40681 -202.222208) (xy 90.221694 -202.176422) (xy 90.038674 -202.122873) (xy 89.858073 -202.061655)
			(xy 89.680214 -201.992879) (xy 89.505412 -201.916666) (xy 89.333978 -201.833152) (xy 89.166218 -201.742485)
			(xy 89.002429 -201.644826) (xy 88.842902 -201.540349) (xy 88.687921 -201.42924) (xy 88.537763 -201.311697)
			(xy 88.392693 -201.187927) (xy 88.252969 -201.058152) (xy 88.118841 -200.922603) (xy 87.990547 -200.781519)
			(xy 87.868313 -200.635152) (xy 87.752359 -200.483763) (xy 87.64289 -200.32762) (xy 87.540101 -200.167001)
			(xy 87.444175 -200.002191) (xy 87.355281 -199.833484) (xy 87.273579 -199.661179) (xy 87.199213 -199.485584)
			(xy 87.132315 -199.307009) (xy 87.073005 -199.125773) (xy 87.021388 -198.942198) (xy 86.977556 -198.75661)
			(xy 86.941587 -198.56934) (xy 86.913544 -198.380719) (xy 86.893478 -198.191084) (xy 86.881424 -198.000771)
			(xy 86.877404 -197.81012) (xy 1.016 -197.81012) (xy 1.016 -202.871578) (xy 1.047496 -202.954382)
			(xy 1.059942 -202.969876) (xy 1.077482 -202.99257) (xy 1.106268 -203.042179) (xy 1.127305 -203.095537)
			(xy 1.14012 -203.151442) (xy 1.144423 -203.208636) (xy 1.14012 -203.26583) (xy 1.127305 -203.321735)
			(xy 1.106268 -203.375093) (xy 1.077482 -203.424702) (xy 1.059942 -203.447396) (xy 1.047496 -203.46289)
			(xy 1.016 -203.545694) (xy 1.016 -206.99984) (xy 11.344156 -206.99984) (xy 11.348157 -206.794781)
			(xy 11.360157 -206.590034) (xy 11.380135 -206.385911) (xy 11.408063 -206.182723) (xy 11.443897 -205.980779)
			(xy 11.487582 -205.780388) (xy 11.539053 -205.581853) (xy 11.598231 -205.385477) (xy 11.665026 -205.19156)
			(xy 11.739335 -205.000397) (xy 11.821046 -204.812279) (xy 11.910035 -204.627492) (xy 12.006166 -204.446317)
			(xy 12.109292 -204.269031) (xy 12.219257 -204.095904) (xy 12.335893 -203.927199) (xy 12.459022 -203.763173)
			(xy 12.588457 -203.604076) (xy 12.724001 -203.45015) (xy 12.865447 -203.30163) (xy 13.01258 -203.158741)
			(xy 13.165176 -203.021702) (xy 13.323003 -202.890721) (xy 13.48582 -202.765997) (xy 13.653379 -202.647721)
			(xy 13.825425 -202.536073) (xy 14.001696 -202.431222) (xy 14.181924 -202.333328) (xy 14.365835 -202.242541)
			(xy 14.553147 -202.158998) (xy 14.743576 -202.082827) (xy 14.936832 -202.014143) (xy 15.132621 -201.953053)
			(xy 15.330644 -201.899647) (xy 15.5306 -201.854009) (xy 15.732184 -201.816206) (xy 15.93509 -201.786298)
			(xy 16.139008 -201.764328) (xy 16.343629 -201.750332) (xy 16.548639 -201.74433) (xy 16.753728 -201.746331)
			(xy 16.958582 -201.756332) (xy 17.16289 -201.774318) (xy 17.366341 -201.800262) (xy 17.568624 -201.834124)
			(xy 17.769433 -201.875852) (xy 17.96846 -201.925384) (xy 18.165404 -201.982643) (xy 18.359963 -202.047542)
			(xy 18.551842 -202.119983) (xy 18.740749 -202.199855) (xy 18.926395 -202.287037) (xy 19.108499 -202.381396)
			(xy 19.286783 -202.482787) (xy 19.460975 -202.591058) (xy 19.63081 -202.706042) (xy 19.796029 -202.827565)
			(xy 19.956381 -202.955442) (xy 20.111622 -203.089477) (xy 20.261516 -203.229468) (xy 20.405833 -203.3752)
			(xy 20.544354 -203.526452) (xy 20.676869 -203.682993) (xy 20.803175 -203.844585) (xy 20.92308 -204.010982)
			(xy 21.036402 -204.181931) (xy 21.142968 -204.357171) (xy 21.242615 -204.536435) (xy 21.335193 -204.719451)
			(xy 21.420559 -204.905939) (xy 21.498584 -205.095616) (xy 21.56915 -205.288193) (xy 21.632148 -205.483376)
			(xy 21.687483 -205.680869) (xy 21.73507 -205.88037) (xy 21.774837 -206.081576) (xy 21.806724 -206.284181)
			(xy 21.830682 -206.487875) (xy 21.846674 -206.692349) (xy 21.854676 -206.897291) (xy 21.855176 -206.99984)
			(xy 21.854676 -207.102389) (xy 21.846674 -207.307331) (xy 21.830682 -207.511805) (xy 21.806724 -207.715499)
			(xy 21.774837 -207.918104) (xy 21.73507 -208.11931) (xy 21.687483 -208.318811) (xy 21.632148 -208.516304)
			(xy 21.56915 -208.711487) (xy 21.498584 -208.904064) (xy 21.420559 -209.093741) (xy 21.335193 -209.280229)
			(xy 21.242615 -209.463245) (xy 21.142968 -209.642509) (xy 21.036402 -209.817749) (xy 20.92308 -209.988698)
			(xy 20.843124 -210.099656) (xy 72.857112 -210.099656) (xy 72.861127 -209.896474) (xy 72.873166 -209.693609)
			(xy 72.89321 -209.491379) (xy 72.921228 -209.290098) (xy 72.957176 -209.090081) (xy 73.000998 -208.89164)
			(xy 73.052625 -208.695086) (xy 73.111977 -208.500725) (xy 73.178962 -208.30886) (xy 73.253474 -208.119791)
			(xy 73.335397 -207.933814) (xy 73.424604 -207.751218) (xy 73.520955 -207.572289) (xy 73.624299 -207.397307)
			(xy 73.734476 -207.226544) (xy 73.851313 -207.060266) (xy 73.974628 -206.898735) (xy 74.104228 -206.742201)
			(xy 74.239911 -206.59091) (xy 74.381466 -206.445097) (xy 74.52867 -206.30499) (xy 74.681294 -206.170808)
			(xy 74.839101 -206.04276) (xy 75.001843 -205.921047) (xy 75.169266 -205.805859) (xy 75.341109 -205.697374)
			(xy 75.517104 -205.595763) (xy 75.696976 -205.501185) (xy 75.880444 -205.413786) (xy 76.067222 -205.333704)
			(xy 76.257018 -205.261064) (xy 76.449535 -205.195978) (xy 76.644473 -205.138549) (xy 76.841528 -205.088866)
			(xy 77.040392 -205.047006) (xy 77.240754 -205.013036) (xy 77.442302 -204.987008) (xy 77.644721 -204.968963)
			(xy 77.847694 -204.958929) (xy 78.050906 -204.956921) (xy 78.254038 -204.962943) (xy 78.456774 -204.976986)
			(xy 78.658797 -204.999027) (xy 78.859791 -205.029032) (xy 79.059443 -205.066954) (xy 79.257441 -205.112734)
			(xy 79.453476 -205.1663) (xy 79.647241 -205.22757) (xy 79.838435 -205.296446) (xy 80.026758 -205.372823)
			(xy 80.211917 -205.456579) (xy 80.393623 -205.547586) (xy 80.571591 -205.645699) (xy 80.745544 -205.750768)
			(xy 80.915211 -205.862626) (xy 81.080325 -205.9811) (xy 81.240631 -206.106005) (xy 81.395877 -206.237145)
			(xy 81.54582 -206.374316) (xy 81.690228 -206.517304) (xy 81.828873 -206.665885) (xy 81.961541 -206.819828)
			(xy 82.088023 -206.978891) (xy 82.208123 -207.142828) (xy 82.321652 -207.311381) (xy 82.428433 -207.484288)
			(xy 82.5283 -207.661278) (xy 82.621097 -207.842075) (xy 82.706679 -208.026398) (xy 82.784912 -208.213957)
			(xy 82.855674 -208.404461) (xy 82.918855 -208.597612) (xy 82.974355 -208.793108) (xy 83.022089 -208.990644)
			(xy 83.061982 -209.189912) (xy 83.093971 -209.3906) (xy 83.118007 -209.592395) (xy 83.134052 -209.794982)
			(xy 83.14208 -209.998045) (xy 83.142582 -210.099656) (xy 83.14208 -210.201267) (xy 83.134052 -210.40433)
			(xy 83.118007 -210.606917) (xy 83.093971 -210.808712) (xy 83.061982 -211.0094) (xy 83.022089 -211.208668)
			(xy 82.974355 -211.406204) (xy 82.918855 -211.6017) (xy 82.855674 -211.794851) (xy 82.784912 -211.985355)
			(xy 82.706679 -212.172914) (xy 82.621097 -212.357237) (xy 82.5283 -212.538034) (xy 82.428433 -212.715024)
			(xy 82.321652 -212.887931) (xy 82.208123 -213.056484) (xy 82.088023 -213.220421) (xy 81.961541 -213.379484)
			(xy 81.828873 -213.533427) (xy 81.690228 -213.682008) (xy 81.54582 -213.824996) (xy 81.395877 -213.962167)
			(xy 81.240631 -214.093307) (xy 81.080325 -214.218212) (xy 80.915211 -214.336686) (xy 80.745544 -214.448544)
			(xy 80.571591 -214.553613) (xy 80.393623 -214.651726) (xy 80.211917 -214.742733) (xy 80.026758 -214.826489)
			(xy 79.838435 -214.902866) (xy 79.647241 -214.971742) (xy 79.453476 -215.033012) (xy 79.257441 -215.086578)
			(xy 79.059443 -215.132358) (xy 78.859791 -215.17028) (xy 78.658797 -215.200285) (xy 78.456774 -215.222326)
			(xy 78.254038 -215.236369) (xy 78.050906 -215.242391) (xy 77.847694 -215.240383) (xy 77.644721 -215.230349)
			(xy 77.442302 -215.212304) (xy 77.240754 -215.186276) (xy 77.040392 -215.152306) (xy 76.841528 -215.110446)
			(xy 76.644473 -215.060763) (xy 76.449535 -215.003334) (xy 76.257018 -214.938248) (xy 76.067222 -214.865608)
			(xy 75.880444 -214.785526) (xy 75.696976 -214.698127) (xy 75.517104 -214.603549) (xy 75.341109 -214.501938)
			(xy 75.169266 -214.393453) (xy 75.001843 -214.278265) (xy 74.839101 -214.156552) (xy 74.681294 -214.028504)
			(xy 74.52867 -213.894322) (xy 74.381466 -213.754215) (xy 74.239911 -213.608402) (xy 74.104228 -213.457111)
			(xy 73.974628 -213.300577) (xy 73.851313 -213.139046) (xy 73.734476 -212.972768) (xy 73.624299 -212.802005)
			(xy 73.520955 -212.627023) (xy 73.424604 -212.448094) (xy 73.335397 -212.265498) (xy 73.253474 -212.079521)
			(xy 73.178962 -211.890452) (xy 73.111977 -211.698587) (xy 73.052625 -211.504226) (xy 73.000998 -211.307672)
			(xy 72.957176 -211.109231) (xy 72.921228 -210.909214) (xy 72.89321 -210.707933) (xy 72.873166 -210.505703)
			(xy 72.861127 -210.302838) (xy 72.857112 -210.099656) (xy 20.843124 -210.099656) (xy 20.803175 -210.155095)
			(xy 20.676869 -210.316687) (xy 20.544354 -210.473228) (xy 20.405833 -210.62448) (xy 20.261516 -210.770212)
			(xy 20.111622 -210.910203) (xy 19.956381 -211.044238) (xy 19.796029 -211.172115) (xy 19.63081 -211.293638)
			(xy 19.460975 -211.408622) (xy 19.286783 -211.516893) (xy 19.108499 -211.618284) (xy 18.926395 -211.712643)
			(xy 18.740749 -211.799825) (xy 18.551842 -211.879697) (xy 18.359963 -211.952138) (xy 18.165404 -212.017037)
			(xy 17.96846 -212.074296) (xy 17.769433 -212.123828) (xy 17.568624 -212.165556) (xy 17.366341 -212.199418)
			(xy 17.16289 -212.225362) (xy 16.958582 -212.243348) (xy 16.753728 -212.253349) (xy 16.548639 -212.25535)
			(xy 16.343629 -212.249348) (xy 16.139008 -212.235352) (xy 15.93509 -212.213382) (xy 15.732184 -212.183474)
			(xy 15.5306 -212.145671) (xy 15.330644 -212.100033) (xy 15.132621 -212.046627) (xy 14.936832 -211.985537)
			(xy 14.743576 -211.916853) (xy 14.553147 -211.840682) (xy 14.365835 -211.757139) (xy 14.181924 -211.666352)
			(xy 14.001696 -211.568458) (xy 13.825425 -211.463607) (xy 13.653379 -211.351959) (xy 13.48582 -211.233683)
			(xy 13.323003 -211.108959) (xy 13.165176 -210.977978) (xy 13.01258 -210.840939) (xy 12.865447 -210.69805)
			(xy 12.724001 -210.54953) (xy 12.588457 -210.395604) (xy 12.459022 -210.236507) (xy 12.335893 -210.072481)
			(xy 12.219257 -209.903776) (xy 12.109292 -209.730649) (xy 12.006166 -209.553363) (xy 11.910035 -209.372188)
			(xy 11.821046 -209.187401) (xy 11.739335 -208.999283) (xy 11.665026 -208.80812) (xy 11.598231 -208.614203)
			(xy 11.539053 -208.417827) (xy 11.487582 -208.219292) (xy 11.443897 -208.018901) (xy 11.408063 -207.816957)
			(xy 11.380135 -207.613769) (xy 11.360157 -207.409646) (xy 11.348157 -207.204899) (xy 11.344156 -206.99984)
			(xy 1.016 -206.99984) (xy 1.016 -215.571578) (xy 1.047496 -215.654382) (xy 1.059942 -215.669876)
			(xy 1.077482 -215.69257) (xy 1.106268 -215.742179) (xy 1.127305 -215.795537) (xy 1.14012 -215.851442)
			(xy 1.144423 -215.908636) (xy 1.14012 -215.96583) (xy 1.127305 -216.021735) (xy 1.106268 -216.075093)
			(xy 1.077482 -216.124702) (xy 1.059942 -216.147396) (xy 1.047496 -216.16289) (xy 1.016 -216.245694)
			(xy 1.016 -228.271578) (xy 1.047496 -228.354382) (xy 1.059942 -228.369876) (xy 1.077482 -228.39257)
			(xy 1.106268 -228.442179) (xy 1.127305 -228.495537) (xy 1.14012 -228.551442) (xy 1.144423 -228.608636)
			(xy 1.14012 -228.66583) (xy 1.127305 -228.721735) (xy 1.106268 -228.775093) (xy 1.077482 -228.824702)
			(xy 1.059942 -228.847396) (xy 1.047496 -228.86289) (xy 1.016 -228.945694) (xy 1.016 -229.16007) (xy 39.818063 -229.16007)
			(xy 39.82207 -229.044046) (xy 39.834072 -228.928574) (xy 39.854012 -228.814206) (xy 39.881795 -228.701486)
			(xy 39.917289 -228.590952) (xy 39.960324 -228.483129) (xy 40.010695 -228.378532) (xy 40.068162 -228.27766)
			(xy 40.132452 -228.180993) (xy 40.203257 -228.088992) (xy 40.280241 -228.002095) (xy 40.363037 -227.920716)
			(xy 40.45125 -227.845243) (xy 40.54446 -227.776036) (xy 40.642223 -227.713424) (xy 40.744072 -227.657707)
			(xy 40.849522 -227.609149) (xy 40.958071 -227.567981) (xy 41.069202 -227.534401) (xy 41.182385 -227.508568)
			(xy 41.29708 -227.490605) (xy 41.412742 -227.480597) (xy 41.528818 -227.478594) (xy 41.644756 -227.484603)
			(xy 41.760003 -227.498596) (xy 41.874009 -227.520507) (xy 41.986233 -227.550232) (xy 42.096139 -227.587628)
			(xy 42.203202 -227.632517) (xy 42.306914 -227.684686) (xy 42.406779 -227.743886) (xy 42.502322 -227.809835)
			(xy 42.593088 -227.882218) (xy 42.678643 -227.960691) (xy 42.758581 -228.044879) (xy 42.83252 -228.134381)
			(xy 42.900108 -228.228772) (xy 42.961022 -228.3276) (xy 43.014974 -228.430396) (xy 43.061704 -228.536669)
			(xy 43.100992 -228.645913) (xy 43.132649 -228.757606) (xy 43.156525 -228.871218) (xy 43.172506 -228.986206)
			(xy 43.180515 -229.102023) (xy 43.181016 -229.16007) (xy 43.180515 -229.218117) (xy 43.172506 -229.333934)
			(xy 43.156525 -229.448922) (xy 43.132649 -229.562534) (xy 43.100992 -229.674227) (xy 43.061704 -229.783471)
			(xy 43.014974 -229.889744) (xy 42.961022 -229.99254) (xy 42.900108 -230.091368) (xy 42.83252 -230.185759)
			(xy 42.758581 -230.275261) (xy 42.678643 -230.359449) (xy 42.593088 -230.437922) (xy 42.502604 -230.51008)
			(xy 93.154506 -230.51008) (xy 93.158522 -230.39381) (xy 93.170549 -230.278095) (xy 93.190531 -230.163485)
			(xy 93.218373 -230.050526) (xy 93.253942 -229.939758) (xy 93.297068 -229.831707) (xy 93.347545 -229.726889)
			(xy 93.405134 -229.625804) (xy 93.46956 -229.528932) (xy 93.540515 -229.436736) (xy 93.617662 -229.349655)
			(xy 93.700633 -229.268104) (xy 93.789033 -229.192472) (xy 93.88244 -229.123118) (xy 93.980409 -229.060375)
			(xy 94.082473 -229.004539) (xy 94.188147 -228.955878) (xy 94.296926 -228.914624) (xy 94.408291 -228.880973)
			(xy 94.521714 -228.855085) (xy 94.636651 -228.837084) (xy 94.752557 -228.827055) (xy 94.868879 -228.825047)
			(xy 94.985062 -228.831069) (xy 95.100553 -228.845092) (xy 95.214801 -228.86705) (xy 95.327262 -228.896837)
			(xy 95.4374 -228.934312) (xy 95.54469 -228.979297) (xy 95.648621 -229.031576) (xy 95.748697 -229.090901)
			(xy 95.844443 -229.156989) (xy 95.9354 -229.229525) (xy 96.021136 -229.308164) (xy 96.101243 -229.39253)
			(xy 96.175339 -229.482222) (xy 96.243069 -229.576812) (xy 96.304113 -229.67585) (xy 96.358178 -229.778863)
			(xy 96.405008 -229.88536) (xy 96.444379 -229.994835) (xy 96.476103 -230.106765) (xy 96.500029 -230.220617)
			(xy 96.516043 -230.335849) (xy 96.52407 -230.451911) (xy 96.524572 -230.51008) (xy 96.52407 -230.568249)
			(xy 96.516043 -230.684311) (xy 96.500029 -230.799543) (xy 96.476103 -230.913395) (xy 96.444379 -231.025325)
			(xy 96.405008 -231.1348) (xy 96.358178 -231.241297) (xy 96.304113 -231.34431) (xy 96.243069 -231.443348)
			(xy 96.175339 -231.537938) (xy 96.101243 -231.62763) (xy 96.021136 -231.711996) (xy 95.9354 -231.790635)
			(xy 95.844443 -231.863171) (xy 95.748697 -231.929259) (xy 95.648621 -231.988584) (xy 95.54469 -232.040863)
			(xy 95.4374 -232.085848) (xy 95.327262 -232.123323) (xy 95.214801 -232.15311) (xy 95.100553 -232.175068)
			(xy 94.985062 -232.189091) (xy 94.868879 -232.195113) (xy 94.752557 -232.193105) (xy 94.636651 -232.183076)
			(xy 94.521714 -232.165075) (xy 94.408291 -232.139187) (xy 94.296926 -232.105536) (xy 94.188147 -232.064282)
			(xy 94.082473 -232.015621) (xy 93.980409 -231.959785) (xy 93.88244 -231.897042) (xy 93.789033 -231.827688)
			(xy 93.700633 -231.752056) (xy 93.617662 -231.670505) (xy 93.540515 -231.583424) (xy 93.46956 -231.491228)
			(xy 93.405134 -231.394356) (xy 93.347545 -231.293271) (xy 93.297068 -231.188453) (xy 93.253942 -231.080402)
			(xy 93.218373 -230.969634) (xy 93.190531 -230.856675) (xy 93.170549 -230.742065) (xy 93.158522 -230.62635)
			(xy 93.154506 -230.51008) (xy 42.502604 -230.51008) (xy 42.502322 -230.510305) (xy 42.406779 -230.576254)
			(xy 42.306914 -230.635454) (xy 42.203202 -230.687623) (xy 42.096139 -230.732512) (xy 41.986233 -230.769908)
			(xy 41.874009 -230.799633) (xy 41.760003 -230.821544) (xy 41.644756 -230.835537) (xy 41.528818 -230.841546)
			(xy 41.412742 -230.839543) (xy 41.29708 -230.829535) (xy 41.182385 -230.811572) (xy 41.069202 -230.785739)
			(xy 40.958071 -230.752159) (xy 40.849522 -230.710991) (xy 40.744072 -230.662433) (xy 40.642223 -230.606716)
			(xy 40.54446 -230.544104) (xy 40.45125 -230.474897) (xy 40.363037 -230.399424) (xy 40.280241 -230.318045)
			(xy 40.203257 -230.231148) (xy 40.132452 -230.139147) (xy 40.068162 -230.04248) (xy 40.010695 -229.941608)
			(xy 39.960324 -229.837011) (xy 39.917289 -229.729188) (xy 39.881795 -229.618654) (xy 39.854012 -229.505934)
			(xy 39.834072 -229.391566) (xy 39.82207 -229.276094) (xy 39.818063 -229.16007) (xy 1.016 -229.16007)
			(xy 1.016 -240.971578) (xy 1.047496 -241.054382) (xy 1.059942 -241.069876) (xy 1.077482 -241.09257)
			(xy 1.106268 -241.142179) (xy 1.127305 -241.195537) (xy 1.14012 -241.251442) (xy 1.144423 -241.308636)
			(xy 1.14012 -241.36583) (xy 1.127305 -241.421735) (xy 1.106268 -241.475093) (xy 1.077482 -241.524702)
			(xy 1.059942 -241.547396) (xy 1.047496 -241.56289) (xy 1.016 -241.645694) (xy 1.016 -242.26012) (xy 86.877404 -242.26012)
			(xy 86.881424 -242.069469) (xy 86.893478 -241.879156) (xy 86.913544 -241.689521) (xy 86.941587 -241.5009)
			(xy 86.977556 -241.31363) (xy 87.021388 -241.128042) (xy 87.073005 -240.944467) (xy 87.132315 -240.763231)
			(xy 87.199213 -240.584656) (xy 87.273579 -240.409061) (xy 87.355281 -240.236756) (xy 87.444175 -240.068049)
			(xy 87.540101 -239.903239) (xy 87.64289 -239.74262) (xy 87.752359 -239.586477) (xy 87.868313 -239.435088)
			(xy 87.990547 -239.288721) (xy 88.118841 -239.147637) (xy 88.252969 -239.012088) (xy 88.392693 -238.882313)
			(xy 88.537763 -238.758543) (xy 88.687921 -238.641) (xy 88.842902 -238.529891) (xy 89.002429 -238.425414)
			(xy 89.166218 -238.327755) (xy 89.333978 -238.237088) (xy 89.505412 -238.153574) (xy 89.680214 -238.077361)
			(xy 89.858073 -238.008585) (xy 90.038674 -237.947367) (xy 90.221694 -237.893818) (xy 90.40681 -237.848032)
			(xy 90.593691 -237.81009) (xy 90.782006 -237.780061) (xy 90.971419 -237.757996) (xy 91.161593 -237.743937)
			(xy 91.352192 -237.737907) (xy 91.542875 -237.739917) (xy 91.733304 -237.749964) (xy 91.92314 -237.76803)
			(xy 92.112046 -237.794083) (xy 92.299685 -237.828076) (xy 92.485725 -237.869949) (xy 92.669834 -237.919628)
			(xy 92.851685 -237.977024) (xy 93.030955 -238.042035) (xy 93.207325 -238.114546) (xy 93.380481 -238.194427)
			(xy 93.550116 -238.281537) (xy 93.715928 -238.375721) (xy 93.877622 -238.476812) (xy 94.03491 -238.584628)
			(xy 94.187513 -238.69898) (xy 94.335161 -238.819663) (xy 94.477589 -238.946464) (xy 94.614545 -239.079155)
			(xy 94.745786 -239.217503) (xy 94.871078 -239.36126) (xy 94.990198 -239.510171) (xy 95.102934 -239.663972)
			(xy 95.209087 -239.822388) (xy 95.308467 -239.985139) (xy 95.400897 -240.151934) (xy 95.486214 -240.322478)
			(xy 95.564266 -240.496466) (xy 95.634913 -240.673591) (xy 95.698031 -240.853536) (xy 95.753507 -241.035982)
			(xy 95.801242 -241.220605) (xy 95.841152 -241.407075) (xy 95.873165 -241.595063) (xy 95.897225 -241.784233)
			(xy 95.913288 -241.974249) (xy 95.921327 -242.164773) (xy 95.92183 -242.26012) (xy 95.921327 -242.355467)
			(xy 95.913288 -242.545991) (xy 95.897225 -242.736007) (xy 95.873165 -242.925177) (xy 95.841152 -243.113165)
			(xy 95.801242 -243.299635) (xy 95.753507 -243.484258) (xy 95.698031 -243.666704) (xy 95.634913 -243.846649)
			(xy 95.564266 -244.023774) (xy 95.486214 -244.197762) (xy 95.400897 -244.368306) (xy 95.308467 -244.535101)
			(xy 95.209087 -244.697852) (xy 95.102934 -244.856268) (xy 94.990198 -245.010069) (xy 94.871078 -245.15898)
			(xy 94.745786 -245.302737) (xy 94.614545 -245.441085) (xy 94.477589 -245.573776) (xy 94.335161 -245.700577)
			(xy 94.187513 -245.82126) (xy 94.03491 -245.935612) (xy 93.877622 -246.043428) (xy 93.715928 -246.144519)
			(xy 93.550116 -246.238703) (xy 93.380481 -246.325813) (xy 93.207325 -246.405694) (xy 93.030955 -246.478205)
			(xy 92.851685 -246.543216) (xy 92.669834 -246.600612) (xy 92.485725 -246.650291) (xy 92.299685 -246.692164)
			(xy 92.112046 -246.726157) (xy 91.92314 -246.75221) (xy 91.733304 -246.770276) (xy 91.542875 -246.780323)
			(xy 91.352192 -246.782333) (xy 91.161593 -246.776303) (xy 90.971419 -246.762244) (xy 90.782006 -246.740179)
			(xy 90.593691 -246.71015) (xy 90.40681 -246.672208) (xy 90.221694 -246.626422) (xy 90.038674 -246.572873)
			(xy 89.858073 -246.511655) (xy 89.680214 -246.442879) (xy 89.505412 -246.366666) (xy 89.333978 -246.283152)
			(xy 89.166218 -246.192485) (xy 89.002429 -246.094826) (xy 88.842902 -245.990349) (xy 88.687921 -245.87924)
			(xy 88.537763 -245.761697) (xy 88.392693 -245.637927) (xy 88.252969 -245.508152) (xy 88.118841 -245.372603)
			(xy 87.990547 -245.231519) (xy 87.868313 -245.085152) (xy 87.752359 -244.933763) (xy 87.64289 -244.77762)
			(xy 87.540101 -244.617001) (xy 87.444175 -244.452191) (xy 87.355281 -244.283484) (xy 87.273579 -244.111179)
			(xy 87.199213 -243.935584) (xy 87.132315 -243.757009) (xy 87.073005 -243.575773) (xy 87.021388 -243.392198)
			(xy 86.977556 -243.20661) (xy 86.941587 -243.01934) (xy 86.913544 -242.830719) (xy 86.893478 -242.641084)
			(xy 86.881424 -242.450771) (xy 86.877404 -242.26012) (xy 1.016 -242.26012) (xy 1.016 -250.020582)
			(xy 3.582162 -250.020582) (xy 3.582659 -249.96334) (xy 3.590757 -249.849142) (xy 3.606915 -249.735803)
			(xy 3.631052 -249.623892) (xy 3.663046 -249.513969) (xy 3.702737 -249.406585) (xy 3.749927 -249.302279)
			(xy 3.804379 -249.201573) (xy 3.865819 -249.104971) (xy 3.93394 -249.012959) (xy 4.008401 -248.925998)
			(xy 4.088828 -248.844523) (xy 4.174818 -248.768942) (xy 4.26594 -248.699635) (xy 4.361737 -248.636949)
			(xy 4.46173 -248.581198) (xy 4.565416 -248.532661) (xy 4.672277 -248.491582) (xy 4.781777 -248.458167)
			(xy 4.893366 -248.432584) (xy 5.006486 -248.414959) (xy 5.120569 -248.405383) (xy 5.235044 -248.403902)
			(xy 5.349337 -248.410524) (xy 5.462875 -248.425217) (xy 5.575088 -248.447906) (xy 5.685416 -248.478477)
			(xy 5.793303 -248.516778) (xy 5.898211 -248.562616) (xy 5.999612 -248.615762) (xy 6.096999 -248.67595)
			(xy 6.189883 -248.742876) (xy 6.277799 -248.816208) (xy 6.360307 -248.895575) (xy 6.436992 -248.980582)
			(xy 6.50747 -249.070801) (xy 6.571389 -249.16578) (xy 6.628427 -249.265044) (xy 6.678299 -249.368095)
			(xy 6.720755 -249.474417) (xy 6.755581 -249.583475) (xy 6.782604 -249.694725) (xy 6.801689 -249.807607)
			(xy 6.812738 -249.921558) (xy 6.815698 -250.036004) (xy 6.810552 -250.150373) (xy 6.797328 -250.264091)
			(xy 6.77609 -250.376588) (xy 6.746947 -250.487301) (xy 6.710043 -250.595675) (xy 6.665563 -250.701165)
			(xy 6.613732 -250.803245) (xy 6.554808 -250.901401) (xy 6.489086 -250.995142) (xy 6.453378 -251.039884)
			(xy 6.059424 -251.039884) (xy 6.020367 -251.072253) (xy 5.938107 -251.131626) (xy 5.895086 -251.158502)
			(xy 5.881509 -251.167452) (xy 5.858992 -251.190897) (xy 5.843109 -251.219259) (xy 5.834884 -251.250707)
			(xy 5.83438 -251.26696) (xy 5.83438 -251.50699) (xy 5.779686 -251.529797) (xy 5.667599 -251.568292)
			(xy 5.552993 -251.598476) (xy 5.436486 -251.620186) (xy 5.318701 -251.633307) (xy 5.200272 -251.637768)
			(xy 5.081834 -251.633545) (xy 4.964023 -251.62066) (xy 4.847473 -251.599183) (xy 4.732807 -251.569229)
			(xy 4.620643 -251.530959) (xy 4.565904 -251.50826) (xy 4.565904 -251.26823) (xy 4.56544 -251.25195)
			(xy 4.557181 -251.220454) (xy 4.541219 -251.192074) (xy 4.518594 -251.168658) (xy 4.504944 -251.159772)
			(xy 4.45885 -251.131059) (xy 4.370982 -251.067228) (xy 4.32943 -251.032264) (xy 3.937762 -251.032264)
			(xy 3.903919 -250.989342) (xy 3.841441 -250.89964) (xy 3.785164 -250.805923) (xy 3.735346 -250.708619)
			(xy 3.692214 -250.608172) (xy 3.655964 -250.505042) (xy 3.626762 -250.399698) (xy 3.604742 -250.292623)
			(xy 3.590005 -250.184306) (xy 3.582617 -250.07524) (xy 3.582162 -250.020582) (xy 1.016 -250.020582)
			(xy 1.016 -253.671578) (xy 1.047496 -253.754382) (xy 1.059942 -253.769876) (xy 1.077482 -253.79257)
			(xy 1.106268 -253.842179) (xy 1.127305 -253.895537) (xy 1.14012 -253.951442) (xy 1.144423 -254.008636)
			(xy 1.14012 -254.06583) (xy 1.127305 -254.121735) (xy 1.106268 -254.175093) (xy 1.077482 -254.224702)
			(xy 1.059942 -254.247396) (xy 1.047496 -254.26289) (xy 1.016 -254.345694) (xy 1.016 -266.371578)
			(xy 1.047496 -266.454382) (xy 1.059942 -266.469876) (xy 1.077482 -266.49257) (xy 1.106268 -266.542179)
			(xy 1.127305 -266.595537) (xy 1.14012 -266.651442) (xy 1.144423 -266.708636) (xy 1.14012 -266.76583)
			(xy 1.127305 -266.821735) (xy 1.106268 -266.875093) (xy 1.077482 -266.924702) (xy 1.059942 -266.947396)
			(xy 1.047496 -266.96289) (xy 1.016 -267.045694) (xy 1.016 -267.869924) (xy 3.584453 -267.869924)
			(xy 3.588477 -267.755973) (xy 3.600528 -267.642589) (xy 3.620548 -267.530339) (xy 3.648436 -267.419779)
			(xy 3.684054 -267.311463) (xy 3.727223 -267.205929) (xy 3.777729 -267.103702) (xy 3.83532 -267.005294)
			(xy 3.899709 -266.911192) (xy 3.970576 -266.821867) (xy 4.047567 -266.737763) (xy 4.130299 -266.6593)
			(xy 4.218359 -266.586868) (xy 4.31131 -266.520828) (xy 4.408687 -266.461509) (xy 4.510006 -266.409207)
			(xy 4.614762 -266.364182) (xy 4.722433 -266.326658) (xy 4.832482 -266.296824) (xy 4.944363 -266.274826)
			(xy 5.057516 -266.260775) (xy 5.171378 -266.25474) (xy 5.285382 -266.256752) (xy 5.398961 -266.266801)
			(xy 5.511548 -266.284837) (xy 5.622582 -266.31077) (xy 5.73151 -266.34447) (xy 5.83779 -266.38577)
			(xy 5.940891 -266.434464) (xy 6.040301 -266.490309) (xy 6.135524 -266.553028) (xy 6.226086 -266.622307)
			(xy 6.311536 -266.697801) (xy 6.391447 -266.779136) (xy 6.465422 -266.865904) (xy 6.533092 -266.957675)
			(xy 6.59412 -267.05399) (xy 6.648202 -267.15437) (xy 6.695069 -267.258315) (xy 6.734487 -267.365307)
			(xy 6.766259 -267.474813) (xy 6.790228 -267.586287) (xy 6.806274 -267.699175) (xy 6.814317 -267.812913)
			(xy 6.81482 -267.869924) (xy 6.814317 -267.926935) (xy 6.806274 -268.040673) (xy 6.790228 -268.153561)
			(xy 6.766259 -268.265035) (xy 6.734487 -268.374541) (xy 6.695069 -268.481533) (xy 6.648202 -268.585478)
			(xy 6.59412 -268.685858) (xy 6.533092 -268.782173) (xy 6.465422 -268.873944) (xy 6.391447 -268.960712)
			(xy 6.311536 -269.042047) (xy 6.226086 -269.117541) (xy 6.135524 -269.18682) (xy 6.040301 -269.249539)
			(xy 5.940891 -269.305384) (xy 5.83779 -269.354078) (xy 5.73151 -269.395378) (xy 5.622582 -269.429078)
			(xy 5.511548 -269.455011) (xy 5.398961 -269.473047) (xy 5.285382 -269.483096) (xy 5.171378 -269.485108)
			(xy 5.057516 -269.479073) (xy 4.944363 -269.465022) (xy 4.832482 -269.443024) (xy 4.722433 -269.41319)
			(xy 4.614762 -269.375666) (xy 4.510006 -269.330641) (xy 4.408687 -269.278339) (xy 4.31131 -269.21902)
			(xy 4.218359 -269.15298) (xy 4.130299 -269.080548) (xy 4.047567 -269.002085) (xy 3.970576 -268.917981)
			(xy 3.899709 -268.828656) (xy 3.83532 -268.734554) (xy 3.777729 -268.636146) (xy 3.727223 -268.533919)
			(xy 3.684054 -268.428385) (xy 3.648436 -268.320069) (xy 3.620548 -268.209509) (xy 3.600528 -268.097259)
			(xy 3.588477 -267.983875) (xy 3.584453 -267.869924) (xy 1.016 -267.869924) (xy 1.016 -273.61007)
			(xy 39.818063 -273.61007) (xy 39.82207 -273.494046) (xy 39.834072 -273.378574) (xy 39.854012 -273.264206)
			(xy 39.881795 -273.151486) (xy 39.917289 -273.040952) (xy 39.960324 -272.933129) (xy 40.010695 -272.828532)
			(xy 40.068162 -272.72766) (xy 40.132452 -272.630993) (xy 40.203257 -272.538992) (xy 40.280241 -272.452095)
			(xy 40.363037 -272.370716) (xy 40.45125 -272.295243) (xy 40.54446 -272.226036) (xy 40.642223 -272.163424)
			(xy 40.744072 -272.107707) (xy 40.849522 -272.059149) (xy 40.958071 -272.017981) (xy 41.069202 -271.984401)
			(xy 41.182385 -271.958568) (xy 41.29708 -271.940605) (xy 41.412742 -271.930597) (xy 41.528818 -271.928594)
			(xy 41.644756 -271.934603) (xy 41.760003 -271.948596) (xy 41.874009 -271.970507) (xy 41.986233 -272.000232)
			(xy 42.096139 -272.037628) (xy 42.203202 -272.082517) (xy 42.306914 -272.134686) (xy 42.406779 -272.193886)
			(xy 42.502322 -272.259835) (xy 42.593088 -272.332218) (xy 42.678643 -272.410691) (xy 42.758581 -272.494879)
			(xy 42.83252 -272.584381) (xy 42.900108 -272.678772) (xy 42.961022 -272.7776) (xy 43.014974 -272.880396)
			(xy 43.061704 -272.986669) (xy 43.100992 -273.095913) (xy 43.132649 -273.207606) (xy 43.156525 -273.321218)
			(xy 43.172506 -273.436206) (xy 43.180515 -273.552023) (xy 43.181016 -273.61007) (xy 43.180515 -273.668117)
			(xy 43.172506 -273.783934) (xy 43.156525 -273.898922) (xy 43.132649 -274.012534) (xy 43.100992 -274.124227)
			(xy 43.061704 -274.233471) (xy 43.014974 -274.339744) (xy 42.961022 -274.44254) (xy 42.900108 -274.541368)
			(xy 42.83252 -274.635759) (xy 42.758581 -274.725261) (xy 42.678643 -274.809449) (xy 42.593088 -274.887922)
			(xy 42.502604 -274.96008) (xy 93.154506 -274.96008) (xy 93.158522 -274.84381) (xy 93.170549 -274.728095)
			(xy 93.190531 -274.613485) (xy 93.218373 -274.500526) (xy 93.253942 -274.389758) (xy 93.297068 -274.281707)
			(xy 93.347545 -274.176889) (xy 93.405134 -274.075804) (xy 93.46956 -273.978932) (xy 93.540515 -273.886736)
			(xy 93.617662 -273.799655) (xy 93.700633 -273.718104) (xy 93.789033 -273.642472) (xy 93.88244 -273.573118)
			(xy 93.980409 -273.510375) (xy 94.082473 -273.454539) (xy 94.188147 -273.405878) (xy 94.296926 -273.364624)
			(xy 94.408291 -273.330973) (xy 94.521714 -273.305085) (xy 94.636651 -273.287084) (xy 94.752557 -273.277055)
			(xy 94.868879 -273.275047) (xy 94.985062 -273.281069) (xy 95.100553 -273.295092) (xy 95.214801 -273.31705)
			(xy 95.327262 -273.346837) (xy 95.4374 -273.384312) (xy 95.54469 -273.429297) (xy 95.648621 -273.481576)
			(xy 95.748697 -273.540901) (xy 95.844443 -273.606989) (xy 95.9354 -273.679525) (xy 96.021136 -273.758164)
			(xy 96.101243 -273.84253) (xy 96.175339 -273.932222) (xy 96.243069 -274.026812) (xy 96.304113 -274.12585)
			(xy 96.358178 -274.228863) (xy 96.405008 -274.33536) (xy 96.444379 -274.444835) (xy 96.476103 -274.556765)
			(xy 96.500029 -274.670617) (xy 96.516043 -274.785849) (xy 96.52407 -274.901911) (xy 96.524572 -274.96008)
			(xy 96.52407 -275.018249) (xy 96.516043 -275.134311) (xy 96.500029 -275.249543) (xy 96.476103 -275.363395)
			(xy 96.444379 -275.475325) (xy 96.405008 -275.5848) (xy 96.358178 -275.691297) (xy 96.304113 -275.79431)
			(xy 96.243069 -275.893348) (xy 96.175339 -275.987938) (xy 96.101243 -276.07763) (xy 96.021136 -276.161996)
			(xy 95.9354 -276.240635) (xy 95.844443 -276.313171) (xy 95.748697 -276.379259) (xy 95.648621 -276.438584)
			(xy 95.54469 -276.490863) (xy 95.4374 -276.535848) (xy 95.327262 -276.573323) (xy 95.214801 -276.60311)
			(xy 95.100553 -276.625068) (xy 94.985062 -276.639091) (xy 94.868879 -276.645113) (xy 94.752557 -276.643105)
			(xy 94.636651 -276.633076) (xy 94.521714 -276.615075) (xy 94.408291 -276.589187) (xy 94.296926 -276.555536)
			(xy 94.188147 -276.514282) (xy 94.082473 -276.465621) (xy 93.980409 -276.409785) (xy 93.88244 -276.347042)
			(xy 93.789033 -276.277688) (xy 93.700633 -276.202056) (xy 93.617662 -276.120505) (xy 93.540515 -276.033424)
			(xy 93.46956 -275.941228) (xy 93.405134 -275.844356) (xy 93.347545 -275.743271) (xy 93.297068 -275.638453)
			(xy 93.253942 -275.530402) (xy 93.218373 -275.419634) (xy 93.190531 -275.306675) (xy 93.170549 -275.192065)
			(xy 93.158522 -275.07635) (xy 93.154506 -274.96008) (xy 42.502604 -274.96008) (xy 42.502322 -274.960305)
			(xy 42.406779 -275.026254) (xy 42.306914 -275.085454) (xy 42.203202 -275.137623) (xy 42.096139 -275.182512)
			(xy 41.986233 -275.219908) (xy 41.874009 -275.249633) (xy 41.760003 -275.271544) (xy 41.644756 -275.285537)
			(xy 41.528818 -275.291546) (xy 41.412742 -275.289543) (xy 41.29708 -275.279535) (xy 41.182385 -275.261572)
			(xy 41.069202 -275.235739) (xy 40.958071 -275.202159) (xy 40.849522 -275.160991) (xy 40.744072 -275.112433)
			(xy 40.642223 -275.056716) (xy 40.54446 -274.994104) (xy 40.45125 -274.924897) (xy 40.363037 -274.849424)
			(xy 40.280241 -274.768045) (xy 40.203257 -274.681148) (xy 40.132452 -274.589147) (xy 40.068162 -274.49248)
			(xy 40.010695 -274.391608) (xy 39.960324 -274.287011) (xy 39.917289 -274.179188) (xy 39.881795 -274.068654)
			(xy 39.854012 -273.955934) (xy 39.834072 -273.841566) (xy 39.82207 -273.726094) (xy 39.818063 -273.61007)
			(xy 1.016 -273.61007) (xy 1.016 -279.071578) (xy 1.047496 -279.154382) (xy 1.059942 -279.169876)
			(xy 1.077482 -279.19257) (xy 1.106268 -279.242179) (xy 1.127305 -279.295537) (xy 1.14012 -279.351442)
			(xy 1.144423 -279.408636) (xy 1.14012 -279.46583) (xy 1.127305 -279.521735) (xy 1.106268 -279.575093)
			(xy 1.077482 -279.624702) (xy 1.059942 -279.647396) (xy 1.047496 -279.66289) (xy 1.016 -279.745694)
			(xy 1.016 -286.709866) (xy 86.877404 -286.709866) (xy 86.881424 -286.519215) (xy 86.893478 -286.328902)
			(xy 86.913544 -286.139267) (xy 86.941587 -285.950646) (xy 86.977556 -285.763376) (xy 87.021388 -285.577788)
			(xy 87.073005 -285.394213) (xy 87.132315 -285.212977) (xy 87.199213 -285.034402) (xy 87.273579 -284.858807)
			(xy 87.355281 -284.686502) (xy 87.444175 -284.517795) (xy 87.540101 -284.352985) (xy 87.64289 -284.192366)
			(xy 87.752359 -284.036223) (xy 87.868313 -283.884834) (xy 87.990547 -283.738467) (xy 88.118841 -283.597383)
			(xy 88.252969 -283.461834) (xy 88.392693 -283.332059) (xy 88.537763 -283.208289) (xy 88.687921 -283.090746)
			(xy 88.842902 -282.979637) (xy 89.002429 -282.87516) (xy 89.166218 -282.777501) (xy 89.333978 -282.686834)
			(xy 89.505412 -282.60332) (xy 89.680214 -282.527107) (xy 89.858073 -282.458331) (xy 90.038674 -282.397113)
			(xy 90.221694 -282.343564) (xy 90.40681 -282.297778) (xy 90.593691 -282.259836) (xy 90.782006 -282.229807)
			(xy 90.971419 -282.207742) (xy 91.161593 -282.193683) (xy 91.352192 -282.187653) (xy 91.542875 -282.189663)
			(xy 91.733304 -282.19971) (xy 91.92314 -282.217776) (xy 92.112046 -282.243829) (xy 92.299685 -282.277822)
			(xy 92.485725 -282.319695) (xy 92.669834 -282.369374) (xy 92.851685 -282.42677) (xy 93.030955 -282.491781)
			(xy 93.207325 -282.564292) (xy 93.380481 -282.644173) (xy 93.550116 -282.731283) (xy 93.715928 -282.825467)
			(xy 93.877622 -282.926558) (xy 94.03491 -283.034374) (xy 94.187513 -283.148726) (xy 94.335161 -283.269409)
			(xy 94.477589 -283.39621) (xy 94.614545 -283.528901) (xy 94.745786 -283.667249) (xy 94.871078 -283.811006)
			(xy 94.990198 -283.959917) (xy 95.102934 -284.113718) (xy 95.209087 -284.272134) (xy 95.308467 -284.434885)
			(xy 95.400897 -284.60168) (xy 95.486214 -284.772224) (xy 95.564266 -284.946212) (xy 95.634913 -285.123337)
			(xy 95.698031 -285.303282) (xy 95.753507 -285.485728) (xy 95.801242 -285.670351) (xy 95.841152 -285.856821)
			(xy 95.873165 -286.044809) (xy 95.897225 -286.233979) (xy 95.913288 -286.423995) (xy 95.921327 -286.614519)
			(xy 95.92183 -286.709866) (xy 95.921327 -286.805213) (xy 95.913288 -286.995737) (xy 95.897225 -287.185753)
			(xy 95.873165 -287.374923) (xy 95.841152 -287.562911) (xy 95.801242 -287.749381) (xy 95.753507 -287.934004)
			(xy 95.698031 -288.11645) (xy 95.634913 -288.296395) (xy 95.564266 -288.47352) (xy 95.486214 -288.647508)
			(xy 95.400897 -288.818052) (xy 95.308467 -288.984847) (xy 95.209087 -289.147598) (xy 95.102934 -289.306014)
			(xy 94.990198 -289.459815) (xy 94.871078 -289.608726) (xy 94.745786 -289.752483) (xy 94.614545 -289.890831)
			(xy 94.477589 -290.023522) (xy 94.335161 -290.150323) (xy 94.187513 -290.271006) (xy 94.03491 -290.385358)
			(xy 93.877622 -290.493174) (xy 93.715928 -290.594265) (xy 93.550116 -290.688449) (xy 93.380481 -290.775559)
			(xy 93.207325 -290.85544) (xy 93.030955 -290.927951) (xy 92.851685 -290.992962) (xy 92.669834 -291.050358)
			(xy 92.485725 -291.100037) (xy 92.299685 -291.14191) (xy 92.112046 -291.175903) (xy 91.92314 -291.201956)
			(xy 91.733304 -291.220022) (xy 91.542875 -291.230069) (xy 91.352192 -291.232079) (xy 91.161593 -291.226049)
			(xy 90.971419 -291.21199) (xy 90.782006 -291.189925) (xy 90.593691 -291.159896) (xy 90.40681 -291.121954)
			(xy 90.221694 -291.076168) (xy 90.038674 -291.022619) (xy 89.858073 -290.961401) (xy 89.680214 -290.892625)
			(xy 89.505412 -290.816412) (xy 89.333978 -290.732898) (xy 89.166218 -290.642231) (xy 89.002429 -290.544572)
			(xy 88.842902 -290.440095) (xy 88.687921 -290.328986) (xy 88.537763 -290.211443) (xy 88.392693 -290.087673)
			(xy 88.252969 -289.957898) (xy 88.118841 -289.822349) (xy 87.990547 -289.681265) (xy 87.868313 -289.534898)
			(xy 87.752359 -289.383509) (xy 87.64289 -289.227366) (xy 87.540101 -289.066747) (xy 87.444175 -288.901937)
			(xy 87.355281 -288.73323) (xy 87.273579 -288.560925) (xy 87.199213 -288.38533) (xy 87.132315 -288.206755)
			(xy 87.073005 -288.025519) (xy 87.021388 -287.841944) (xy 86.977556 -287.656356) (xy 86.941587 -287.469086)
			(xy 86.913544 -287.280465) (xy 86.893478 -287.09083) (xy 86.881424 -286.900517) (xy 86.877404 -286.709866)
			(xy 1.016 -286.709866) (xy 1.016 -291.771578) (xy 1.047496 -291.854382) (xy 1.059942 -291.869876)
			(xy 1.077482 -291.89257) (xy 1.106268 -291.942179) (xy 1.127305 -291.995537) (xy 1.14012 -292.051442)
			(xy 1.144423 -292.108636) (xy 1.14012 -292.16583) (xy 1.127305 -292.221735) (xy 1.106268 -292.275093)
			(xy 1.077482 -292.324702) (xy 1.059942 -292.347396) (xy 1.047496 -292.36289) (xy 1.016 -292.445694)
			(xy 1.016 -295.89984) (xy 11.343648 -295.89984) (xy 11.34765 -295.694761) (xy 11.35965 -295.489994)
			(xy 11.379631 -295.285852) (xy 11.407561 -295.082644) (xy 11.443398 -294.880681) (xy 11.487088 -294.68027)
			(xy 11.538564 -294.481716) (xy 11.597748 -294.285321) (xy 11.664549 -294.091386) (xy 11.738865 -293.900204)
			(xy 11.820585 -293.712067) (xy 11.909582 -293.527262) (xy 12.005722 -293.34607) (xy 12.108858 -293.168767)
			(xy 12.218834 -292.995623) (xy 12.335481 -292.826902) (xy 12.458622 -292.66286) (xy 12.588069 -292.503748)
			(xy 12.723626 -292.349807) (xy 12.865086 -292.201272) (xy 13.012233 -292.05837) (xy 13.164844 -291.921318)
			(xy 13.322686 -291.790324) (xy 13.485519 -291.665588) (xy 13.653094 -291.547301) (xy 13.825157 -291.435641)
			(xy 14.001445 -291.33078) (xy 14.181691 -291.232877) (xy 14.365619 -291.142081) (xy 14.552949 -291.05853)
			(xy 14.743397 -290.982351) (xy 14.936671 -290.913662) (xy 15.132479 -290.852565) (xy 15.330521 -290.799154)
			(xy 15.530497 -290.753511) (xy 15.7321 -290.715705) (xy 15.935026 -290.685794) (xy 16.138964 -290.663822)
			(xy 16.343604 -290.649825) (xy 16.548634 -290.643822) (xy 16.753742 -290.645823) (xy 16.958616 -290.655825)
			(xy 17.162944 -290.673813) (xy 17.366415 -290.699759) (xy 17.568718 -290.733625) (xy 17.769546 -290.775357)
			(xy 17.968592 -290.824893) (xy 18.165555 -290.882158) (xy 18.360133 -290.947064) (xy 18.552031 -291.019512)
			(xy 18.740956 -291.099391) (xy 18.92662 -291.186582) (xy 19.108742 -291.280949) (xy 19.287042 -291.382351)
			(xy 19.461251 -291.490632) (xy 19.631103 -291.605627) (xy 19.796338 -291.727162) (xy 19.956706 -291.855051)
			(xy 20.111962 -291.989099) (xy 20.261869 -292.129103) (xy 20.406201 -292.274849) (xy 20.544735 -292.426116)
			(xy 20.677263 -292.582672) (xy 20.803581 -292.74428) (xy 20.923498 -292.910693) (xy 21.036831 -293.081659)
			(xy 21.143407 -293.256916) (xy 21.243064 -293.436197) (xy 21.33565 -293.619231) (xy 21.421025 -293.805737)
			(xy 21.499058 -293.995432) (xy 21.56963 -294.188028) (xy 21.632634 -294.38323) (xy 21.687974 -294.580742)
			(xy 21.735566 -294.780262) (xy 21.775337 -294.981488) (xy 21.807227 -295.184112) (xy 21.831187 -295.387825)
			(xy 21.847181 -295.592319) (xy 21.855184 -295.797281) (xy 21.855684 -295.89984) (xy 21.855184 -296.002399)
			(xy 21.847181 -296.207361) (xy 21.831187 -296.411855) (xy 21.807227 -296.615568) (xy 21.775337 -296.818192)
			(xy 21.735566 -297.019418) (xy 21.687974 -297.218938) (xy 21.632634 -297.41645) (xy 21.56963 -297.611652)
			(xy 21.499058 -297.804248) (xy 21.421025 -297.993943) (xy 21.33565 -298.180449) (xy 21.243064 -298.363483)
			(xy 21.143407 -298.542764) (xy 21.036831 -298.718021) (xy 20.923498 -298.888987) (xy 20.803581 -299.0554)
			(xy 20.677263 -299.217008) (xy 20.544735 -299.373564) (xy 20.406201 -299.524831) (xy 20.261869 -299.670577)
			(xy 20.111962 -299.810581) (xy 19.956706 -299.944629) (xy 19.796338 -300.072518) (xy 19.631103 -300.194053)
			(xy 19.461251 -300.309048) (xy 19.287042 -300.417329) (xy 19.108742 -300.518731) (xy 18.92662 -300.613098)
			(xy 18.740956 -300.700289) (xy 18.552031 -300.780168) (xy 18.360133 -300.852616) (xy 18.165555 -300.917522)
			(xy 17.968592 -300.974787) (xy 17.769546 -301.024323) (xy 17.568718 -301.066055) (xy 17.366415 -301.099921)
			(xy 17.162944 -301.125867) (xy 16.958616 -301.143855) (xy 16.753742 -301.153857) (xy 16.548634 -301.155858)
			(xy 16.343604 -301.149855) (xy 16.138964 -301.135858) (xy 15.935026 -301.113886) (xy 15.7321 -301.083975)
			(xy 15.530497 -301.046169) (xy 15.330521 -301.000526) (xy 15.132479 -300.947115) (xy 14.936671 -300.886018)
			(xy 14.743397 -300.817329) (xy 14.552949 -300.74115) (xy 14.365619 -300.657599) (xy 14.181691 -300.566803)
			(xy 14.001445 -300.4689) (xy 13.825157 -300.364039) (xy 13.653094 -300.252379) (xy 13.485519 -300.134092)
			(xy 13.322686 -300.009356) (xy 13.164844 -299.878362) (xy 13.012233 -299.74131) (xy 12.865086 -299.598408)
			(xy 12.723626 -299.449873) (xy 12.588069 -299.295932) (xy 12.458622 -299.13682) (xy 12.335481 -298.972778)
			(xy 12.218834 -298.804057) (xy 12.108858 -298.630913) (xy 12.005722 -298.45361) (xy 11.909582 -298.272418)
			(xy 11.820585 -298.087613) (xy 11.738865 -297.899476) (xy 11.664549 -297.708294) (xy 11.597748 -297.514359)
			(xy 11.538564 -297.317964) (xy 11.487088 -297.11941) (xy 11.443398 -296.918999) (xy 11.407561 -296.717036)
			(xy 11.379631 -296.513828) (xy 11.35965 -296.309686) (xy 11.34765 -296.104919) (xy 11.343648 -295.89984)
			(xy 1.016 -295.89984) (xy 1.016 -304.471578) (xy 1.047496 -304.554382) (xy 1.059942 -304.569876)
			(xy 1.077482 -304.59257) (xy 1.106268 -304.642179) (xy 1.127305 -304.695537) (xy 1.14012 -304.751442)
			(xy 1.144423 -304.808636) (xy 1.14012 -304.86583) (xy 1.127305 -304.921735) (xy 1.106268 -304.975093)
			(xy 1.077482 -305.024702) (xy 1.059942 -305.047396) (xy 1.047496 -305.06289) (xy 1.016 -305.145694)
			(xy 1.016 -317.171578) (xy 1.047496 -317.254382) (xy 1.059942 -317.269876) (xy 1.077482 -317.29257)
			(xy 1.106268 -317.342179) (xy 1.127305 -317.395537) (xy 1.14012 -317.451442) (xy 1.144423 -317.508636)
			(xy 1.14012 -317.56583) (xy 1.127305 -317.621735) (xy 1.106268 -317.675093) (xy 1.077482 -317.724702)
			(xy 1.059942 -317.747396) (xy 1.047496 -317.76289) (xy 1.016 -317.845694) (xy 1.016 -318.06007) (xy 39.818063 -318.06007)
			(xy 39.82207 -317.944046) (xy 39.834072 -317.828574) (xy 39.854012 -317.714206) (xy 39.881795 -317.601486)
			(xy 39.917289 -317.490952) (xy 39.960324 -317.383129) (xy 40.010695 -317.278532) (xy 40.068162 -317.17766)
			(xy 40.132452 -317.080993) (xy 40.203257 -316.988992) (xy 40.280241 -316.902095) (xy 40.363037 -316.820716)
			(xy 40.45125 -316.745243) (xy 40.54446 -316.676036) (xy 40.642223 -316.613424) (xy 40.744072 -316.557707)
			(xy 40.849522 -316.509149) (xy 40.958071 -316.467981) (xy 41.069202 -316.434401) (xy 41.182385 -316.408568)
			(xy 41.29708 -316.390605) (xy 41.412742 -316.380597) (xy 41.528818 -316.378594) (xy 41.644756 -316.384603)
			(xy 41.760003 -316.398596) (xy 41.874009 -316.420507) (xy 41.986233 -316.450232) (xy 42.096139 -316.487628)
			(xy 42.203202 -316.532517) (xy 42.306914 -316.584686) (xy 42.406779 -316.643886) (xy 42.502322 -316.709835)
			(xy 42.593088 -316.782218) (xy 42.678643 -316.860691) (xy 42.758581 -316.944879) (xy 42.83252 -317.034381)
			(xy 42.900108 -317.128772) (xy 42.961022 -317.2276) (xy 43.014974 -317.330396) (xy 43.061704 -317.436669)
			(xy 43.100992 -317.545913) (xy 43.132649 -317.657606) (xy 43.156525 -317.771218) (xy 43.172506 -317.886206)
			(xy 43.180515 -318.002023) (xy 43.181016 -318.06007) (xy 43.180515 -318.118117) (xy 43.172506 -318.233934)
			(xy 43.156525 -318.348922) (xy 43.132649 -318.462534) (xy 43.100992 -318.574227) (xy 43.061704 -318.683471)
			(xy 43.014974 -318.789744) (xy 42.961022 -318.89254) (xy 42.900108 -318.991368) (xy 42.83252 -319.085759)
			(xy 42.758581 -319.175261) (xy 42.678643 -319.259449) (xy 42.593088 -319.337922) (xy 42.502604 -319.41008)
			(xy 93.154506 -319.41008) (xy 93.158522 -319.29381) (xy 93.170549 -319.178095) (xy 93.190531 -319.063485)
			(xy 93.218373 -318.950526) (xy 93.253942 -318.839758) (xy 93.297068 -318.731707) (xy 93.347545 -318.626889)
			(xy 93.405134 -318.525804) (xy 93.46956 -318.428932) (xy 93.540515 -318.336736) (xy 93.617662 -318.249655)
			(xy 93.700633 -318.168104) (xy 93.789033 -318.092472) (xy 93.88244 -318.023118) (xy 93.980409 -317.960375)
			(xy 94.082473 -317.904539) (xy 94.188147 -317.855878) (xy 94.296926 -317.814624) (xy 94.408291 -317.780973)
			(xy 94.521714 -317.755085) (xy 94.636651 -317.737084) (xy 94.752557 -317.727055) (xy 94.868879 -317.725047)
			(xy 94.985062 -317.731069) (xy 95.100553 -317.745092) (xy 95.214801 -317.76705) (xy 95.327262 -317.796837)
			(xy 95.4374 -317.834312) (xy 95.54469 -317.879297) (xy 95.648621 -317.931576) (xy 95.748697 -317.990901)
			(xy 95.844443 -318.056989) (xy 95.9354 -318.129525) (xy 96.021136 -318.208164) (xy 96.101243 -318.29253)
			(xy 96.175339 -318.382222) (xy 96.243069 -318.476812) (xy 96.304113 -318.57585) (xy 96.358178 -318.678863)
			(xy 96.405008 -318.78536) (xy 96.444379 -318.894835) (xy 96.476103 -319.006765) (xy 96.500029 -319.120617)
			(xy 96.516043 -319.235849) (xy 96.52407 -319.351911) (xy 96.524572 -319.41008) (xy 96.52407 -319.468249)
			(xy 96.516043 -319.584311) (xy 96.500029 -319.699543) (xy 96.476103 -319.813395) (xy 96.444379 -319.925325)
			(xy 96.405008 -320.0348) (xy 96.358178 -320.141297) (xy 96.304113 -320.24431) (xy 96.243069 -320.343348)
			(xy 96.175339 -320.437938) (xy 96.101243 -320.52763) (xy 96.021136 -320.611996) (xy 95.9354 -320.690635)
			(xy 95.844443 -320.763171) (xy 95.748697 -320.829259) (xy 95.648621 -320.888584) (xy 95.54469 -320.940863)
			(xy 95.4374 -320.985848) (xy 95.327262 -321.023323) (xy 95.214801 -321.05311) (xy 95.100553 -321.075068)
			(xy 94.985062 -321.089091) (xy 94.868879 -321.095113) (xy 94.752557 -321.093105) (xy 94.636651 -321.083076)
			(xy 94.521714 -321.065075) (xy 94.408291 -321.039187) (xy 94.296926 -321.005536) (xy 94.188147 -320.964282)
			(xy 94.082473 -320.915621) (xy 93.980409 -320.859785) (xy 93.88244 -320.797042) (xy 93.789033 -320.727688)
			(xy 93.700633 -320.652056) (xy 93.617662 -320.570505) (xy 93.540515 -320.483424) (xy 93.46956 -320.391228)
			(xy 93.405134 -320.294356) (xy 93.347545 -320.193271) (xy 93.297068 -320.088453) (xy 93.253942 -319.980402)
			(xy 93.218373 -319.869634) (xy 93.190531 -319.756675) (xy 93.170549 -319.642065) (xy 93.158522 -319.52635)
			(xy 93.154506 -319.41008) (xy 42.502604 -319.41008) (xy 42.502322 -319.410305) (xy 42.406779 -319.476254)
			(xy 42.306914 -319.535454) (xy 42.203202 -319.587623) (xy 42.096139 -319.632512) (xy 41.986233 -319.669908)
			(xy 41.874009 -319.699633) (xy 41.760003 -319.721544) (xy 41.644756 -319.735537) (xy 41.528818 -319.741546)
			(xy 41.412742 -319.739543) (xy 41.29708 -319.729535) (xy 41.182385 -319.711572) (xy 41.069202 -319.685739)
			(xy 40.958071 -319.652159) (xy 40.849522 -319.610991) (xy 40.744072 -319.562433) (xy 40.642223 -319.506716)
			(xy 40.54446 -319.444104) (xy 40.45125 -319.374897) (xy 40.363037 -319.299424) (xy 40.280241 -319.218045)
			(xy 40.203257 -319.131148) (xy 40.132452 -319.039147) (xy 40.068162 -318.94248) (xy 40.010695 -318.841608)
			(xy 39.960324 -318.737011) (xy 39.917289 -318.629188) (xy 39.881795 -318.518654) (xy 39.854012 -318.405934)
			(xy 39.834072 -318.291566) (xy 39.82207 -318.176094) (xy 39.818063 -318.06007) (xy 1.016 -318.06007)
			(xy 1.016 -329.871578) (xy 1.047496 -329.954382) (xy 1.059942 -329.969876) (xy 1.077482 -329.99257)
			(xy 1.106268 -330.042179) (xy 1.127305 -330.095537) (xy 1.14012 -330.151442) (xy 1.144423 -330.208636)
			(xy 1.14012 -330.26583) (xy 1.127305 -330.321735) (xy 1.106268 -330.375093) (xy 1.077482 -330.424702)
			(xy 1.059942 -330.447396) (xy 1.047496 -330.46289) (xy 1.016 -330.545694) (xy 1.016 -331.16012) (xy 86.877404 -331.16012)
			(xy 86.881424 -330.969469) (xy 86.893478 -330.779156) (xy 86.913544 -330.589521) (xy 86.941587 -330.4009)
			(xy 86.977556 -330.21363) (xy 87.021388 -330.028042) (xy 87.073005 -329.844467) (xy 87.132315 -329.663231)
			(xy 87.199213 -329.484656) (xy 87.273579 -329.309061) (xy 87.355281 -329.136756) (xy 87.444175 -328.968049)
			(xy 87.540101 -328.803239) (xy 87.64289 -328.64262) (xy 87.752359 -328.486477) (xy 87.868313 -328.335088)
			(xy 87.990547 -328.188721) (xy 88.118841 -328.047637) (xy 88.252969 -327.912088) (xy 88.392693 -327.782313)
			(xy 88.537763 -327.658543) (xy 88.687921 -327.541) (xy 88.842902 -327.429891) (xy 89.002429 -327.325414)
			(xy 89.166218 -327.227755) (xy 89.333978 -327.137088) (xy 89.505412 -327.053574) (xy 89.680214 -326.977361)
			(xy 89.858073 -326.908585) (xy 90.038674 -326.847367) (xy 90.221694 -326.793818) (xy 90.40681 -326.748032)
			(xy 90.593691 -326.71009) (xy 90.782006 -326.680061) (xy 90.971419 -326.657996) (xy 91.161593 -326.643937)
			(xy 91.352192 -326.637907) (xy 91.542875 -326.639917) (xy 91.733304 -326.649964) (xy 91.92314 -326.66803)
			(xy 92.112046 -326.694083) (xy 92.299685 -326.728076) (xy 92.485725 -326.769949) (xy 92.669834 -326.819628)
			(xy 92.851685 -326.877024) (xy 93.030955 -326.942035) (xy 93.207325 -327.014546) (xy 93.380481 -327.094427)
			(xy 93.550116 -327.181537) (xy 93.715928 -327.275721) (xy 93.877622 -327.376812) (xy 94.03491 -327.484628)
			(xy 94.187513 -327.59898) (xy 94.335161 -327.719663) (xy 94.477589 -327.846464) (xy 94.614545 -327.979155)
			(xy 94.745786 -328.117503) (xy 94.871078 -328.26126) (xy 94.990198 -328.410171) (xy 95.102934 -328.563972)
			(xy 95.209087 -328.722388) (xy 95.308467 -328.885139) (xy 95.400897 -329.051934) (xy 95.486214 -329.222478)
			(xy 95.564266 -329.396466) (xy 95.634913 -329.573591) (xy 95.698031 -329.753536) (xy 95.753507 -329.935982)
			(xy 95.801242 -330.120605) (xy 95.841152 -330.307075) (xy 95.873165 -330.495063) (xy 95.897225 -330.684233)
			(xy 95.913288 -330.874249) (xy 95.921327 -331.064773) (xy 95.92183 -331.16012) (xy 95.921327 -331.255467)
			(xy 95.913288 -331.445991) (xy 95.897225 -331.636007) (xy 95.873165 -331.825177) (xy 95.841152 -332.013165)
			(xy 95.801242 -332.199635) (xy 95.753507 -332.384258) (xy 95.698031 -332.566704) (xy 95.634913 -332.746649)
			(xy 95.564266 -332.923774) (xy 95.486214 -333.097762) (xy 95.400897 -333.268306) (xy 95.308467 -333.435101)
			(xy 95.209087 -333.597852) (xy 95.102934 -333.756268) (xy 94.990198 -333.910069) (xy 94.871078 -334.05898)
			(xy 94.745786 -334.202737) (xy 94.614545 -334.341085) (xy 94.477589 -334.473776) (xy 94.335161 -334.600577)
			(xy 94.187513 -334.72126) (xy 94.03491 -334.835612) (xy 93.877622 -334.943428) (xy 93.715928 -335.044519)
			(xy 93.550116 -335.138703) (xy 93.380481 -335.225813) (xy 93.207325 -335.305694) (xy 93.030955 -335.378205)
			(xy 92.851685 -335.443216) (xy 92.669834 -335.500612) (xy 92.485725 -335.550291) (xy 92.299685 -335.592164)
			(xy 92.112046 -335.626157) (xy 91.92314 -335.65221) (xy 91.733304 -335.670276) (xy 91.542875 -335.680323)
			(xy 91.352192 -335.682333) (xy 91.161593 -335.676303) (xy 90.971419 -335.662244) (xy 90.782006 -335.640179)
			(xy 90.593691 -335.61015) (xy 90.40681 -335.572208) (xy 90.221694 -335.526422) (xy 90.038674 -335.472873)
			(xy 89.858073 -335.411655) (xy 89.680214 -335.342879) (xy 89.505412 -335.266666) (xy 89.333978 -335.183152)
			(xy 89.166218 -335.092485) (xy 89.002429 -334.994826) (xy 88.842902 -334.890349) (xy 88.687921 -334.77924)
			(xy 88.537763 -334.661697) (xy 88.392693 -334.537927) (xy 88.252969 -334.408152) (xy 88.118841 -334.272603)
			(xy 87.990547 -334.131519) (xy 87.868313 -333.985152) (xy 87.752359 -333.833763) (xy 87.64289 -333.67762)
			(xy 87.540101 -333.517001) (xy 87.444175 -333.352191) (xy 87.355281 -333.183484) (xy 87.273579 -333.011179)
			(xy 87.199213 -332.835584) (xy 87.132315 -332.657009) (xy 87.073005 -332.475773) (xy 87.021388 -332.292198)
			(xy 86.977556 -332.10661) (xy 86.941587 -331.91934) (xy 86.913544 -331.730719) (xy 86.893478 -331.541084)
			(xy 86.881424 -331.350771) (xy 86.877404 -331.16012) (xy 1.016 -331.16012) (xy 1.016 -341.019892)
			(xy 3.583178 -341.019892) (xy 3.583678 -340.962646) (xy 3.59178 -340.848441) (xy 3.607943 -340.735095)
			(xy 3.632086 -340.623177) (xy 3.664086 -340.513247) (xy 3.703785 -340.405858) (xy 3.750982 -340.301546)
			(xy 3.805442 -340.200836) (xy 3.866891 -340.104231) (xy 3.935021 -340.012216) (xy 4.009491 -339.925252)
			(xy 4.089928 -339.843775) (xy 4.175928 -339.768194) (xy 4.26706 -339.698887) (xy 4.362867 -339.636202)
			(xy 4.46287 -339.580453) (xy 4.566566 -339.531919) (xy 4.673437 -339.490844) (xy 4.782946 -339.457434)
			(xy 4.894545 -339.431855) (xy 5.007674 -339.414237) (xy 5.121765 -339.404668) (xy 5.236248 -339.403195)
			(xy 5.350548 -339.409826) (xy 5.464093 -339.424528) (xy 5.576313 -339.447227) (xy 5.686645 -339.477809)
			(xy 5.794537 -339.516121) (xy 5.899448 -339.561971) (xy 6.000852 -339.615129) (xy 6.09824 -339.675328)
			(xy 6.191125 -339.742268) (xy 6.279041 -339.815611) (xy 6.361547 -339.894992) (xy 6.43823 -339.980011)
			(xy 6.508705 -340.070243) (xy 6.572619 -340.165235) (xy 6.629651 -340.264511) (xy 6.679516 -340.367574)
			(xy 6.721964 -340.473907) (xy 6.756783 -340.582977) (xy 6.783796 -340.694236) (xy 6.80287 -340.807129)
			(xy 6.813908 -340.921088) (xy 6.816855 -341.035542) (xy 6.811697 -341.149918) (xy 6.800075 -341.249762)
			(xy 72.857112 -341.249762) (xy 72.861127 -341.04658) (xy 72.873166 -340.843715) (xy 72.89321 -340.641485)
			(xy 72.921228 -340.440204) (xy 72.957176 -340.240187) (xy 73.000998 -340.041746) (xy 73.052625 -339.845192)
			(xy 73.111977 -339.650831) (xy 73.178962 -339.458966) (xy 73.253474 -339.269897) (xy 73.335397 -339.08392)
			(xy 73.424604 -338.901324) (xy 73.520955 -338.722395) (xy 73.624299 -338.547413) (xy 73.734476 -338.37665)
			(xy 73.851313 -338.210372) (xy 73.974628 -338.048841) (xy 74.104228 -337.892307) (xy 74.239911 -337.741016)
			(xy 74.381466 -337.595203) (xy 74.52867 -337.455096) (xy 74.681294 -337.320914) (xy 74.839101 -337.192866)
			(xy 75.001843 -337.071153) (xy 75.169266 -336.955965) (xy 75.341109 -336.84748) (xy 75.517104 -336.745869)
			(xy 75.696976 -336.651291) (xy 75.880444 -336.563892) (xy 76.067222 -336.48381) (xy 76.257018 -336.41117)
			(xy 76.449535 -336.346084) (xy 76.644473 -336.288655) (xy 76.841528 -336.238972) (xy 77.040392 -336.197112)
			(xy 77.240754 -336.163142) (xy 77.442302 -336.137114) (xy 77.644721 -336.119069) (xy 77.847694 -336.109035)
			(xy 78.050906 -336.107027) (xy 78.254038 -336.113049) (xy 78.456774 -336.127092) (xy 78.658797 -336.149133)
			(xy 78.859791 -336.179138) (xy 79.059443 -336.21706) (xy 79.257441 -336.26284) (xy 79.453476 -336.316406)
			(xy 79.647241 -336.377676) (xy 79.838435 -336.446552) (xy 80.026758 -336.522929) (xy 80.211917 -336.606685)
			(xy 80.393623 -336.697692) (xy 80.571591 -336.795805) (xy 80.745544 -336.900874) (xy 80.915211 -337.012732)
			(xy 81.080325 -337.131206) (xy 81.240631 -337.256111) (xy 81.395877 -337.387251) (xy 81.54582 -337.524422)
			(xy 81.690228 -337.66741) (xy 81.828873 -337.815991) (xy 81.961541 -337.969934) (xy 82.088023 -338.128997)
			(xy 82.208123 -338.292934) (xy 82.321652 -338.461487) (xy 82.428433 -338.634394) (xy 82.5283 -338.811384)
			(xy 82.621097 -338.992181) (xy 82.706679 -339.176504) (xy 82.784912 -339.364063) (xy 82.855674 -339.554567)
			(xy 82.918855 -339.747718) (xy 82.974355 -339.943214) (xy 83.022089 -340.14075) (xy 83.061982 -340.340018)
			(xy 83.093971 -340.540706) (xy 83.118007 -340.742501) (xy 83.134052 -340.945088) (xy 83.14208 -341.148151)
			(xy 83.142582 -341.249762) (xy 83.14208 -341.351373) (xy 83.134052 -341.554436) (xy 83.118007 -341.757023)
			(xy 83.093971 -341.958818) (xy 83.061982 -342.159506) (xy 83.022089 -342.358774) (xy 82.974355 -342.55631)
			(xy 82.918855 -342.751806) (xy 82.855674 -342.944957) (xy 82.784912 -343.135461) (xy 82.706679 -343.32302)
			(xy 82.621097 -343.507343) (xy 82.5283 -343.68814) (xy 82.428433 -343.86513) (xy 82.321652 -344.038037)
			(xy 82.208123 -344.20659) (xy 82.088023 -344.370527) (xy 81.961541 -344.52959) (xy 81.828873 -344.683533)
			(xy 81.690228 -344.832114) (xy 81.54582 -344.975102) (xy 81.395877 -345.112273) (xy 81.240631 -345.243413)
			(xy 81.080325 -345.368318) (xy 80.915211 -345.486792) (xy 80.745544 -345.59865) (xy 80.571591 -345.703719)
			(xy 80.393623 -345.801832) (xy 80.211917 -345.892839) (xy 80.026758 -345.976595) (xy 79.838435 -346.052972)
			(xy 79.647241 -346.121848) (xy 79.453476 -346.183118) (xy 79.257441 -346.236684) (xy 79.059443 -346.282464)
			(xy 78.859791 -346.320386) (xy 78.658797 -346.350391) (xy 78.456774 -346.372432) (xy 78.254038 -346.386475)
			(xy 78.050906 -346.392497) (xy 77.847694 -346.390489) (xy 77.644721 -346.380455) (xy 77.442302 -346.36241)
			(xy 77.240754 -346.336382) (xy 77.040392 -346.302412) (xy 76.841528 -346.260552) (xy 76.644473 -346.210869)
			(xy 76.449535 -346.15344) (xy 76.257018 -346.088354) (xy 76.067222 -346.015714) (xy 75.880444 -345.935632)
			(xy 75.696976 -345.848233) (xy 75.517104 -345.753655) (xy 75.341109 -345.652044) (xy 75.169266 -345.543559)
			(xy 75.001843 -345.428371) (xy 74.839101 -345.306658) (xy 74.681294 -345.17861) (xy 74.52867 -345.044428)
			(xy 74.381466 -344.904321) (xy 74.239911 -344.758508) (xy 74.104228 -344.607217) (xy 73.974628 -344.450683)
			(xy 73.851313 -344.289152) (xy 73.734476 -344.122874) (xy 73.624299 -343.952111) (xy 73.520955 -343.777129)
			(xy 73.424604 -343.5982) (xy 73.335397 -343.415604) (xy 73.253474 -343.229627) (xy 73.178962 -343.040558)
			(xy 73.111977 -342.848693) (xy 73.052625 -342.654332) (xy 73.000998 -342.457778) (xy 72.957176 -342.259337)
			(xy 72.921228 -342.05932) (xy 72.89321 -341.858039) (xy 72.873166 -341.655809) (xy 72.861127 -341.452944)
			(xy 72.857112 -341.249762) (xy 6.800075 -341.249762) (xy 6.798459 -341.263643) (xy 6.777208 -341.376146)
			(xy 6.748049 -341.486863) (xy 6.71113 -341.595239) (xy 6.666635 -341.700732) (xy 6.614788 -341.802812)
			(xy 6.555848 -341.900968) (xy 6.49011 -341.994707) (xy 6.454394 -342.039448) (xy 6.060186 -342.039448)
			(xy 6.021179 -342.071737) (xy 5.939048 -342.130983) (xy 5.896102 -342.157812) (xy 5.882524 -342.166761)
			(xy 5.860006 -342.190206) (xy 5.844123 -342.218568) (xy 5.8359 -342.250017) (xy 5.835396 -342.26627)
			(xy 5.835396 -342.5063) (xy 5.780703 -342.52911) (xy 5.668615 -342.567604) (xy 5.55401 -342.597788)
			(xy 5.437502 -342.619498) (xy 5.319718 -342.632619) (xy 5.201288 -342.63708) (xy 5.08285 -342.632856)
			(xy 4.96504 -342.619971) (xy 4.848489 -342.598494) (xy 4.733823 -342.56854) (xy 4.621659 -342.53027)
			(xy 4.56692 -342.50757) (xy 4.56692 -342.26754) (xy 4.566441 -342.251261) (xy 4.558186 -342.219766)
			(xy 4.542229 -342.191387) (xy 4.519608 -342.167969) (xy 4.50596 -342.159082) (xy 4.459776 -342.130343)
			(xy 4.371783 -342.066378) (xy 4.330192 -342.03132) (xy 3.938778 -342.03132) (xy 3.904941 -341.988409)
			(xy 3.842477 -341.898728) (xy 3.78621 -341.805035) (xy 3.736399 -341.707756) (xy 3.69327 -341.607335)
			(xy 3.657021 -341.504231) (xy 3.627816 -341.398915) (xy 3.60579 -341.291867) (xy 3.591042 -341.183577)
			(xy 3.583641 -341.074537) (xy 3.583178 -341.019892) (xy 1.016 -341.019892) (xy 1.016 -342.571578)
			(xy 1.047496 -342.654382) (xy 1.059942 -342.669876) (xy 1.077482 -342.69257) (xy 1.106268 -342.742179)
			(xy 1.127305 -342.795537) (xy 1.14012 -342.851442) (xy 1.144423 -342.908636) (xy 1.14012 -342.96583)
			(xy 1.127305 -343.021735) (xy 1.106268 -343.075093) (xy 1.077482 -343.124702) (xy 1.059942 -343.147396)
			(xy 1.047496 -343.16289) (xy 1.016 -343.245694) (xy 1.016 -355.271578) (xy 1.047496 -355.354382)
			(xy 1.059942 -355.369876) (xy 1.077482 -355.39257) (xy 1.106268 -355.442179) (xy 1.127305 -355.495537)
			(xy 1.14012 -355.551442) (xy 1.144423 -355.608636) (xy 1.14012 -355.66583) (xy 1.127305 -355.721735)
			(xy 1.106268 -355.775093) (xy 1.077482 -355.824702) (xy 1.059942 -355.847396) (xy 1.047496 -355.86289)
			(xy 1.016 -355.945694) (xy 1.016 -362.51007) (xy 39.818063 -362.51007) (xy 39.82207 -362.394046)
			(xy 39.834072 -362.278574) (xy 39.854012 -362.164206) (xy 39.881795 -362.051486) (xy 39.917289 -361.940952)
			(xy 39.960324 -361.833129) (xy 40.010695 -361.728532) (xy 40.068162 -361.62766) (xy 40.132452 -361.530993)
			(xy 40.203257 -361.438992) (xy 40.280241 -361.352095) (xy 40.363037 -361.270716) (xy 40.45125 -361.195243)
			(xy 40.54446 -361.126036) (xy 40.642223 -361.063424) (xy 40.744072 -361.007707) (xy 40.849522 -360.959149)
			(xy 40.958071 -360.917981) (xy 41.069202 -360.884401) (xy 41.182385 -360.858568) (xy 41.29708 -360.840605)
			(xy 41.412742 -360.830597) (xy 41.528818 -360.828594) (xy 41.644756 -360.834603) (xy 41.760003 -360.848596)
			(xy 41.874009 -360.870507) (xy 41.986233 -360.900232) (xy 42.096139 -360.937628) (xy 42.203202 -360.982517)
			(xy 42.306914 -361.034686) (xy 42.406779 -361.093886) (xy 42.502322 -361.159835) (xy 42.593088 -361.232218)
			(xy 42.678643 -361.310691) (xy 42.758581 -361.394879) (xy 42.83252 -361.484381) (xy 42.900108 -361.578772)
			(xy 42.961022 -361.6776) (xy 43.014974 -361.780396) (xy 43.061704 -361.886669) (xy 43.100992 -361.995913)
			(xy 43.132649 -362.107606) (xy 43.156525 -362.221218) (xy 43.172506 -362.336206) (xy 43.180515 -362.452023)
			(xy 43.181016 -362.51007) (xy 43.180515 -362.568117) (xy 43.172506 -362.683934) (xy 43.156525 -362.798922)
			(xy 43.132649 -362.912534) (xy 43.100992 -363.024227) (xy 43.061704 -363.133471) (xy 43.014974 -363.239744)
			(xy 42.961022 -363.34254) (xy 42.900108 -363.441368) (xy 42.83252 -363.535759) (xy 42.758581 -363.625261)
			(xy 42.678643 -363.709449) (xy 42.593088 -363.787922) (xy 42.502604 -363.86008) (xy 93.154506 -363.86008)
			(xy 93.158522 -363.74381) (xy 93.170549 -363.628095) (xy 93.190531 -363.513485) (xy 93.218373 -363.400526)
			(xy 93.253942 -363.289758) (xy 93.297068 -363.181707) (xy 93.347545 -363.076889) (xy 93.405134 -362.975804)
			(xy 93.46956 -362.878932) (xy 93.540515 -362.786736) (xy 93.617662 -362.699655) (xy 93.700633 -362.618104)
			(xy 93.789033 -362.542472) (xy 93.88244 -362.473118) (xy 93.980409 -362.410375) (xy 94.082473 -362.354539)
			(xy 94.188147 -362.305878) (xy 94.296926 -362.264624) (xy 94.408291 -362.230973) (xy 94.521714 -362.205085)
			(xy 94.636651 -362.187084) (xy 94.752557 -362.177055) (xy 94.868879 -362.175047) (xy 94.985062 -362.181069)
			(xy 95.100553 -362.195092) (xy 95.214801 -362.21705) (xy 95.327262 -362.246837) (xy 95.4374 -362.284312)
			(xy 95.54469 -362.329297) (xy 95.648621 -362.381576) (xy 95.748697 -362.440901) (xy 95.844443 -362.506989)
			(xy 95.9354 -362.579525) (xy 96.021136 -362.658164) (xy 96.101243 -362.74253) (xy 96.175339 -362.832222)
			(xy 96.243069 -362.926812) (xy 96.304113 -363.02585) (xy 96.358178 -363.128863) (xy 96.405008 -363.23536)
			(xy 96.444379 -363.344835) (xy 96.476103 -363.456765) (xy 96.500029 -363.570617) (xy 96.516043 -363.685849)
			(xy 96.52407 -363.801911) (xy 96.524572 -363.86008) (xy 96.52407 -363.918249) (xy 96.516043 -364.034311)
			(xy 96.500029 -364.149543) (xy 96.476103 -364.263395) (xy 96.444379 -364.375325) (xy 96.405008 -364.4848)
			(xy 96.358178 -364.591297) (xy 96.304113 -364.69431) (xy 96.243069 -364.793348) (xy 96.175339 -364.887938)
			(xy 96.101243 -364.97763) (xy 96.021136 -365.061996) (xy 95.9354 -365.140635) (xy 95.844443 -365.213171)
			(xy 95.748697 -365.279259) (xy 95.648621 -365.338584) (xy 95.54469 -365.390863) (xy 95.4374 -365.435848)
			(xy 95.327262 -365.473323) (xy 95.214801 -365.50311) (xy 95.100553 -365.525068) (xy 94.985062 -365.539091)
			(xy 94.868879 -365.545113) (xy 94.752557 -365.543105) (xy 94.636651 -365.533076) (xy 94.521714 -365.515075)
			(xy 94.408291 -365.489187) (xy 94.296926 -365.455536) (xy 94.188147 -365.414282) (xy 94.082473 -365.365621)
			(xy 93.980409 -365.309785) (xy 93.88244 -365.247042) (xy 93.789033 -365.177688) (xy 93.700633 -365.102056)
			(xy 93.617662 -365.020505) (xy 93.540515 -364.933424) (xy 93.46956 -364.841228) (xy 93.405134 -364.744356)
			(xy 93.347545 -364.643271) (xy 93.297068 -364.538453) (xy 93.253942 -364.430402) (xy 93.218373 -364.319634)
			(xy 93.190531 -364.206675) (xy 93.170549 -364.092065) (xy 93.158522 -363.97635) (xy 93.154506 -363.86008)
			(xy 42.502604 -363.86008) (xy 42.502322 -363.860305) (xy 42.406779 -363.926254) (xy 42.306914 -363.985454)
			(xy 42.203202 -364.037623) (xy 42.096139 -364.082512) (xy 41.986233 -364.119908) (xy 41.874009 -364.149633)
			(xy 41.760003 -364.171544) (xy 41.644756 -364.185537) (xy 41.528818 -364.191546) (xy 41.412742 -364.189543)
			(xy 41.29708 -364.179535) (xy 41.182385 -364.161572) (xy 41.069202 -364.135739) (xy 40.958071 -364.102159)
			(xy 40.849522 -364.060991) (xy 40.744072 -364.012433) (xy 40.642223 -363.956716) (xy 40.54446 -363.894104)
			(xy 40.45125 -363.824897) (xy 40.363037 -363.749424) (xy 40.280241 -363.668045) (xy 40.203257 -363.581148)
			(xy 40.132452 -363.489147) (xy 40.068162 -363.39248) (xy 40.010695 -363.291608) (xy 39.960324 -363.187011)
			(xy 39.917289 -363.079188) (xy 39.881795 -362.968654) (xy 39.854012 -362.855934) (xy 39.834072 -362.741566)
			(xy 39.82207 -362.626094) (xy 39.818063 -362.51007) (xy 1.016 -362.51007) (xy 1.016 -367.971578)
			(xy 1.047496 -368.054382) (xy 1.059942 -368.069876) (xy 1.077482 -368.09257) (xy 1.106268 -368.142179)
			(xy 1.127305 -368.195537) (xy 1.14012 -368.251442) (xy 1.144423 -368.308636) (xy 1.14012 -368.36583)
			(xy 1.127305 -368.421735) (xy 1.106268 -368.475093) (xy 1.077482 -368.524702) (xy 1.059942 -368.547396)
			(xy 1.047496 -368.56289) (xy 1.016 -368.645694) (xy 1.016 -375.61012) (xy 86.877404 -375.61012) (xy 86.881424 -375.419469)
			(xy 86.893478 -375.229156) (xy 86.913544 -375.039521) (xy 86.941587 -374.8509) (xy 86.977556 -374.66363)
			(xy 87.021388 -374.478042) (xy 87.073005 -374.294467) (xy 87.132315 -374.113231) (xy 87.199213 -373.934656)
			(xy 87.273579 -373.759061) (xy 87.355281 -373.586756) (xy 87.444175 -373.418049) (xy 87.540101 -373.253239)
			(xy 87.64289 -373.09262) (xy 87.752359 -372.936477) (xy 87.868313 -372.785088) (xy 87.990547 -372.638721)
			(xy 88.118841 -372.497637) (xy 88.252969 -372.362088) (xy 88.392693 -372.232313) (xy 88.537763 -372.108543)
			(xy 88.687921 -371.991) (xy 88.842902 -371.879891) (xy 89.002429 -371.775414) (xy 89.166218 -371.677755)
			(xy 89.333978 -371.587088) (xy 89.505412 -371.503574) (xy 89.680214 -371.427361) (xy 89.858073 -371.358585)
			(xy 90.038674 -371.297367) (xy 90.221694 -371.243818) (xy 90.40681 -371.198032) (xy 90.593691 -371.16009)
			(xy 90.782006 -371.130061) (xy 90.971419 -371.107996) (xy 91.161593 -371.093937) (xy 91.352192 -371.087907)
			(xy 91.542875 -371.089917) (xy 91.733304 -371.099964) (xy 91.92314 -371.11803) (xy 92.112046 -371.144083)
			(xy 92.299685 -371.178076) (xy 92.485725 -371.219949) (xy 92.669834 -371.269628) (xy 92.851685 -371.327024)
			(xy 93.030955 -371.392035) (xy 93.207325 -371.464546) (xy 93.380481 -371.544427) (xy 93.550116 -371.631537)
			(xy 93.715928 -371.725721) (xy 93.877622 -371.826812) (xy 94.03491 -371.934628) (xy 94.187513 -372.04898)
			(xy 94.335161 -372.169663) (xy 94.477589 -372.296464) (xy 94.614545 -372.429155) (xy 94.745786 -372.567503)
			(xy 94.871078 -372.71126) (xy 94.990198 -372.860171) (xy 95.102934 -373.013972) (xy 95.209087 -373.172388)
			(xy 95.308467 -373.335139) (xy 95.400897 -373.501934) (xy 95.486214 -373.672478) (xy 95.564266 -373.846466)
			(xy 95.634913 -374.023591) (xy 95.698031 -374.203536) (xy 95.753507 -374.385982) (xy 95.801242 -374.570605)
			(xy 95.841152 -374.757075) (xy 95.873165 -374.945063) (xy 95.897225 -375.134233) (xy 95.913288 -375.324249)
			(xy 95.921327 -375.514773) (xy 95.92183 -375.61012) (xy 95.921327 -375.705467) (xy 95.913288 -375.895991)
			(xy 95.897225 -376.086007) (xy 95.873165 -376.275177) (xy 95.841152 -376.463165) (xy 95.801242 -376.649635)
			(xy 95.753507 -376.834258) (xy 95.698031 -377.016704) (xy 95.634913 -377.196649) (xy 95.564266 -377.373774)
			(xy 95.486214 -377.547762) (xy 95.400897 -377.718306) (xy 95.308467 -377.885101) (xy 95.209087 -378.047852)
			(xy 95.102934 -378.206268) (xy 94.990198 -378.360069) (xy 94.871078 -378.50898) (xy 94.745786 -378.652737)
			(xy 94.614545 -378.791085) (xy 94.477589 -378.923776) (xy 94.335161 -379.050577) (xy 94.187513 -379.17126)
			(xy 94.03491 -379.285612) (xy 93.877622 -379.393428) (xy 93.715928 -379.494519) (xy 93.550116 -379.588703)
			(xy 93.380481 -379.675813) (xy 93.207325 -379.755694) (xy 93.030955 -379.828205) (xy 92.851685 -379.893216)
			(xy 92.669834 -379.950612) (xy 92.485725 -380.000291) (xy 92.299685 -380.042164) (xy 92.112046 -380.076157)
			(xy 91.92314 -380.10221) (xy 91.733304 -380.120276) (xy 91.542875 -380.130323) (xy 91.352192 -380.132333)
			(xy 91.161593 -380.126303) (xy 90.971419 -380.112244) (xy 90.782006 -380.090179) (xy 90.593691 -380.06015)
			(xy 90.40681 -380.022208) (xy 90.221694 -379.976422) (xy 90.038674 -379.922873) (xy 89.858073 -379.861655)
			(xy 89.680214 -379.792879) (xy 89.505412 -379.716666) (xy 89.333978 -379.633152) (xy 89.166218 -379.542485)
			(xy 89.002429 -379.444826) (xy 88.842902 -379.340349) (xy 88.687921 -379.22924) (xy 88.537763 -379.111697)
			(xy 88.392693 -378.987927) (xy 88.252969 -378.858152) (xy 88.118841 -378.722603) (xy 87.990547 -378.581519)
			(xy 87.868313 -378.435152) (xy 87.752359 -378.283763) (xy 87.64289 -378.12762) (xy 87.540101 -377.967001)
			(xy 87.444175 -377.802191) (xy 87.355281 -377.633484) (xy 87.273579 -377.461179) (xy 87.199213 -377.285584)
			(xy 87.132315 -377.107009) (xy 87.073005 -376.925773) (xy 87.021388 -376.742198) (xy 86.977556 -376.55661)
			(xy 86.941587 -376.36934) (xy 86.913544 -376.180719) (xy 86.893478 -375.991084) (xy 86.881424 -375.800771)
			(xy 86.877404 -375.61012) (xy 1.016 -375.61012) (xy 1.016 -380.671578) (xy 1.047496 -380.754382)
			(xy 1.059942 -380.769876) (xy 1.077482 -380.79257) (xy 1.106268 -380.842179) (xy 1.127305 -380.895537)
			(xy 1.14012 -380.951442) (xy 1.144423 -381.008636) (xy 1.14012 -381.06583) (xy 1.127305 -381.121735)
			(xy 1.106268 -381.175093) (xy 1.077482 -381.224702) (xy 1.059942 -381.247396) (xy 1.047496 -381.26289)
			(xy 1.016 -381.345694) (xy 1.016 -384.79984) (xy 11.344156 -384.79984) (xy 11.348157 -384.594781)
			(xy 11.360157 -384.390034) (xy 11.380135 -384.185911) (xy 11.408063 -383.982723) (xy 11.443897 -383.780779)
			(xy 11.487582 -383.580388) (xy 11.539053 -383.381853) (xy 11.598231 -383.185477) (xy 11.665026 -382.99156)
			(xy 11.739335 -382.800397) (xy 11.821046 -382.612279) (xy 11.910035 -382.427492) (xy 12.006166 -382.246317)
			(xy 12.109292 -382.069031) (xy 12.219257 -381.895904) (xy 12.335893 -381.727199) (xy 12.459022 -381.563173)
			(xy 12.588457 -381.404076) (xy 12.724001 -381.25015) (xy 12.865447 -381.10163) (xy 13.01258 -380.958741)
			(xy 13.165176 -380.821702) (xy 13.323003 -380.690721) (xy 13.48582 -380.565997) (xy 13.653379 -380.447721)
			(xy 13.825425 -380.336073) (xy 14.001696 -380.231222) (xy 14.181924 -380.133328) (xy 14.365835 -380.042541)
			(xy 14.553147 -379.958998) (xy 14.743576 -379.882827) (xy 14.936832 -379.814143) (xy 15.132621 -379.753053)
			(xy 15.330644 -379.699647) (xy 15.5306 -379.654009) (xy 15.732184 -379.616206) (xy 15.93509 -379.586298)
			(xy 16.139008 -379.564328) (xy 16.343629 -379.550332) (xy 16.548639 -379.54433) (xy 16.753728 -379.546331)
			(xy 16.958582 -379.556332) (xy 17.16289 -379.574318) (xy 17.366341 -379.600262) (xy 17.568624 -379.634124)
			(xy 17.769433 -379.675852) (xy 17.96846 -379.725384) (xy 18.165404 -379.782643) (xy 18.359963 -379.847542)
			(xy 18.551842 -379.919983) (xy 18.740749 -379.999855) (xy 18.926395 -380.087037) (xy 19.108499 -380.181396)
			(xy 19.286783 -380.282787) (xy 19.460975 -380.391058) (xy 19.63081 -380.506042) (xy 19.796029 -380.627565)
			(xy 19.956381 -380.755442) (xy 20.111622 -380.889477) (xy 20.261516 -381.029468) (xy 20.405833 -381.1752)
			(xy 20.544354 -381.326452) (xy 20.676869 -381.482993) (xy 20.803175 -381.644585) (xy 20.92308 -381.810982)
			(xy 21.036402 -381.981931) (xy 21.142968 -382.157171) (xy 21.242615 -382.336435) (xy 21.335193 -382.519451)
			(xy 21.420559 -382.705939) (xy 21.498584 -382.895616) (xy 21.56915 -383.088193) (xy 21.632148 -383.283376)
			(xy 21.687483 -383.480869) (xy 21.73507 -383.68037) (xy 21.774837 -383.881576) (xy 21.806724 -384.084181)
			(xy 21.830682 -384.287875) (xy 21.846674 -384.492349) (xy 21.854676 -384.697291) (xy 21.855176 -384.79984)
			(xy 21.854676 -384.902389) (xy 21.846674 -385.107331) (xy 21.830682 -385.311805) (xy 21.806724 -385.515499)
			(xy 21.774837 -385.718104) (xy 21.73507 -385.91931) (xy 21.687483 -386.118811) (xy 21.632148 -386.316304)
			(xy 21.56915 -386.511487) (xy 21.498584 -386.704064) (xy 21.420559 -386.893741) (xy 21.335193 -387.080229)
			(xy 21.242615 -387.263245) (xy 21.142968 -387.442509) (xy 21.036402 -387.617749) (xy 20.92308 -387.788698)
			(xy 20.803175 -387.955095) (xy 20.676869 -388.116687) (xy 20.544354 -388.273228) (xy 20.405833 -388.42448)
			(xy 20.261516 -388.570212) (xy 20.111622 -388.710203) (xy 19.956381 -388.844238) (xy 19.796029 -388.972115)
			(xy 19.63081 -389.093638) (xy 19.460975 -389.208622) (xy 19.286783 -389.316893) (xy 19.108499 -389.418284)
			(xy 18.926395 -389.512643) (xy 18.740749 -389.599825) (xy 18.551842 -389.679697) (xy 18.359963 -389.752138)
			(xy 18.165404 -389.817037) (xy 17.96846 -389.874296) (xy 17.769433 -389.923828) (xy 17.568624 -389.965556)
			(xy 17.366341 -389.999418) (xy 17.16289 -390.025362) (xy 16.958582 -390.043348) (xy 16.753728 -390.053349)
			(xy 16.548639 -390.05535) (xy 16.343629 -390.049348) (xy 16.139008 -390.035352) (xy 15.93509 -390.013382)
			(xy 15.732184 -389.983474) (xy 15.5306 -389.945671) (xy 15.330644 -389.900033) (xy 15.132621 -389.846627)
			(xy 14.936832 -389.785537) (xy 14.743576 -389.716853) (xy 14.553147 -389.640682) (xy 14.365835 -389.557139)
			(xy 14.181924 -389.466352) (xy 14.001696 -389.368458) (xy 13.825425 -389.263607) (xy 13.653379 -389.151959)
			(xy 13.48582 -389.033683) (xy 13.323003 -388.908959) (xy 13.165176 -388.777978) (xy 13.01258 -388.640939)
			(xy 12.865447 -388.49805) (xy 12.724001 -388.34953) (xy 12.588457 -388.195604) (xy 12.459022 -388.036507)
			(xy 12.335893 -387.872481) (xy 12.219257 -387.703776) (xy 12.109292 -387.530649) (xy 12.006166 -387.353363)
			(xy 11.910035 -387.172188) (xy 11.821046 -386.987401) (xy 11.739335 -386.799283) (xy 11.665026 -386.60812)
			(xy 11.598231 -386.414203) (xy 11.539053 -386.217827) (xy 11.487582 -386.019292) (xy 11.443897 -385.818901)
			(xy 11.408063 -385.616957) (xy 11.380135 -385.413769) (xy 11.360157 -385.209646) (xy 11.348157 -385.004899)
			(xy 11.344156 -384.79984) (xy 1.016 -384.79984) (xy 1.016 -393.371578) (xy 1.047496 -393.454382)
			(xy 1.059942 -393.469876) (xy 1.077482 -393.49257) (xy 1.106268 -393.542179) (xy 1.127305 -393.595537)
			(xy 1.14012 -393.651442) (xy 1.144423 -393.708636) (xy 1.14012 -393.76583) (xy 1.127305 -393.821735)
			(xy 1.106268 -393.875093) (xy 1.077482 -393.924702) (xy 1.059942 -393.947396) (xy 1.047496 -393.96289)
			(xy 1.016 -394.045694) (xy 1.016 -403.413036) (xy 1.547863 -403.413036) (xy 1.547863 -403.2869) (xy 1.555783 -403.161012)
			(xy 1.571593 -403.03587) (xy 1.595228 -402.911967) (xy 1.626597 -402.789794) (xy 1.665575 -402.669831)
			(xy 1.712009 -402.552552) (xy 1.765716 -402.43842) (xy 1.826483 -402.327885) (xy 1.89407 -402.221385)
			(xy 1.968211 -402.119338) (xy 2.048614 -402.022148) (xy 2.13496 -401.930198) (xy 2.22691 -401.843852)
			(xy 2.3241 -401.763449) (xy 2.426147 -401.689308) (xy 2.532647 -401.621721) (xy 2.643182 -401.560954)
			(xy 2.757314 -401.507247) (xy 2.874593 -401.460813) (xy 2.994556 -401.421835) (xy 3.116729 -401.390466)
			(xy 3.240632 -401.366831) (xy 3.365774 -401.351021) (xy 3.491662 -401.343101) (xy 3.617798 -401.343101)
			(xy 3.743686 -401.351021) (xy 3.868828 -401.366831) (xy 3.992731 -401.390466) (xy 4.114904 -401.421835)
			(xy 4.234867 -401.460813) (xy 4.352146 -401.507247) (xy 4.466278 -401.560954) (xy 4.576813 -401.621721)
			(xy 4.683313 -401.689308) (xy 4.78536 -401.763449) (xy 4.88255 -401.843852) (xy 4.9745 -401.930198)
			(xy 5.060846 -402.022148) (xy 5.141249 -402.119338) (xy 5.21539 -402.221385) (xy 5.282977 -402.327885)
			(xy 5.343744 -402.43842) (xy 5.397451 -402.552552) (xy 5.443885 -402.669831) (xy 5.482863 -402.789794)
			(xy 5.514232 -402.911967) (xy 5.537867 -403.03587) (xy 5.553677 -403.161012) (xy 5.561597 -403.2869)
			(xy 5.562092 -403.349968) (xy 5.561597 -403.413036) (xy 12.977863 -403.413036) (xy 12.977863 -403.2869)
			(xy 12.985783 -403.161012) (xy 13.001593 -403.03587) (xy 13.025228 -402.911967) (xy 13.056597 -402.789794)
			(xy 13.095575 -402.669831) (xy 13.142009 -402.552552) (xy 13.195716 -402.43842) (xy 13.256483 -402.327885)
			(xy 13.32407 -402.221385) (xy 13.398211 -402.119338) (xy 13.478614 -402.022148) (xy 13.56496 -401.930198)
			(xy 13.65691 -401.843852) (xy 13.7541 -401.763449) (xy 13.856147 -401.689308) (xy 13.962647 -401.621721)
			(xy 14.073182 -401.560954) (xy 14.187314 -401.507247) (xy 14.304593 -401.460813) (xy 14.424556 -401.421835)
			(xy 14.546729 -401.390466) (xy 14.670632 -401.366831) (xy 14.795774 -401.351021) (xy 14.921662 -401.343101)
			(xy 15.047798 -401.343101) (xy 15.173686 -401.351021) (xy 15.298828 -401.366831) (xy 15.422731 -401.390466)
			(xy 15.544904 -401.421835) (xy 15.664867 -401.460813) (xy 15.782146 -401.507247) (xy 15.896278 -401.560954)
			(xy 16.006813 -401.621721) (xy 16.113313 -401.689308) (xy 16.21536 -401.763449) (xy 16.31255 -401.843852)
			(xy 16.4045 -401.930198) (xy 16.490846 -402.022148) (xy 16.571249 -402.119338) (xy 16.64539 -402.221385)
			(xy 16.712977 -402.327885) (xy 16.773744 -402.43842) (xy 16.827451 -402.552552) (xy 16.873885 -402.669831)
			(xy 16.912863 -402.789794) (xy 16.944232 -402.911967) (xy 16.967867 -403.03587) (xy 16.983677 -403.161012)
			(xy 16.991597 -403.2869) (xy 16.992092 -403.349968) (xy 16.991597 -403.413036) (xy 16.983677 -403.538924)
			(xy 16.967867 -403.664066) (xy 16.944232 -403.787969) (xy 16.912863 -403.910142) (xy 16.873885 -404.030105)
			(xy 16.827451 -404.147384) (xy 16.773744 -404.261516) (xy 16.712977 -404.372051) (xy 16.64539 -404.478551)
			(xy 16.571249 -404.580598) (xy 16.490846 -404.677788) (xy 16.4045 -404.769738) (xy 16.31255 -404.856084)
			(xy 16.21536 -404.936487) (xy 16.113313 -405.010628) (xy 16.006813 -405.078215) (xy 15.896278 -405.138982)
			(xy 15.782146 -405.192689) (xy 15.664867 -405.239123) (xy 15.544904 -405.278101) (xy 15.422731 -405.30947)
			(xy 15.298828 -405.333105) (xy 15.173686 -405.348915) (xy 15.047798 -405.356835) (xy 14.921662 -405.356835)
			(xy 14.795774 -405.348915) (xy 14.670632 -405.333105) (xy 14.546729 -405.30947) (xy 14.424556 -405.278101)
			(xy 14.304593 -405.239123) (xy 14.187314 -405.192689) (xy 14.073182 -405.138982) (xy 13.962647 -405.078215)
			(xy 13.856147 -405.010628) (xy 13.7541 -404.936487) (xy 13.65691 -404.856084) (xy 13.56496 -404.769738)
			(xy 13.478614 -404.677788) (xy 13.398211 -404.580598) (xy 13.32407 -404.478551) (xy 13.256483 -404.372051)
			(xy 13.195716 -404.261516) (xy 13.142009 -404.147384) (xy 13.095575 -404.030105) (xy 13.056597 -403.910142)
			(xy 13.025228 -403.787969) (xy 13.001593 -403.664066) (xy 12.985783 -403.538924) (xy 12.977863 -403.413036)
			(xy 5.561597 -403.413036) (xy 5.553677 -403.538924) (xy 5.537867 -403.664066) (xy 5.514232 -403.787969)
			(xy 5.482863 -403.910142) (xy 5.443885 -404.030105) (xy 5.397451 -404.147384) (xy 5.343744 -404.261516)
			(xy 5.282977 -404.372051) (xy 5.21539 -404.478551) (xy 5.141249 -404.580598) (xy 5.060846 -404.677788)
			(xy 4.9745 -404.769738) (xy 4.88255 -404.856084) (xy 4.78536 -404.936487) (xy 4.683313 -405.010628)
			(xy 4.576813 -405.078215) (xy 4.466278 -405.138982) (xy 4.352146 -405.192689) (xy 4.234867 -405.239123)
			(xy 4.114904 -405.278101) (xy 3.992731 -405.30947) (xy 3.868828 -405.333105) (xy 3.743686 -405.348915)
			(xy 3.617798 -405.356835) (xy 3.491662 -405.356835) (xy 3.365774 -405.348915) (xy 3.240632 -405.333105)
			(xy 3.116729 -405.30947) (xy 2.994556 -405.278101) (xy 2.874593 -405.239123) (xy 2.757314 -405.192689)
			(xy 2.643182 -405.138982) (xy 2.532647 -405.078215) (xy 2.426147 -405.010628) (xy 2.3241 -404.936487)
			(xy 2.22691 -404.856084) (xy 2.13496 -404.769738) (xy 2.048614 -404.677788) (xy 1.968211 -404.580598)
			(xy 1.89407 -404.478551) (xy 1.826483 -404.372051) (xy 1.765716 -404.261516) (xy 1.712009 -404.147384)
			(xy 1.665575 -404.030105) (xy 1.626597 -403.910142) (xy 1.595228 -403.787969) (xy 1.571593 -403.664066)
			(xy 1.555783 -403.538924) (xy 1.547863 -403.413036) (xy 1.016 -403.413036) (xy 1.016 -404.690326)
			(xy 1.047496 -404.77313) (xy 1.060196 -404.788878) (xy 1.077936 -404.811646) (xy 1.107068 -404.861472)
			(xy 1.128365 -404.915116) (xy 1.141341 -404.971356) (xy 1.145699 -405.028908) (xy 1.141341 -405.086461)
			(xy 1.128366 -405.142701) (xy 1.10707 -405.196345) (xy 1.077938 -405.246171) (xy 1.060196 -405.268938)
			(xy 1.047496 -405.284686) (xy 1.016 -405.36749) (xy 1.016 -406.96007) (xy 39.818063 -406.96007) (xy 39.82207 -406.844046)
			(xy 39.834072 -406.728574) (xy 39.854012 -406.614206) (xy 39.881795 -406.501486) (xy 39.917289 -406.390952)
			(xy 39.960324 -406.283129) (xy 40.010695 -406.178532) (xy 40.068162 -406.07766) (xy 40.132452 -405.980993)
			(xy 40.203257 -405.888992) (xy 40.280241 -405.802095) (xy 40.363037 -405.720716) (xy 40.45125 -405.645243)
			(xy 40.54446 -405.576036) (xy 40.642223 -405.513424) (xy 40.744072 -405.457707) (xy 40.849522 -405.409149)
			(xy 40.958071 -405.367981) (xy 41.069202 -405.334401) (xy 41.182385 -405.308568) (xy 41.29708 -405.290605)
			(xy 41.412742 -405.280597) (xy 41.528818 -405.278594) (xy 41.644756 -405.284603) (xy 41.760003 -405.298596)
			(xy 41.874009 -405.320507) (xy 41.986233 -405.350232) (xy 42.096139 -405.387628) (xy 42.203202 -405.432517)
			(xy 42.306914 -405.484686) (xy 42.406779 -405.543886) (xy 42.502322 -405.609835) (xy 42.593088 -405.682218)
			(xy 42.678643 -405.760691) (xy 42.758581 -405.844879) (xy 42.83252 -405.934381) (xy 42.900108 -406.028772)
			(xy 42.961022 -406.1276) (xy 43.014974 -406.230396) (xy 43.061704 -406.336669) (xy 43.100992 -406.445913)
			(xy 43.132649 -406.557606) (xy 43.156525 -406.671218) (xy 43.172506 -406.786206) (xy 43.180515 -406.902023)
			(xy 43.181016 -406.96007) (xy 43.180515 -407.018117) (xy 43.172506 -407.133934) (xy 43.156525 -407.248922)
			(xy 43.132649 -407.362534) (xy 43.100992 -407.474227) (xy 43.061704 -407.583471) (xy 43.014974 -407.689744)
			(xy 42.961022 -407.79254) (xy 42.900108 -407.891368) (xy 42.83252 -407.985759) (xy 42.758581 -408.075261)
			(xy 42.678643 -408.159449) (xy 42.593088 -408.237922) (xy 42.502604 -408.31008) (xy 93.154506 -408.31008)
			(xy 93.158522 -408.19381) (xy 93.170549 -408.078095) (xy 93.190531 -407.963485) (xy 93.218373 -407.850526)
			(xy 93.253942 -407.739758) (xy 93.297068 -407.631707) (xy 93.347545 -407.526889) (xy 93.405134 -407.425804)
			(xy 93.46956 -407.328932) (xy 93.540515 -407.236736) (xy 93.617662 -407.149655) (xy 93.700633 -407.068104)
			(xy 93.789033 -406.992472) (xy 93.88244 -406.923118) (xy 93.980409 -406.860375) (xy 94.082473 -406.804539)
			(xy 94.188147 -406.755878) (xy 94.296926 -406.714624) (xy 94.408291 -406.680973) (xy 94.521714 -406.655085)
			(xy 94.636651 -406.637084) (xy 94.752557 -406.627055) (xy 94.868879 -406.625047) (xy 94.985062 -406.631069)
			(xy 95.100553 -406.645092) (xy 95.214801 -406.66705) (xy 95.327262 -406.696837) (xy 95.4374 -406.734312)
			(xy 95.54469 -406.779297) (xy 95.648621 -406.831576) (xy 95.748697 -406.890901) (xy 95.844443 -406.956989)
			(xy 95.9354 -407.029525) (xy 96.021136 -407.108164) (xy 96.101243 -407.19253) (xy 96.175339 -407.282222)
			(xy 96.243069 -407.376812) (xy 96.304113 -407.47585) (xy 96.358178 -407.578863) (xy 96.405008 -407.68536)
			(xy 96.444379 -407.794835) (xy 96.476103 -407.906765) (xy 96.500029 -408.020617) (xy 96.516043 -408.135849)
			(xy 96.52407 -408.251911) (xy 96.524572 -408.31008) (xy 96.52407 -408.368249) (xy 96.516043 -408.484311)
			(xy 96.500029 -408.599543) (xy 96.476103 -408.713395) (xy 96.444379 -408.825325) (xy 96.405008 -408.9348)
			(xy 96.358178 -409.041297) (xy 96.304113 -409.14431) (xy 96.243069 -409.243348) (xy 96.175339 -409.337938)
			(xy 96.101243 -409.42763) (xy 96.021136 -409.511996) (xy 95.9354 -409.590635) (xy 95.844443 -409.663171)
			(xy 95.748697 -409.729259) (xy 95.648621 -409.788584) (xy 95.54469 -409.840863) (xy 95.4374 -409.885848)
			(xy 95.327262 -409.923323) (xy 95.214801 -409.95311) (xy 95.100553 -409.975068) (xy 94.985062 -409.989091)
			(xy 94.868879 -409.995113) (xy 94.752557 -409.993105) (xy 94.636651 -409.983076) (xy 94.521714 -409.965075)
			(xy 94.408291 -409.939187) (xy 94.296926 -409.905536) (xy 94.188147 -409.864282) (xy 94.082473 -409.815621)
			(xy 93.980409 -409.759785) (xy 93.88244 -409.697042) (xy 93.789033 -409.627688) (xy 93.700633 -409.552056)
			(xy 93.617662 -409.470505) (xy 93.540515 -409.383424) (xy 93.46956 -409.291228) (xy 93.405134 -409.194356)
			(xy 93.347545 -409.093271) (xy 93.297068 -408.988453) (xy 93.253942 -408.880402) (xy 93.218373 -408.769634)
			(xy 93.190531 -408.656675) (xy 93.170549 -408.542065) (xy 93.158522 -408.42635) (xy 93.154506 -408.31008)
			(xy 42.502604 -408.31008) (xy 42.502322 -408.310305) (xy 42.406779 -408.376254) (xy 42.306914 -408.435454)
			(xy 42.203202 -408.487623) (xy 42.096139 -408.532512) (xy 41.986233 -408.569908) (xy 41.874009 -408.599633)
			(xy 41.760003 -408.621544) (xy 41.644756 -408.635537) (xy 41.528818 -408.641546) (xy 41.412742 -408.639543)
			(xy 41.29708 -408.629535) (xy 41.182385 -408.611572) (xy 41.069202 -408.585739) (xy 40.958071 -408.552159)
			(xy 40.849522 -408.510991) (xy 40.744072 -408.462433) (xy 40.642223 -408.406716) (xy 40.54446 -408.344104)
			(xy 40.45125 -408.274897) (xy 40.363037 -408.199424) (xy 40.280241 -408.118045) (xy 40.203257 -408.031148)
			(xy 40.132452 -407.939147) (xy 40.068162 -407.84248) (xy 40.010695 -407.741608) (xy 39.960324 -407.637011)
			(xy 39.917289 -407.529188) (xy 39.881795 -407.418654) (xy 39.854012 -407.305934) (xy 39.834072 -407.191566)
			(xy 39.82207 -407.076094) (xy 39.818063 -406.96007) (xy 1.016 -406.96007) (xy 1.016 -408.641804)
			(xy 1.048004 -408.725116) (xy 1.060704 -408.741118) (xy 1.061212 -408.741626) (xy 1.079005 -408.764403)
			(xy 1.10823 -408.814266) (xy 1.129596 -408.867968) (xy 1.142615 -408.924279) (xy 1.146988 -408.98191)
			(xy 1.142615 -409.039541) (xy 1.129596 -409.095852) (xy 1.10823 -409.149554) (xy 1.079005 -409.199417)
			(xy 1.061212 -409.222194) (xy 1.060704 -409.222702) (xy 1.048004 -409.238704) (xy 1.016 -409.322016)
			(xy 1.016 -418.771578) (xy 1.047496 -418.854382) (xy 1.059942 -418.869876) (xy 1.077482 -418.89257)
			(xy 1.106268 -418.942179) (xy 1.127305 -418.995537) (xy 1.14012 -419.051442) (xy 1.144423 -419.108636)
			(xy 1.14012 -419.16583) (xy 1.127305 -419.221735) (xy 1.106268 -419.275093) (xy 1.077482 -419.324702)
			(xy 1.059942 -419.347396) (xy 1.047496 -419.36289) (xy 1.016 -419.445694) (xy 1.016 -420.06012) (xy 86.877404 -420.06012)
			(xy 86.881424 -419.869469) (xy 86.893478 -419.679156) (xy 86.913544 -419.489521) (xy 86.941587 -419.3009)
			(xy 86.977556 -419.11363) (xy 87.021388 -418.928042) (xy 87.073005 -418.744467) (xy 87.132315 -418.563231)
			(xy 87.199213 -418.384656) (xy 87.273579 -418.209061) (xy 87.355281 -418.036756) (xy 87.444175 -417.868049)
			(xy 87.540101 -417.703239) (xy 87.64289 -417.54262) (xy 87.752359 -417.386477) (xy 87.868313 -417.235088)
			(xy 87.990547 -417.088721) (xy 88.118841 -416.947637) (xy 88.252969 -416.812088) (xy 88.392693 -416.682313)
			(xy 88.537763 -416.558543) (xy 88.687921 -416.441) (xy 88.842902 -416.329891) (xy 89.002429 -416.225414)
			(xy 89.166218 -416.127755) (xy 89.333978 -416.037088) (xy 89.505412 -415.953574) (xy 89.680214 -415.877361)
			(xy 89.858073 -415.808585) (xy 90.038674 -415.747367) (xy 90.221694 -415.693818) (xy 90.40681 -415.648032)
			(xy 90.593691 -415.61009) (xy 90.782006 -415.580061) (xy 90.971419 -415.557996) (xy 91.161593 -415.543937)
			(xy 91.352192 -415.537907) (xy 91.542875 -415.539917) (xy 91.733304 -415.549964) (xy 91.92314 -415.56803)
			(xy 92.112046 -415.594083) (xy 92.299685 -415.628076) (xy 92.485725 -415.669949) (xy 92.669834 -415.719628)
			(xy 92.851685 -415.777024) (xy 93.030955 -415.842035) (xy 93.207325 -415.914546) (xy 93.380481 -415.994427)
			(xy 93.550116 -416.081537) (xy 93.715928 -416.175721) (xy 93.877622 -416.276812) (xy 94.03491 -416.384628)
			(xy 94.187513 -416.49898) (xy 94.335161 -416.619663) (xy 94.477589 -416.746464) (xy 94.614545 -416.879155)
			(xy 94.745786 -417.017503) (xy 94.871078 -417.16126) (xy 94.990198 -417.310171) (xy 95.102934 -417.463972)
			(xy 95.209087 -417.622388) (xy 95.308467 -417.785139) (xy 95.400897 -417.951934) (xy 95.486214 -418.122478)
			(xy 95.564266 -418.296466) (xy 95.634913 -418.473591) (xy 95.698031 -418.653536) (xy 95.753507 -418.835982)
			(xy 95.801242 -419.020605) (xy 95.841152 -419.207075) (xy 95.873165 -419.395063) (xy 95.897225 -419.584233)
			(xy 95.913288 -419.774249) (xy 95.921327 -419.964773) (xy 95.92183 -420.06012) (xy 95.921327 -420.155467)
			(xy 95.913288 -420.345991) (xy 95.897225 -420.536007) (xy 95.873165 -420.725177) (xy 95.841152 -420.913165)
			(xy 95.801242 -421.099635) (xy 95.753507 -421.284258) (xy 95.698031 -421.466704) (xy 95.634913 -421.646649)
			(xy 95.564266 -421.823774) (xy 95.486214 -421.997762) (xy 95.400897 -422.168306) (xy 95.308467 -422.335101)
			(xy 95.209087 -422.497852) (xy 95.102934 -422.656268) (xy 94.990198 -422.810069) (xy 94.871078 -422.95898)
			(xy 94.745786 -423.102737) (xy 94.614545 -423.241085) (xy 94.477589 -423.373776) (xy 94.335161 -423.500577)
			(xy 94.187513 -423.62126) (xy 94.03491 -423.735612) (xy 93.877622 -423.843428) (xy 93.715928 -423.944519)
			(xy 93.550116 -424.038703) (xy 93.380481 -424.125813) (xy 93.207325 -424.205694) (xy 93.030955 -424.278205)
			(xy 92.851685 -424.343216) (xy 92.669834 -424.400612) (xy 92.485725 -424.450291) (xy 92.299685 -424.492164)
			(xy 92.112046 -424.526157) (xy 91.92314 -424.55221) (xy 91.733304 -424.570276) (xy 91.542875 -424.580323)
			(xy 91.352192 -424.582333) (xy 91.161593 -424.576303) (xy 90.971419 -424.562244) (xy 90.782006 -424.540179)
			(xy 90.593691 -424.51015) (xy 90.40681 -424.472208) (xy 90.221694 -424.426422) (xy 90.038674 -424.372873)
			(xy 89.858073 -424.311655) (xy 89.680214 -424.242879) (xy 89.505412 -424.166666) (xy 89.333978 -424.083152)
			(xy 89.166218 -423.992485) (xy 89.002429 -423.894826) (xy 88.842902 -423.790349) (xy 88.687921 -423.67924)
			(xy 88.537763 -423.561697) (xy 88.392693 -423.437927) (xy 88.252969 -423.308152) (xy 88.118841 -423.172603)
			(xy 87.990547 -423.031519) (xy 87.868313 -422.885152) (xy 87.752359 -422.733763) (xy 87.64289 -422.57762)
			(xy 87.540101 -422.417001) (xy 87.444175 -422.252191) (xy 87.355281 -422.083484) (xy 87.273579 -421.911179)
			(xy 87.199213 -421.735584) (xy 87.132315 -421.557009) (xy 87.073005 -421.375773) (xy 87.021388 -421.192198)
			(xy 86.977556 -421.00661) (xy 86.941587 -420.81934) (xy 86.913544 -420.630719) (xy 86.893478 -420.441084)
			(xy 86.881424 -420.250771) (xy 86.877404 -420.06012) (xy 1.016 -420.06012) (xy 1.016 -430.149762)
			(xy 72.857112 -430.149762) (xy 72.861127 -429.94658) (xy 72.873166 -429.743715) (xy 72.89321 -429.541485)
			(xy 72.921228 -429.340204) (xy 72.957176 -429.140187) (xy 73.000998 -428.941746) (xy 73.052625 -428.745192)
			(xy 73.111977 -428.550831) (xy 73.178962 -428.358966) (xy 73.253474 -428.169897) (xy 73.335397 -427.98392)
			(xy 73.424604 -427.801324) (xy 73.520955 -427.622395) (xy 73.624299 -427.447413) (xy 73.734476 -427.27665)
			(xy 73.851313 -427.110372) (xy 73.974628 -426.948841) (xy 74.104228 -426.792307) (xy 74.239911 -426.641016)
			(xy 74.381466 -426.495203) (xy 74.52867 -426.355096) (xy 74.681294 -426.220914) (xy 74.839101 -426.092866)
			(xy 75.001843 -425.971153) (xy 75.169266 -425.855965) (xy 75.341109 -425.74748) (xy 75.517104 -425.645869)
			(xy 75.696976 -425.551291) (xy 75.880444 -425.463892) (xy 76.067222 -425.38381) (xy 76.257018 -425.31117)
			(xy 76.449535 -425.246084) (xy 76.644473 -425.188655) (xy 76.841528 -425.138972) (xy 77.040392 -425.097112)
			(xy 77.240754 -425.063142) (xy 77.442302 -425.037114) (xy 77.644721 -425.019069) (xy 77.847694 -425.009035)
			(xy 78.050906 -425.007027) (xy 78.254038 -425.013049) (xy 78.456774 -425.027092) (xy 78.658797 -425.049133)
			(xy 78.859791 -425.079138) (xy 79.059443 -425.11706) (xy 79.257441 -425.16284) (xy 79.453476 -425.216406)
			(xy 79.647241 -425.277676) (xy 79.838435 -425.346552) (xy 80.026758 -425.422929) (xy 80.211917 -425.506685)
			(xy 80.393623 -425.597692) (xy 80.571591 -425.695805) (xy 80.745544 -425.800874) (xy 80.915211 -425.912732)
			(xy 81.080325 -426.031206) (xy 81.240631 -426.156111) (xy 81.395877 -426.287251) (xy 81.54582 -426.424422)
			(xy 81.690228 -426.56741) (xy 81.828873 -426.715991) (xy 81.961541 -426.869934) (xy 82.088023 -427.028997)
			(xy 82.208123 -427.192934) (xy 82.321652 -427.361487) (xy 82.428433 -427.534394) (xy 82.5283 -427.711384)
			(xy 82.621097 -427.892181) (xy 82.706679 -428.076504) (xy 82.784912 -428.264063) (xy 82.855674 -428.454567)
			(xy 82.918855 -428.647718) (xy 82.974355 -428.843214) (xy 83.022089 -429.04075) (xy 83.061982 -429.240018)
			(xy 83.093971 -429.440706) (xy 83.118007 -429.642501) (xy 83.134052 -429.845088) (xy 83.14208 -430.048151)
			(xy 83.142582 -430.149762) (xy 83.14208 -430.251373) (xy 83.134052 -430.454436) (xy 83.118007 -430.657023)
			(xy 83.093971 -430.858818) (xy 83.061982 -431.059506) (xy 83.022089 -431.258774) (xy 82.974355 -431.45631)
			(xy 82.918855 -431.651806) (xy 82.855674 -431.844957) (xy 82.784912 -432.035461) (xy 82.706679 -432.22302)
			(xy 82.621097 -432.407343) (xy 82.5283 -432.58814) (xy 82.428433 -432.76513) (xy 82.321652 -432.938037)
			(xy 82.208123 -433.10659) (xy 82.088023 -433.270527) (xy 81.961541 -433.42959) (xy 81.828873 -433.583533)
			(xy 81.690228 -433.732114) (xy 81.54582 -433.875102) (xy 81.395877 -434.012273) (xy 81.240631 -434.143413)
			(xy 81.080325 -434.268318) (xy 80.915211 -434.386792) (xy 80.745544 -434.49865) (xy 80.571591 -434.603719)
			(xy 80.393623 -434.701832) (xy 80.211917 -434.792839) (xy 80.026758 -434.876595) (xy 79.838435 -434.952972)
			(xy 79.647241 -435.021848) (xy 79.453476 -435.083118) (xy 79.257441 -435.136684) (xy 79.059443 -435.182464)
			(xy 78.859791 -435.220386) (xy 78.658797 -435.250391) (xy 78.456774 -435.272432) (xy 78.254038 -435.286475)
			(xy 78.050906 -435.292497) (xy 77.847694 -435.290489) (xy 77.644721 -435.280455) (xy 77.442302 -435.26241)
			(xy 77.240754 -435.236382) (xy 77.040392 -435.202412) (xy 76.841528 -435.160552) (xy 76.644473 -435.110869)
			(xy 76.449535 -435.05344) (xy 76.257018 -434.988354) (xy 76.067222 -434.915714) (xy 75.880444 -434.835632)
			(xy 75.696976 -434.748233) (xy 75.517104 -434.653655) (xy 75.341109 -434.552044) (xy 75.169266 -434.443559)
			(xy 75.001843 -434.328371) (xy 74.839101 -434.206658) (xy 74.681294 -434.07861) (xy 74.52867 -433.944428)
			(xy 74.381466 -433.804321) (xy 74.239911 -433.658508) (xy 74.104228 -433.507217) (xy 73.974628 -433.350683)
			(xy 73.851313 -433.189152) (xy 73.734476 -433.022874) (xy 73.624299 -432.852111) (xy 73.520955 -432.677129)
			(xy 73.424604 -432.4982) (xy 73.335397 -432.315604) (xy 73.253474 -432.129627) (xy 73.178962 -431.940558)
			(xy 73.111977 -431.748693) (xy 73.052625 -431.554332) (xy 73.000998 -431.357778) (xy 72.957176 -431.159337)
			(xy 72.921228 -430.95932) (xy 72.89321 -430.758039) (xy 72.873166 -430.555809) (xy 72.861127 -430.352944)
			(xy 72.857112 -430.149762) (xy 1.016 -430.149762) (xy 1.016 -431.471578) (xy 1.047496 -431.554382)
			(xy 1.059942 -431.569876) (xy 1.077482 -431.59257) (xy 1.106268 -431.642179) (xy 1.127305 -431.695537)
			(xy 1.14012 -431.751442) (xy 1.144423 -431.808636) (xy 1.14012 -431.86583) (xy 1.127305 -431.921735)
			(xy 1.106268 -431.975093) (xy 1.077482 -432.024702) (xy 1.059942 -432.047396) (xy 1.047496 -432.06289)
			(xy 1.016 -432.145694) (xy 1.016 -444.171578) (xy 1.047496 -444.254382) (xy 1.059942 -444.269876)
			(xy 1.077482 -444.29257) (xy 1.106268 -444.342179) (xy 1.127305 -444.395537) (xy 1.14012 -444.451442)
			(xy 1.144423 -444.508636) (xy 1.14012 -444.56583) (xy 1.127305 -444.621735) (xy 1.106268 -444.675093)
			(xy 1.077482 -444.724702) (xy 1.059942 -444.747396) (xy 1.047496 -444.76289) (xy 1.016 -444.845694)
			(xy 1.016 -451.41007) (xy 39.818063 -451.41007) (xy 39.82207 -451.294046) (xy 39.834072 -451.178574)
			(xy 39.854012 -451.064206) (xy 39.881795 -450.951486) (xy 39.917289 -450.840952) (xy 39.960324 -450.733129)
			(xy 40.010695 -450.628532) (xy 40.068162 -450.52766) (xy 40.132452 -450.430993) (xy 40.203257 -450.338992)
			(xy 40.280241 -450.252095) (xy 40.363037 -450.170716) (xy 40.45125 -450.095243) (xy 40.54446 -450.026036)
			(xy 40.642223 -449.963424) (xy 40.744072 -449.907707) (xy 40.849522 -449.859149) (xy 40.958071 -449.817981)
			(xy 41.069202 -449.784401) (xy 41.182385 -449.758568) (xy 41.29708 -449.740605) (xy 41.412742 -449.730597)
			(xy 41.528818 -449.728594) (xy 41.644756 -449.734603) (xy 41.760003 -449.748596) (xy 41.874009 -449.770507)
			(xy 41.986233 -449.800232) (xy 42.096139 -449.837628) (xy 42.203202 -449.882517) (xy 42.306914 -449.934686)
			(xy 42.406779 -449.993886) (xy 42.502322 -450.059835) (xy 42.593088 -450.132218) (xy 42.678643 -450.210691)
			(xy 42.758581 -450.294879) (xy 42.83252 -450.384381) (xy 42.900108 -450.478772) (xy 42.961022 -450.5776)
			(xy 43.014974 -450.680396) (xy 43.061704 -450.786669) (xy 43.100992 -450.895913) (xy 43.132649 -451.007606)
			(xy 43.156525 -451.121218) (xy 43.172506 -451.236206) (xy 43.180515 -451.352023) (xy 43.181016 -451.41007)
			(xy 43.180515 -451.468117) (xy 43.172506 -451.583934) (xy 43.156525 -451.698922) (xy 43.132649 -451.812534)
			(xy 43.100992 -451.924227) (xy 43.061704 -452.033471) (xy 43.014974 -452.139744) (xy 42.961022 -452.24254)
			(xy 42.900108 -452.341368) (xy 42.83252 -452.435759) (xy 42.758581 -452.525261) (xy 42.678643 -452.609449)
			(xy 42.593088 -452.687922) (xy 42.502604 -452.76008) (xy 93.154506 -452.76008) (xy 93.158522 -452.64381)
			(xy 93.170549 -452.528095) (xy 93.190531 -452.413485) (xy 93.218373 -452.300526) (xy 93.253942 -452.189758)
			(xy 93.297068 -452.081707) (xy 93.347545 -451.976889) (xy 93.405134 -451.875804) (xy 93.46956 -451.778932)
			(xy 93.540515 -451.686736) (xy 93.617662 -451.599655) (xy 93.700633 -451.518104) (xy 93.789033 -451.442472)
			(xy 93.88244 -451.373118) (xy 93.980409 -451.310375) (xy 94.082473 -451.254539) (xy 94.188147 -451.205878)
			(xy 94.296926 -451.164624) (xy 94.408291 -451.130973) (xy 94.521714 -451.105085) (xy 94.636651 -451.087084)
			(xy 94.752557 -451.077055) (xy 94.868879 -451.075047) (xy 94.985062 -451.081069) (xy 95.100553 -451.095092)
			(xy 95.214801 -451.11705) (xy 95.327262 -451.146837) (xy 95.4374 -451.184312) (xy 95.54469 -451.229297)
			(xy 95.648621 -451.281576) (xy 95.748697 -451.340901) (xy 95.844443 -451.406989) (xy 95.9354 -451.479525)
			(xy 96.021136 -451.558164) (xy 96.101243 -451.64253) (xy 96.175339 -451.732222) (xy 96.243069 -451.826812)
			(xy 96.304113 -451.92585) (xy 96.358178 -452.028863) (xy 96.405008 -452.13536) (xy 96.444379 -452.244835)
			(xy 96.476103 -452.356765) (xy 96.500029 -452.470617) (xy 96.516043 -452.585849) (xy 96.52407 -452.701911)
			(xy 96.524572 -452.76008) (xy 96.52407 -452.818249) (xy 96.516043 -452.934311) (xy 96.500029 -453.049543)
			(xy 96.476103 -453.163395) (xy 96.444379 -453.275325) (xy 96.405008 -453.3848) (xy 96.358178 -453.491297)
			(xy 96.304113 -453.59431) (xy 96.243069 -453.693348) (xy 96.175339 -453.787938) (xy 96.101243 -453.87763)
			(xy 96.021136 -453.961996) (xy 95.9354 -454.040635) (xy 95.844443 -454.113171) (xy 95.748697 -454.179259)
			(xy 95.648621 -454.238584) (xy 95.54469 -454.290863) (xy 95.4374 -454.335848) (xy 95.327262 -454.373323)
			(xy 95.214801 -454.40311) (xy 95.100553 -454.425068) (xy 94.985062 -454.439091) (xy 94.868879 -454.445113)
			(xy 94.752557 -454.443105) (xy 94.636651 -454.433076) (xy 94.521714 -454.415075) (xy 94.408291 -454.389187)
			(xy 94.296926 -454.355536) (xy 94.188147 -454.314282) (xy 94.082473 -454.265621) (xy 93.980409 -454.209785)
			(xy 93.88244 -454.147042) (xy 93.789033 -454.077688) (xy 93.700633 -454.002056) (xy 93.617662 -453.920505)
			(xy 93.540515 -453.833424) (xy 93.46956 -453.741228) (xy 93.405134 -453.644356) (xy 93.347545 -453.543271)
			(xy 93.297068 -453.438453) (xy 93.253942 -453.330402) (xy 93.218373 -453.219634) (xy 93.190531 -453.106675)
			(xy 93.170549 -452.992065) (xy 93.158522 -452.87635) (xy 93.154506 -452.76008) (xy 42.502604 -452.76008)
			(xy 42.502322 -452.760305) (xy 42.406779 -452.826254) (xy 42.306914 -452.885454) (xy 42.203202 -452.937623)
			(xy 42.096139 -452.982512) (xy 41.986233 -453.019908) (xy 41.874009 -453.049633) (xy 41.760003 -453.071544)
			(xy 41.644756 -453.085537) (xy 41.528818 -453.091546) (xy 41.412742 -453.089543) (xy 41.29708 -453.079535)
			(xy 41.182385 -453.061572) (xy 41.069202 -453.035739) (xy 40.958071 -453.002159) (xy 40.849522 -452.960991)
			(xy 40.744072 -452.912433) (xy 40.642223 -452.856716) (xy 40.54446 -452.794104) (xy 40.45125 -452.724897)
			(xy 40.363037 -452.649424) (xy 40.280241 -452.568045) (xy 40.203257 -452.481148) (xy 40.132452 -452.389147)
			(xy 40.068162 -452.29248) (xy 40.010695 -452.191608) (xy 39.960324 -452.087011) (xy 39.917289 -451.979188)
			(xy 39.881795 -451.868654) (xy 39.854012 -451.755934) (xy 39.834072 -451.641566) (xy 39.82207 -451.526094)
			(xy 39.818063 -451.41007) (xy 1.016 -451.41007) (xy 1.016 -456.871578) (xy 1.047496 -456.954382)
			(xy 1.059942 -456.969876) (xy 1.077482 -456.99257) (xy 1.106268 -457.042179) (xy 1.127305 -457.095537)
			(xy 1.14012 -457.151442) (xy 1.144423 -457.208636) (xy 1.14012 -457.26583) (xy 1.127305 -457.321735)
			(xy 1.106268 -457.375093) (xy 1.077482 -457.424702) (xy 1.059942 -457.447396) (xy 1.047496 -457.46289)
			(xy 1.016 -457.545694) (xy 1.016 -464.509866) (xy 86.877404 -464.509866) (xy 86.881424 -464.319215)
			(xy 86.893478 -464.128902) (xy 86.913544 -463.939267) (xy 86.941587 -463.750646) (xy 86.977556 -463.563376)
			(xy 87.021388 -463.377788) (xy 87.073005 -463.194213) (xy 87.132315 -463.012977) (xy 87.199213 -462.834402)
			(xy 87.273579 -462.658807) (xy 87.355281 -462.486502) (xy 87.444175 -462.317795) (xy 87.540101 -462.152985)
			(xy 87.64289 -461.992366) (xy 87.752359 -461.836223) (xy 87.868313 -461.684834) (xy 87.990547 -461.538467)
			(xy 88.118841 -461.397383) (xy 88.252969 -461.261834) (xy 88.392693 -461.132059) (xy 88.537763 -461.008289)
			(xy 88.687921 -460.890746) (xy 88.842902 -460.779637) (xy 89.002429 -460.67516) (xy 89.166218 -460.577501)
			(xy 89.333978 -460.486834) (xy 89.505412 -460.40332) (xy 89.680214 -460.327107) (xy 89.858073 -460.258331)
			(xy 90.038674 -460.197113) (xy 90.221694 -460.143564) (xy 90.40681 -460.097778) (xy 90.593691 -460.059836)
			(xy 90.782006 -460.029807) (xy 90.971419 -460.007742) (xy 91.161593 -459.993683) (xy 91.352192 -459.987653)
			(xy 91.542875 -459.989663) (xy 91.733304 -459.99971) (xy 91.92314 -460.017776) (xy 92.112046 -460.043829)
			(xy 92.299685 -460.077822) (xy 92.485725 -460.119695) (xy 92.669834 -460.169374) (xy 92.851685 -460.22677)
			(xy 93.030955 -460.291781) (xy 93.207325 -460.364292) (xy 93.380481 -460.444173) (xy 93.550116 -460.531283)
			(xy 93.715928 -460.625467) (xy 93.877622 -460.726558) (xy 94.03491 -460.834374) (xy 94.187513 -460.948726)
			(xy 94.335161 -461.069409) (xy 94.477589 -461.19621) (xy 94.614545 -461.328901) (xy 94.745786 -461.467249)
			(xy 94.871078 -461.611006) (xy 94.990198 -461.759917) (xy 95.102934 -461.913718) (xy 95.209087 -462.072134)
			(xy 95.308467 -462.234885) (xy 95.400897 -462.40168) (xy 95.486214 -462.572224) (xy 95.564266 -462.746212)
			(xy 95.634913 -462.923337) (xy 95.698031 -463.103282) (xy 95.753507 -463.285728) (xy 95.801242 -463.470351)
			(xy 95.841152 -463.656821) (xy 95.873165 -463.844809) (xy 95.897225 -464.033979) (xy 95.913288 -464.223995)
			(xy 95.921327 -464.414519) (xy 95.92183 -464.509866) (xy 95.921327 -464.605213) (xy 95.913288 -464.795737)
			(xy 95.897225 -464.985753) (xy 95.873165 -465.174923) (xy 95.841152 -465.362911) (xy 95.801242 -465.549381)
			(xy 95.753507 -465.734004) (xy 95.698031 -465.91645) (xy 95.634913 -466.096395) (xy 95.564266 -466.27352)
			(xy 95.486214 -466.447508) (xy 95.400897 -466.618052) (xy 95.308467 -466.784847) (xy 95.209087 -466.947598)
			(xy 95.102934 -467.106014) (xy 94.990198 -467.259815) (xy 94.871078 -467.408726) (xy 94.745786 -467.552483)
			(xy 94.614545 -467.690831) (xy 94.477589 -467.823522) (xy 94.335161 -467.950323) (xy 94.187513 -468.071006)
			(xy 94.03491 -468.185358) (xy 93.877622 -468.293174) (xy 93.715928 -468.394265) (xy 93.550116 -468.488449)
			(xy 93.380481 -468.575559) (xy 93.207325 -468.65544) (xy 93.030955 -468.727951) (xy 92.851685 -468.792962)
			(xy 92.669834 -468.850358) (xy 92.485725 -468.900037) (xy 92.299685 -468.94191) (xy 92.112046 -468.975903)
			(xy 91.92314 -469.001956) (xy 91.733304 -469.020022) (xy 91.542875 -469.030069) (xy 91.352192 -469.032079)
			(xy 91.161593 -469.026049) (xy 90.971419 -469.01199) (xy 90.782006 -468.989925) (xy 90.593691 -468.959896)
			(xy 90.40681 -468.921954) (xy 90.221694 -468.876168) (xy 90.038674 -468.822619) (xy 89.858073 -468.761401)
			(xy 89.680214 -468.692625) (xy 89.505412 -468.616412) (xy 89.333978 -468.532898) (xy 89.166218 -468.442231)
			(xy 89.002429 -468.344572) (xy 88.842902 -468.240095) (xy 88.687921 -468.128986) (xy 88.537763 -468.011443)
			(xy 88.392693 -467.887673) (xy 88.252969 -467.757898) (xy 88.118841 -467.622349) (xy 87.990547 -467.481265)
			(xy 87.868313 -467.334898) (xy 87.752359 -467.183509) (xy 87.64289 -467.027366) (xy 87.540101 -466.866747)
			(xy 87.444175 -466.701937) (xy 87.355281 -466.53323) (xy 87.273579 -466.360925) (xy 87.199213 -466.18533)
			(xy 87.132315 -466.006755) (xy 87.073005 -465.825519) (xy 87.021388 -465.641944) (xy 86.977556 -465.456356)
			(xy 86.941587 -465.269086) (xy 86.913544 -465.080465) (xy 86.893478 -464.89083) (xy 86.881424 -464.700517)
			(xy 86.877404 -464.509866) (xy 1.016 -464.509866) (xy 1.016 -469.571578) (xy 1.047496 -469.654382)
			(xy 1.059942 -469.669876) (xy 1.077482 -469.69257) (xy 1.106268 -469.742179) (xy 1.127305 -469.795537)
			(xy 1.14012 -469.851442) (xy 1.144423 -469.908636) (xy 1.14012 -469.96583) (xy 1.127305 -470.021735)
			(xy 1.106268 -470.075093) (xy 1.077482 -470.124702) (xy 1.059942 -470.147396) (xy 1.047496 -470.16289)
			(xy 1.016 -470.245694) (xy 1.016 -473.69984) (xy 11.34441 -473.69984) (xy 11.348411 -473.494791)
			(xy 11.36041 -473.290054) (xy 11.380388 -473.085941) (xy 11.408314 -472.882762) (xy 11.444146 -472.680829)
			(xy 11.48783 -472.480446) (xy 11.539298 -472.281921) (xy 11.598473 -472.085555) (xy 11.665264 -471.891648)
			(xy 11.73957 -471.700494) (xy 11.821277 -471.512384) (xy 11.910262 -471.327606) (xy 12.006388 -471.14644)
			(xy 12.109509 -470.969163) (xy 12.219469 -470.796044) (xy 12.336099 -470.627347) (xy 12.459222 -470.463329)
			(xy 12.588651 -470.30424) (xy 12.724188 -470.150322) (xy 12.865627 -470.001808) (xy 13.012754 -469.858927)
			(xy 13.165342 -469.721894) (xy 13.323161 -469.59092) (xy 13.48597 -469.466202) (xy 13.653521 -469.347932)
			(xy 13.825559 -469.236288) (xy 14.001822 -469.131442) (xy 14.182041 -469.033553) (xy 14.365942 -468.94277)
			(xy 14.553246 -468.859232) (xy 14.743666 -468.783064) (xy 14.936912 -468.714384) (xy 15.132692 -468.653296)
			(xy 15.330705 -468.599894) (xy 15.530652 -468.554257) (xy 15.732226 -468.516457) (xy 15.935122 -468.486549)
			(xy 16.139031 -468.464581) (xy 16.343641 -468.450586) (xy 16.548641 -468.444584) (xy 16.75372 -468.446585)
			(xy 16.958564 -468.456585) (xy 17.162863 -468.474571) (xy 17.366304 -468.500513) (xy 17.568577 -468.534374)
			(xy 17.769376 -468.5761) (xy 17.968394 -468.625629) (xy 18.165328 -468.682885) (xy 18.359878 -468.747782)
			(xy 18.551748 -468.820219) (xy 18.740645 -468.900087) (xy 18.926283 -468.987265) (xy 19.108378 -469.081619)
			(xy 19.286653 -469.183006) (xy 19.460836 -469.291271) (xy 19.630663 -469.406249) (xy 19.795875 -469.527767)
			(xy 19.956219 -469.655637) (xy 20.111453 -469.789666) (xy 20.261339 -469.92965) (xy 20.405649 -470.075375)
			(xy 20.544163 -470.22662) (xy 20.676672 -470.383153) (xy 20.802972 -470.544738) (xy 20.922871 -470.711127)
			(xy 21.036188 -470.882067) (xy 21.142748 -471.057299) (xy 21.242391 -471.236554) (xy 21.334964 -471.419561)
			(xy 21.420326 -471.60604) (xy 21.498347 -471.795708) (xy 21.56891 -471.988276) (xy 21.631905 -472.18345)
			(xy 21.687237 -472.380933) (xy 21.734822 -472.580424) (xy 21.774587 -472.781621) (xy 21.806472 -472.984215)
			(xy 21.830429 -473.1879) (xy 21.84642 -473.392364) (xy 21.854422 -473.597296) (xy 21.854922 -473.69984)
			(xy 21.854422 -473.802384) (xy 21.84642 -474.007316) (xy 21.830429 -474.21178) (xy 21.806472 -474.415465)
			(xy 21.774587 -474.618059) (xy 21.734822 -474.819256) (xy 21.687237 -475.018747) (xy 21.631905 -475.21623)
			(xy 21.56891 -475.411404) (xy 21.498347 -475.603972) (xy 21.420326 -475.79364) (xy 21.334964 -475.980119)
			(xy 21.242391 -476.163126) (xy 21.142748 -476.342381) (xy 21.036188 -476.517613) (xy 20.922871 -476.688553)
			(xy 20.802972 -476.854942) (xy 20.676672 -477.016527) (xy 20.544163 -477.17306) (xy 20.405649 -477.324305)
			(xy 20.261339 -477.47003) (xy 20.111453 -477.610014) (xy 19.956219 -477.744043) (xy 19.795875 -477.871913)
			(xy 19.630663 -477.993431) (xy 19.460836 -478.108409) (xy 19.286653 -478.216674) (xy 19.108378 -478.318061)
			(xy 18.926283 -478.412415) (xy 18.740645 -478.499593) (xy 18.551748 -478.579461) (xy 18.359878 -478.651898)
			(xy 18.165328 -478.716795) (xy 17.968394 -478.774051) (xy 17.864503 -478.799906) (xy 74.3839 -478.799906)
			(xy 74.3839 -477.799908) (xy 74.384397 -477.715129) (xy 74.392344 -477.545758) (xy 74.408222 -477.376946)
			(xy 74.431995 -477.209063) (xy 74.46361 -477.04248) (xy 74.503 -476.877561) (xy 74.550075 -476.71467)
			(xy 74.604735 -476.554164) (xy 74.666857 -476.396397) (xy 74.736306 -476.241715) (xy 74.812929 -476.090458)
			(xy 74.896558 -475.942959) (xy 74.987008 -475.799542) (xy 75.084081 -475.660522) (xy 75.187564 -475.526205)
			(xy 75.297228 -475.396886) (xy 75.412834 -475.27285) (xy 75.534126 -475.154368) (xy 75.660839 -475.041702)
			(xy 75.792693 -474.935099) (xy 75.929399 -474.834794) (xy 76.070656 -474.741006) (xy 76.216154 -474.653943)
			(xy 76.365573 -474.573795) (xy 76.518585 -474.500739) (xy 76.674852 -474.434935) (xy 76.834032 -474.376528)
			(xy 76.995775 -474.325647) (xy 77.159725 -474.282402) (xy 77.325522 -474.24689) (xy 77.492801 -474.219188)
			(xy 77.661195 -474.199358) (xy 77.830333 -474.187442) (xy 77.999844 -474.183467) (xy 78.169355 -474.187442)
			(xy 78.338493 -474.199358) (xy 78.506887 -474.219188) (xy 78.674166 -474.24689) (xy 78.839963 -474.282402)
			(xy 79.003913 -474.325647) (xy 79.165656 -474.376528) (xy 79.324836 -474.434935) (xy 79.481103 -474.500739)
			(xy 79.634115 -474.573795) (xy 79.783534 -474.653943) (xy 79.929032 -474.741006) (xy 80.070289 -474.834794)
			(xy 80.206995 -474.935099) (xy 80.338849 -475.041702) (xy 80.465562 -475.154368) (xy 80.586854 -475.27285)
			(xy 80.70246 -475.396886) (xy 80.812124 -475.526205) (xy 80.915607 -475.660522) (xy 81.01268 -475.799542)
			(xy 81.10313 -475.942959) (xy 81.186759 -476.090458) (xy 81.263382 -476.241715) (xy 81.332831 -476.396397)
			(xy 81.394953 -476.554164) (xy 81.449613 -476.71467) (xy 81.496688 -476.877561) (xy 81.536078 -477.04248)
			(xy 81.567693 -477.209063) (xy 81.591466 -477.376946) (xy 81.607344 -477.545758) (xy 81.615291 -477.715129)
			(xy 81.615788 -477.799908) (xy 81.615788 -478.799906) (xy 81.615291 -478.884685) (xy 81.607344 -479.054056)
			(xy 81.591466 -479.222868) (xy 81.567693 -479.390751) (xy 81.536078 -479.557334) (xy 81.496688 -479.722253)
			(xy 81.449613 -479.885144) (xy 81.394953 -480.04565) (xy 81.332831 -480.203417) (xy 81.263382 -480.358099)
			(xy 81.186759 -480.509356) (xy 81.10313 -480.656855) (xy 81.01268 -480.800272) (xy 80.915607 -480.939292)
			(xy 80.812124 -481.073609) (xy 80.70246 -481.202928) (xy 80.586854 -481.326964) (xy 80.465562 -481.445446)
			(xy 80.338849 -481.558112) (xy 80.206995 -481.664715) (xy 80.070289 -481.76502) (xy 79.929032 -481.858808)
			(xy 79.783534 -481.945871) (xy 79.634115 -482.026019) (xy 79.481103 -482.099075) (xy 79.324836 -482.164879)
			(xy 79.165656 -482.223286) (xy 79.003913 -482.274167) (xy 78.839963 -482.317412) (xy 78.674166 -482.352924)
			(xy 78.506887 -482.380626) (xy 78.338493 -482.400456) (xy 78.169355 -482.412372) (xy 77.999844 -482.416347)
			(xy 77.830333 -482.412372) (xy 77.661195 -482.400456) (xy 77.492801 -482.380626) (xy 77.325522 -482.352924)
			(xy 77.159725 -482.317412) (xy 76.995775 -482.274167) (xy 76.834032 -482.223286) (xy 76.674852 -482.164879)
			(xy 76.518585 -482.099075) (xy 76.365573 -482.026019) (xy 76.216154 -481.945871) (xy 76.070656 -481.858808)
			(xy 75.929399 -481.76502) (xy 75.792693 -481.664715) (xy 75.660839 -481.558112) (xy 75.534126 -481.445446)
			(xy 75.412834 -481.326964) (xy 75.297228 -481.202928) (xy 75.187564 -481.073609) (xy 75.084081 -480.939292)
			(xy 74.987008 -480.800272) (xy 74.896558 -480.656855) (xy 74.812929 -480.509356) (xy 74.736306 -480.358099)
			(xy 74.666857 -480.203417) (xy 74.604735 -480.04565) (xy 74.550075 -479.885144) (xy 74.503 -479.722253)
			(xy 74.46361 -479.557334) (xy 74.431995 -479.390751) (xy 74.408222 -479.222868) (xy 74.392344 -479.054056)
			(xy 74.384397 -478.884685) (xy 74.3839 -478.799906) (xy 17.864503 -478.799906) (xy 17.769376 -478.82358)
			(xy 17.568577 -478.865306) (xy 17.366304 -478.899167) (xy 17.162863 -478.925109) (xy 16.958564 -478.943095)
			(xy 16.75372 -478.953095) (xy 16.548641 -478.955096) (xy 16.343641 -478.949094) (xy 16.139031 -478.935099)
			(xy 15.935122 -478.913131) (xy 15.732226 -478.883223) (xy 15.530652 -478.845423) (xy 15.330705 -478.799786)
			(xy 15.132692 -478.746384) (xy 14.936912 -478.685296) (xy 14.743666 -478.616616) (xy 14.553246 -478.540448)
			(xy 14.365942 -478.45691) (xy 14.182041 -478.366127) (xy 14.001822 -478.268238) (xy 13.825559 -478.163392)
			(xy 13.653521 -478.051748) (xy 13.48597 -477.933478) (xy 13.323161 -477.80876) (xy 13.165342 -477.677786)
			(xy 13.012754 -477.540753) (xy 12.865627 -477.397872) (xy 12.724188 -477.249358) (xy 12.588651 -477.09544)
			(xy 12.459222 -476.936351) (xy 12.336099 -476.772333) (xy 12.219469 -476.603636) (xy 12.109509 -476.430517)
			(xy 12.006388 -476.25324) (xy 11.910262 -476.072074) (xy 11.821277 -475.887296) (xy 11.73957 -475.699186)
			(xy 11.665264 -475.508032) (xy 11.598473 -475.314125) (xy 11.539298 -475.117759) (xy 11.48783 -474.919234)
			(xy 11.444146 -474.718851) (xy 11.408314 -474.516918) (xy 11.380388 -474.313739) (xy 11.36041 -474.109626)
			(xy 11.348411 -473.904889) (xy 11.34441 -473.69984) (xy 1.016 -473.69984) (xy 1.016 -482.271578)
			(xy 1.047496 -482.354382) (xy 1.059942 -482.369876) (xy 1.077482 -482.39257) (xy 1.106268 -482.442179)
			(xy 1.127305 -482.495537) (xy 1.14012 -482.551442) (xy 1.144423 -482.608636) (xy 1.14012 -482.66583)
			(xy 1.127305 -482.721735) (xy 1.106268 -482.775093) (xy 1.077482 -482.824702) (xy 1.059942 -482.847396)
			(xy 1.047496 -482.86289) (xy 1.016 -482.945694) (xy 1.016 -486.99547) (xy 1.016504 -487.01881) (xy 1.024982 -487.064714)
			(xy 1.041699 -487.108297) (xy 1.066094 -487.148095) (xy 1.097346 -487.182768) (xy 1.134405 -487.211152)
			(xy 1.176024 -487.232291) (xy 1.220803 -487.245475) (xy 1.267237 -487.250259) (xy 1.313763 -487.246484)
			(xy 1.358818 -487.234276) (xy 1.400886 -487.214045) (xy 1.438552 -487.186473) (xy 1.47055 -487.152486)
			(xy 1.483614 -487.133138) (xy 1.51897 -487.079202) (xy 1.595424 -486.975326) (xy 1.678157 -486.876378)
			(xy 1.766854 -486.782738) (xy 1.861173 -486.694764) (xy 1.960754 -486.612795) (xy 2.065216 -486.537142)
			(xy 2.174158 -486.468097) (xy 2.287162 -486.405924) (xy 2.403796 -486.350861) (xy 2.523614 -486.303119)
			(xy 2.646155 -486.26288) (xy 2.770951 -486.2303) (xy 2.897523 -486.205502) (xy 3.025387 -486.188583)
			(xy 3.154053 -486.179606) (xy 3.283028 -486.178606) (xy 3.411818 -486.185586) (xy 3.539929 -486.200521)
			(xy 3.66687 -486.223353) (xy 3.792157 -486.253994) (xy 3.915307 -486.292328) (xy 4.03585 -486.338206)
			(xy 4.153324 -486.391454) (xy 4.267279 -486.451868) (xy 4.377278 -486.519215) (xy 4.482901 -486.593239)
			(xy 4.583741 -486.673655) (xy 4.679413 -486.760155) (xy 4.769551 -486.852408) (xy 4.853809 -486.950061)
			(xy 4.931864 -487.05274) (xy 5.003418 -487.16005) (xy 5.068196 -487.271582) (xy 5.12595 -487.386907)
			(xy 5.176459 -487.505585) (xy 5.219529 -487.62716) (xy 5.254996 -487.751166) (xy 5.282723 -487.87713)
			(xy 5.302604 -488.004567) (xy 5.314563 -488.13299) (xy 5.318555 -488.261907) (xy 5.318555 -488.261914)
			(xy 12.580624 -488.261914) (xy 12.584655 -488.132348) (xy 12.596734 -488.003284) (xy 12.616813 -487.87522)
			(xy 12.644815 -487.748653) (xy 12.680632 -487.62407) (xy 12.724124 -487.501956) (xy 12.775124 -487.382782)
			(xy 12.833435 -487.267009) (xy 12.89883 -487.155085) (xy 12.971057 -487.047443) (xy 13.049837 -486.9445)
			(xy 13.134864 -486.846654) (xy 13.225809 -486.754282) (xy 13.322321 -486.667744) (xy 13.424027 -486.587373)
			(xy 13.530533 -486.513481) (xy 13.641426 -486.446353) (xy 13.756278 -486.386249) (xy 13.874645 -486.333402)
			(xy 13.996068 -486.288015) (xy 14.120078 -486.250266) (xy 14.246195 -486.220299) (xy 14.373931 -486.19823)
			(xy 14.502792 -486.184146) (xy 14.632279 -486.1781) (xy 14.761892 -486.180116) (xy 14.891128 -486.190186)
			(xy 15.019489 -486.208271) (xy 15.146477 -486.234301) (xy 15.271601 -486.268176) (xy 15.394377 -486.309764)
			(xy 15.51433 -486.358905) (xy 15.630995 -486.415408) (xy 15.743923 -486.479055) (xy 15.852675 -486.549599)
			(xy 15.956831 -486.626768) (xy 16.055988 -486.710263) (xy 16.149762 -486.799761) (xy 16.237791 -486.894916)
			(xy 16.319734 -486.995359) (xy 16.395273 -487.100702) (xy 16.464118 -487.210538) (xy 16.526001 -487.324442)
			(xy 16.580682 -487.441972) (xy 16.627952 -487.562675) (xy 16.667625 -487.686083) (xy 16.69955 -487.811719)
			(xy 16.723602 -487.939096) (xy 16.739689 -488.067722) (xy 16.747748 -488.1971) (xy 16.748252 -488.261914)
			(xy 16.747748 -488.326728) (xy 16.739689 -488.456106) (xy 16.723602 -488.584732) (xy 16.69955 -488.712109)
			(xy 16.667625 -488.837745) (xy 16.627952 -488.961153) (xy 16.580682 -489.081856) (xy 16.526001 -489.199386)
			(xy 16.464118 -489.31329) (xy 16.395273 -489.423126) (xy 16.319734 -489.528469) (xy 16.237791 -489.628912)
			(xy 16.149762 -489.724067) (xy 16.055988 -489.813565) (xy 15.956831 -489.89706) (xy 15.852675 -489.974229)
			(xy 15.743923 -490.044773) (xy 15.630995 -490.10842) (xy 15.51433 -490.164923) (xy 15.394377 -490.214064)
			(xy 15.271601 -490.255652) (xy 15.146477 -490.289527) (xy 15.019489 -490.315557) (xy 14.891128 -490.333642)
			(xy 14.761892 -490.343712) (xy 14.632279 -490.345728) (xy 14.502792 -490.339682) (xy 14.373931 -490.325598)
			(xy 14.246195 -490.303529) (xy 14.120078 -490.273562) (xy 13.996068 -490.235813) (xy 13.874645 -490.190426)
			(xy 13.756278 -490.137579) (xy 13.641426 -490.077475) (xy 13.530533 -490.010347) (xy 13.424027 -489.936455)
			(xy 13.322321 -489.856084) (xy 13.225809 -489.769546) (xy 13.134864 -489.677174) (xy 13.049837 -489.579328)
			(xy 12.971057 -489.476385) (xy 12.89883 -489.368743) (xy 12.833435 -489.256819) (xy 12.775124 -489.141046)
			(xy 12.724124 -489.021872) (xy 12.680632 -488.899758) (xy 12.644815 -488.775175) (xy 12.616813 -488.648608)
			(xy 12.596734 -488.520544) (xy 12.584655 -488.39148) (xy 12.580624 -488.261914) (xy 5.318555 -488.261914)
			(xy 5.314564 -488.390824) (xy 5.302605 -488.519247) (xy 5.282724 -488.646684) (xy 5.254997 -488.772647)
			(xy 5.219531 -488.896654) (xy 5.176461 -489.018229) (xy 5.125953 -489.136906) (xy 5.068199 -489.252232)
			(xy 5.003422 -489.363764) (xy 4.931868 -489.471075) (xy 4.853813 -489.573754) (xy 4.769556 -489.671407)
			(xy 4.679418 -489.76366) (xy 4.583746 -489.850161) (xy 4.482906 -489.930577) (xy 4.377284 -490.004601)
			(xy 4.267285 -490.071949) (xy 4.15333 -490.132363) (xy 4.035857 -490.185611) (xy 3.915313 -490.23149)
			(xy 3.792163 -490.269824) (xy 3.666877 -490.300465) (xy 3.539935 -490.323298) (xy 3.411824 -490.338233)
			(xy 3.283035 -490.345214) (xy 3.15406 -490.344215) (xy 3.025394 -490.335238) (xy 2.89753 -490.318319)
			(xy 2.770957 -490.293522) (xy 2.646161 -490.260942) (xy 2.52362 -490.220704) (xy 2.403802 -490.172962)
			(xy 2.287168 -490.117899) (xy 2.174163 -490.055726) (xy 2.065222 -489.986682) (xy 1.96076 -489.91103)
			(xy 1.861178 -489.82906) (xy 1.766858 -489.741087) (xy 1.678162 -489.647447) (xy 1.595428 -489.5485)
			(xy 1.518974 -489.444623) (xy 1.483614 -489.39069) (xy 1.470543 -489.371347) (xy 1.438546 -489.337361)
			(xy 1.400881 -489.30979) (xy 1.358815 -489.289561) (xy 1.313761 -489.277353) (xy 1.267236 -489.273578)
			(xy 1.220804 -489.278362) (xy 1.176027 -489.291545) (xy 1.134409 -489.312684) (xy 1.097352 -489.341066)
			(xy 1.0661 -489.375739) (xy 1.041706 -489.415535) (xy 1.024989 -489.459117) (xy 1.016512 -489.505018)
			(xy 1.016 -489.528358) (xy 1.016 -494.971578) (xy 1.047496 -495.054382) (xy 1.059942 -495.069876)
			(xy 1.077482 -495.09257) (xy 1.106268 -495.142179) (xy 1.127305 -495.195537) (xy 1.14012 -495.251442)
			(xy 1.144423 -495.308636) (xy 1.14012 -495.36583) (xy 1.127305 -495.421735) (xy 1.106268 -495.475093)
			(xy 1.077482 -495.524702) (xy 1.059942 -495.547396) (xy 1.047496 -495.56289) (xy 1.016 -495.645694)
			(xy 1.016 -495.86007) (xy 39.818063 -495.86007) (xy 39.82207 -495.744046) (xy 39.834072 -495.628574)
			(xy 39.854012 -495.514206) (xy 39.881795 -495.401486) (xy 39.917289 -495.290952) (xy 39.960324 -495.183129)
			(xy 40.010695 -495.078532) (xy 40.068162 -494.97766) (xy 40.132452 -494.880993) (xy 40.203257 -494.788992)
			(xy 40.280241 -494.702095) (xy 40.363037 -494.620716) (xy 40.45125 -494.545243) (xy 40.54446 -494.476036)
			(xy 40.642223 -494.413424) (xy 40.744072 -494.357707) (xy 40.849522 -494.309149) (xy 40.958071 -494.267981)
			(xy 41.069202 -494.234401) (xy 41.182385 -494.208568) (xy 41.29708 -494.190605) (xy 41.412742 -494.180597)
			(xy 41.528818 -494.178594) (xy 41.644756 -494.184603) (xy 41.760003 -494.198596) (xy 41.874009 -494.220507)
			(xy 41.986233 -494.250232) (xy 42.096139 -494.287628) (xy 42.203202 -494.332517) (xy 42.306914 -494.384686)
			(xy 42.406779 -494.443886) (xy 42.502322 -494.509835) (xy 42.593088 -494.582218) (xy 42.678643 -494.660691)
			(xy 42.758581 -494.744879) (xy 42.83252 -494.834381) (xy 42.900108 -494.928772) (xy 42.961022 -495.0276)
			(xy 43.014974 -495.130396) (xy 43.061704 -495.236669) (xy 43.100992 -495.345913) (xy 43.132649 -495.457606)
			(xy 43.156525 -495.571218) (xy 43.172506 -495.686206) (xy 43.180515 -495.802023) (xy 43.181016 -495.86007)
			(xy 43.180515 -495.918117) (xy 43.172506 -496.033934) (xy 43.156525 -496.148922) (xy 43.132649 -496.262534)
			(xy 43.100992 -496.374227) (xy 43.061704 -496.483471) (xy 43.014974 -496.589744) (xy 42.961022 -496.69254)
			(xy 42.900108 -496.791368) (xy 42.83252 -496.885759) (xy 42.758581 -496.975261) (xy 42.678643 -497.059449)
			(xy 42.593088 -497.137922) (xy 42.502604 -497.21008) (xy 93.154506 -497.21008) (xy 93.158522 -497.09381)
			(xy 93.170549 -496.978095) (xy 93.190531 -496.863485) (xy 93.218373 -496.750526) (xy 93.253942 -496.639758)
			(xy 93.297068 -496.531707) (xy 93.347545 -496.426889) (xy 93.405134 -496.325804) (xy 93.46956 -496.228932)
			(xy 93.540515 -496.136736) (xy 93.617662 -496.049655) (xy 93.700633 -495.968104) (xy 93.789033 -495.892472)
			(xy 93.88244 -495.823118) (xy 93.980409 -495.760375) (xy 94.082473 -495.704539) (xy 94.188147 -495.655878)
			(xy 94.296926 -495.614624) (xy 94.408291 -495.580973) (xy 94.521714 -495.555085) (xy 94.636651 -495.537084)
			(xy 94.752557 -495.527055) (xy 94.868879 -495.525047) (xy 94.985062 -495.531069) (xy 95.100553 -495.545092)
			(xy 95.214801 -495.56705) (xy 95.327262 -495.596837) (xy 95.4374 -495.634312) (xy 95.54469 -495.679297)
			(xy 95.648621 -495.731576) (xy 95.748697 -495.790901) (xy 95.844443 -495.856989) (xy 95.9354 -495.929525)
			(xy 96.021136 -496.008164) (xy 96.101243 -496.09253) (xy 96.175339 -496.182222) (xy 96.243069 -496.276812)
			(xy 96.304113 -496.37585) (xy 96.358178 -496.478863) (xy 96.405008 -496.58536) (xy 96.444379 -496.694835)
			(xy 96.476103 -496.806765) (xy 96.500029 -496.920617) (xy 96.516043 -497.035849) (xy 96.52407 -497.151911)
			(xy 96.524572 -497.21008) (xy 96.52407 -497.268249) (xy 96.516043 -497.384311) (xy 96.500029 -497.499543)
			(xy 96.476103 -497.613395) (xy 96.444379 -497.725325) (xy 96.405008 -497.8348) (xy 96.358178 -497.941297)
			(xy 96.304113 -498.04431) (xy 96.243069 -498.143348) (xy 96.175339 -498.237938) (xy 96.101243 -498.32763)
			(xy 96.021136 -498.411996) (xy 95.9354 -498.490635) (xy 95.844443 -498.563171) (xy 95.748697 -498.629259)
			(xy 95.648621 -498.688584) (xy 95.54469 -498.740863) (xy 95.4374 -498.785848) (xy 95.327262 -498.823323)
			(xy 95.214801 -498.85311) (xy 95.100553 -498.875068) (xy 94.985062 -498.889091) (xy 94.868879 -498.895113)
			(xy 94.752557 -498.893105) (xy 94.636651 -498.883076) (xy 94.521714 -498.865075) (xy 94.408291 -498.839187)
			(xy 94.296926 -498.805536) (xy 94.188147 -498.764282) (xy 94.082473 -498.715621) (xy 93.980409 -498.659785)
			(xy 93.88244 -498.597042) (xy 93.789033 -498.527688) (xy 93.700633 -498.452056) (xy 93.617662 -498.370505)
			(xy 93.540515 -498.283424) (xy 93.46956 -498.191228) (xy 93.405134 -498.094356) (xy 93.347545 -497.993271)
			(xy 93.297068 -497.888453) (xy 93.253942 -497.780402) (xy 93.218373 -497.669634) (xy 93.190531 -497.556675)
			(xy 93.170549 -497.442065) (xy 93.158522 -497.32635) (xy 93.154506 -497.21008) (xy 42.502604 -497.21008)
			(xy 42.502322 -497.210305) (xy 42.406779 -497.276254) (xy 42.306914 -497.335454) (xy 42.203202 -497.387623)
			(xy 42.096139 -497.432512) (xy 41.986233 -497.469908) (xy 41.874009 -497.499633) (xy 41.760003 -497.521544)
			(xy 41.644756 -497.535537) (xy 41.528818 -497.541546) (xy 41.412742 -497.539543) (xy 41.29708 -497.529535)
			(xy 41.182385 -497.511572) (xy 41.069202 -497.485739) (xy 40.958071 -497.452159) (xy 40.849522 -497.410991)
			(xy 40.744072 -497.362433) (xy 40.642223 -497.306716) (xy 40.54446 -497.244104) (xy 40.45125 -497.174897)
			(xy 40.363037 -497.099424) (xy 40.280241 -497.018045) (xy 40.203257 -496.931148) (xy 40.132452 -496.839147)
			(xy 40.068162 -496.74248) (xy 40.010695 -496.641608) (xy 39.960324 -496.537011) (xy 39.917289 -496.429188)
			(xy 39.881795 -496.318654) (xy 39.854012 -496.205934) (xy 39.834072 -496.091566) (xy 39.82207 -495.976094)
			(xy 39.818063 -495.86007) (xy 1.016 -495.86007) (xy 1.016 -507.671578) (xy 1.047496 -507.754382)
			(xy 1.059942 -507.769876) (xy 1.077482 -507.79257) (xy 1.106268 -507.842179) (xy 1.127305 -507.895537)
			(xy 1.14012 -507.951442) (xy 1.144423 -508.008636) (xy 1.14012 -508.06583) (xy 1.127305 -508.121735)
			(xy 1.106268 -508.175093) (xy 1.077482 -508.224702) (xy 1.059942 -508.247396) (xy 1.047496 -508.26289)
			(xy 1.016 -508.345694) (xy 1.016 -508.96012) (xy 86.877404 -508.96012) (xy 86.881424 -508.769469)
			(xy 86.893478 -508.579156) (xy 86.913544 -508.389521) (xy 86.941587 -508.2009) (xy 86.977556 -508.01363)
			(xy 87.021388 -507.828042) (xy 87.073005 -507.644467) (xy 87.132315 -507.463231) (xy 87.199213 -507.284656)
			(xy 87.273579 -507.109061) (xy 87.355281 -506.936756) (xy 87.444175 -506.768049) (xy 87.540101 -506.603239)
			(xy 87.64289 -506.44262) (xy 87.752359 -506.286477) (xy 87.868313 -506.135088) (xy 87.990547 -505.988721)
			(xy 88.118841 -505.847637) (xy 88.252969 -505.712088) (xy 88.392693 -505.582313) (xy 88.537763 -505.458543)
			(xy 88.687921 -505.341) (xy 88.842902 -505.229891) (xy 89.002429 -505.125414) (xy 89.166218 -505.027755)
			(xy 89.333978 -504.937088) (xy 89.505412 -504.853574) (xy 89.680214 -504.777361) (xy 89.858073 -504.708585)
			(xy 90.038674 -504.647367) (xy 90.221694 -504.593818) (xy 90.40681 -504.548032) (xy 90.593691 -504.51009)
			(xy 90.782006 -504.480061) (xy 90.971419 -504.457996) (xy 91.161593 -504.443937) (xy 91.352192 -504.437907)
			(xy 91.542875 -504.439917) (xy 91.733304 -504.449964) (xy 91.92314 -504.46803) (xy 92.112046 -504.494083)
			(xy 92.299685 -504.528076) (xy 92.485725 -504.569949) (xy 92.669834 -504.619628) (xy 92.851685 -504.677024)
			(xy 93.030955 -504.742035) (xy 93.207325 -504.814546) (xy 93.380481 -504.894427) (xy 93.550116 -504.981537)
			(xy 93.715928 -505.075721) (xy 93.877622 -505.176812) (xy 94.03491 -505.284628) (xy 94.187513 -505.39898)
			(xy 94.335161 -505.519663) (xy 94.477589 -505.646464) (xy 94.614545 -505.779155) (xy 94.745786 -505.917503)
			(xy 94.871078 -506.06126) (xy 94.990198 -506.210171) (xy 95.102934 -506.363972) (xy 95.209087 -506.522388)
			(xy 95.308467 -506.685139) (xy 95.400897 -506.851934) (xy 95.486214 -507.022478) (xy 95.564266 -507.196466)
			(xy 95.634913 -507.373591) (xy 95.698031 -507.553536) (xy 95.753507 -507.735982) (xy 95.801242 -507.920605)
			(xy 95.841152 -508.107075) (xy 95.873165 -508.295063) (xy 95.897225 -508.484233) (xy 95.913288 -508.674249)
			(xy 95.921327 -508.864773) (xy 95.92183 -508.96012) (xy 95.921327 -509.055467) (xy 95.913288 -509.245991)
			(xy 95.897225 -509.436007) (xy 95.873165 -509.625177) (xy 95.841152 -509.813165) (xy 95.801242 -509.999635)
			(xy 95.753507 -510.184258) (xy 95.698031 -510.366704) (xy 95.634913 -510.546649) (xy 95.564266 -510.723774)
			(xy 95.486214 -510.897762) (xy 95.400897 -511.068306) (xy 95.308467 -511.235101) (xy 95.209087 -511.397852)
			(xy 95.102934 -511.556268) (xy 94.990198 -511.710069) (xy 94.871078 -511.85898) (xy 94.745786 -512.002737)
			(xy 94.614545 -512.141085) (xy 94.477589 -512.273776) (xy 94.335161 -512.400577) (xy 94.187513 -512.52126)
			(xy 94.03491 -512.635612) (xy 93.877622 -512.743428) (xy 93.715928 -512.844519) (xy 93.550116 -512.938703)
			(xy 93.380481 -513.025813) (xy 93.207325 -513.105694) (xy 93.030955 -513.178205) (xy 92.851685 -513.243216)
			(xy 92.669834 -513.300612) (xy 92.485725 -513.350291) (xy 92.299685 -513.392164) (xy 92.112046 -513.426157)
			(xy 91.92314 -513.45221) (xy 91.733304 -513.470276) (xy 91.542875 -513.480323) (xy 91.352192 -513.482333)
			(xy 91.161593 -513.476303) (xy 90.971419 -513.462244) (xy 90.782006 -513.440179) (xy 90.593691 -513.41015)
			(xy 90.40681 -513.372208) (xy 90.221694 -513.326422) (xy 90.038674 -513.272873) (xy 89.858073 -513.211655)
			(xy 89.680214 -513.142879) (xy 89.505412 -513.066666) (xy 89.333978 -512.983152) (xy 89.166218 -512.892485)
			(xy 89.002429 -512.794826) (xy 88.842902 -512.690349) (xy 88.687921 -512.57924) (xy 88.537763 -512.461697)
			(xy 88.392693 -512.337927) (xy 88.252969 -512.208152) (xy 88.118841 -512.072603) (xy 87.990547 -511.931519)
			(xy 87.868313 -511.785152) (xy 87.752359 -511.633763) (xy 87.64289 -511.47762) (xy 87.540101 -511.317001)
			(xy 87.444175 -511.152191) (xy 87.355281 -510.983484) (xy 87.273579 -510.811179) (xy 87.199213 -510.635584)
			(xy 87.132315 -510.457009) (xy 87.073005 -510.275773) (xy 87.021388 -510.092198) (xy 86.977556 -509.90661)
			(xy 86.941587 -509.71934) (xy 86.913544 -509.530719) (xy 86.893478 -509.341084) (xy 86.881424 -509.150771)
			(xy 86.877404 -508.96012) (xy 1.016 -508.96012) (xy 1.016 -513.50545) (xy 1.016504 -513.52879) (xy 1.024982 -513.574694)
			(xy 1.041699 -513.618277) (xy 1.066094 -513.658075) (xy 1.097346 -513.692748) (xy 1.134405 -513.721132)
			(xy 1.176024 -513.742271) (xy 1.220803 -513.755455) (xy 1.267237 -513.760239) (xy 1.313763 -513.756464)
			(xy 1.358818 -513.744256) (xy 1.400886 -513.724025) (xy 1.438552 -513.696453) (xy 1.47055 -513.662466)
			(xy 1.483614 -513.643118) (xy 1.51897 -513.589182) (xy 1.595424 -513.485306) (xy 1.678157 -513.386358)
			(xy 1.766854 -513.292718) (xy 1.861173 -513.204744) (xy 1.960754 -513.122775) (xy 2.065216 -513.047122)
			(xy 2.174158 -512.978077) (xy 2.287162 -512.915904) (xy 2.403796 -512.860841) (xy 2.523614 -512.813099)
			(xy 2.646155 -512.77286) (xy 2.770951 -512.74028) (xy 2.897523 -512.715482) (xy 3.025387 -512.698563)
			(xy 3.154053 -512.689586) (xy 3.283028 -512.688586) (xy 3.411818 -512.695566) (xy 3.539929 -512.710501)
			(xy 3.66687 -512.733333) (xy 3.792157 -512.763974) (xy 3.915307 -512.802308) (xy 4.03585 -512.848186)
			(xy 4.153324 -512.901434) (xy 4.267279 -512.961848) (xy 4.377278 -513.029195) (xy 4.482901 -513.103219)
			(xy 4.583741 -513.183635) (xy 4.679413 -513.270135) (xy 4.769551 -513.362388) (xy 4.853809 -513.460041)
			(xy 4.931864 -513.56272) (xy 5.003418 -513.67003) (xy 5.068196 -513.781562) (xy 5.12595 -513.896887)
			(xy 5.176459 -514.015565) (xy 5.219529 -514.13714) (xy 5.254996 -514.261146) (xy 5.282723 -514.38711)
			(xy 5.302604 -514.514547) (xy 5.314563 -514.64297) (xy 5.318555 -514.771887) (xy 5.318555 -514.771894)
			(xy 12.580624 -514.771894) (xy 12.584655 -514.642328) (xy 12.596734 -514.513264) (xy 12.616813 -514.3852)
			(xy 12.644815 -514.258633) (xy 12.680632 -514.13405) (xy 12.724124 -514.011936) (xy 12.775124 -513.892762)
			(xy 12.833435 -513.776989) (xy 12.89883 -513.665065) (xy 12.971057 -513.557423) (xy 13.049837 -513.45448)
			(xy 13.134864 -513.356634) (xy 13.225809 -513.264262) (xy 13.322321 -513.177724) (xy 13.424027 -513.097353)
			(xy 13.530533 -513.023461) (xy 13.641426 -512.956333) (xy 13.756278 -512.896229) (xy 13.874645 -512.843382)
			(xy 13.996068 -512.797995) (xy 14.120078 -512.760246) (xy 14.246195 -512.730279) (xy 14.373931 -512.70821)
			(xy 14.502792 -512.694126) (xy 14.632279 -512.68808) (xy 14.761892 -512.690096) (xy 14.891128 -512.700166)
			(xy 15.019489 -512.718251) (xy 15.146477 -512.744281) (xy 15.271601 -512.778156) (xy 15.394377 -512.819744)
			(xy 15.51433 -512.868885) (xy 15.630995 -512.925388) (xy 15.743923 -512.989035) (xy 15.852675 -513.059579)
			(xy 15.956831 -513.136748) (xy 16.055988 -513.220243) (xy 16.149762 -513.309741) (xy 16.237791 -513.404896)
			(xy 16.319734 -513.505339) (xy 16.395273 -513.610682) (xy 16.464118 -513.720518) (xy 16.526001 -513.834422)
			(xy 16.580682 -513.951952) (xy 16.627952 -514.072655) (xy 16.667625 -514.196063) (xy 16.69955 -514.321699)
			(xy 16.723602 -514.449076) (xy 16.739689 -514.577702) (xy 16.747748 -514.70708) (xy 16.748252 -514.771894)
			(xy 16.747748 -514.836708) (xy 16.739689 -514.966086) (xy 16.723602 -515.094712) (xy 16.69955 -515.222089)
			(xy 16.667625 -515.347725) (xy 16.627952 -515.471133) (xy 16.580682 -515.591836) (xy 16.526001 -515.709366)
			(xy 16.464118 -515.82327) (xy 16.395273 -515.933106) (xy 16.319734 -516.038449) (xy 16.237791 -516.138892)
			(xy 16.149762 -516.234047) (xy 16.055988 -516.323545) (xy 15.956831 -516.40704) (xy 15.852675 -516.484209)
			(xy 15.743923 -516.554753) (xy 15.630995 -516.6184) (xy 15.51433 -516.674903) (xy 15.394377 -516.724044)
			(xy 15.271601 -516.765632) (xy 15.146477 -516.799507) (xy 15.019489 -516.825537) (xy 14.891128 -516.843622)
			(xy 14.761892 -516.853692) (xy 14.632279 -516.855708) (xy 14.502792 -516.849662) (xy 14.373931 -516.835578)
			(xy 14.246195 -516.813509) (xy 14.120078 -516.783542) (xy 13.996068 -516.745793) (xy 13.874645 -516.700406)
			(xy 13.756278 -516.647559) (xy 13.641426 -516.587455) (xy 13.530533 -516.520327) (xy 13.424027 -516.446435)
			(xy 13.322321 -516.366064) (xy 13.225809 -516.279526) (xy 13.134864 -516.187154) (xy 13.049837 -516.089308)
			(xy 12.971057 -515.986365) (xy 12.89883 -515.878723) (xy 12.833435 -515.766799) (xy 12.775124 -515.651026)
			(xy 12.724124 -515.531852) (xy 12.680632 -515.409738) (xy 12.644815 -515.285155) (xy 12.616813 -515.158588)
			(xy 12.596734 -515.030524) (xy 12.584655 -514.90146) (xy 12.580624 -514.771894) (xy 5.318555 -514.771894)
			(xy 5.314564 -514.900804) (xy 5.302605 -515.029227) (xy 5.282724 -515.156664) (xy 5.254997 -515.282627)
			(xy 5.219531 -515.406634) (xy 5.176461 -515.528209) (xy 5.125953 -515.646886) (xy 5.068199 -515.762212)
			(xy 5.003422 -515.873744) (xy 4.931868 -515.981055) (xy 4.853813 -516.083734) (xy 4.769556 -516.181387)
			(xy 4.679418 -516.27364) (xy 4.583746 -516.360141) (xy 4.482906 -516.440557) (xy 4.377284 -516.514581)
			(xy 4.267285 -516.581929) (xy 4.15333 -516.642343) (xy 4.035857 -516.695591) (xy 3.915313 -516.74147)
			(xy 3.792163 -516.779804) (xy 3.666877 -516.810445) (xy 3.539935 -516.833278) (xy 3.411824 -516.848213)
			(xy 3.283035 -516.855194) (xy 3.15406 -516.854195) (xy 3.025394 -516.845218) (xy 2.89753 -516.828299)
			(xy 2.770957 -516.803502) (xy 2.646161 -516.770922) (xy 2.52362 -516.730684) (xy 2.403802 -516.682942)
			(xy 2.287168 -516.627879) (xy 2.174163 -516.565706) (xy 2.065222 -516.496662) (xy 1.96076 -516.42101)
			(xy 1.861178 -516.33904) (xy 1.766858 -516.251067) (xy 1.678162 -516.157427) (xy 1.595428 -516.05848)
			(xy 1.518974 -515.954603) (xy 1.483614 -515.90067) (xy 1.470542 -515.881328) (xy 1.438544 -515.847345)
			(xy 1.400878 -515.819776) (xy 1.358811 -515.799548) (xy 1.313758 -515.787342) (xy 1.267234 -515.783567)
			(xy 1.220802 -515.788352) (xy 1.176025 -515.801534) (xy 1.134408 -515.822671) (xy 1.09735 -515.851053)
			(xy 1.066098 -515.885724) (xy 1.041702 -515.925518) (xy 1.024983 -515.969098) (xy 1.016503 -516.014999)
			(xy 1.016 -516.038338) (xy 1.016 -519.049762) (xy 72.857112 -519.049762) (xy 72.861127 -518.84658)
			(xy 72.873166 -518.643715) (xy 72.89321 -518.441485) (xy 72.921228 -518.240204) (xy 72.957176 -518.040187)
			(xy 73.000998 -517.841746) (xy 73.052625 -517.645192) (xy 73.111977 -517.450831) (xy 73.178962 -517.258966)
			(xy 73.253474 -517.069897) (xy 73.335397 -516.88392) (xy 73.424604 -516.701324) (xy 73.520955 -516.522395)
			(xy 73.624299 -516.347413) (xy 73.734476 -516.17665) (xy 73.851313 -516.010372) (xy 73.974628 -515.848841)
			(xy 74.104228 -515.692307) (xy 74.239911 -515.541016) (xy 74.381466 -515.395203) (xy 74.52867 -515.255096)
			(xy 74.681294 -515.120914) (xy 74.839101 -514.992866) (xy 75.001843 -514.871153) (xy 75.169266 -514.755965)
			(xy 75.341109 -514.64748) (xy 75.517104 -514.545869) (xy 75.696976 -514.451291) (xy 75.880444 -514.363892)
			(xy 76.067222 -514.28381) (xy 76.257018 -514.21117) (xy 76.449535 -514.146084) (xy 76.644473 -514.088655)
			(xy 76.841528 -514.038972) (xy 77.040392 -513.997112) (xy 77.240754 -513.963142) (xy 77.442302 -513.937114)
			(xy 77.644721 -513.919069) (xy 77.847694 -513.909035) (xy 78.050906 -513.907027) (xy 78.254038 -513.913049)
			(xy 78.456774 -513.927092) (xy 78.658797 -513.949133) (xy 78.859791 -513.979138) (xy 79.059443 -514.01706)
			(xy 79.257441 -514.06284) (xy 79.453476 -514.116406) (xy 79.647241 -514.177676) (xy 79.838435 -514.246552)
			(xy 80.026758 -514.322929) (xy 80.211917 -514.406685) (xy 80.393623 -514.497692) (xy 80.571591 -514.595805)
			(xy 80.745544 -514.700874) (xy 80.915211 -514.812732) (xy 81.080325 -514.931206) (xy 81.240631 -515.056111)
			(xy 81.395877 -515.187251) (xy 81.54582 -515.324422) (xy 81.690228 -515.46741) (xy 81.828873 -515.615991)
			(xy 81.961541 -515.769934) (xy 82.088023 -515.928997) (xy 82.208123 -516.092934) (xy 82.321652 -516.261487)
			(xy 82.428433 -516.434394) (xy 82.5283 -516.611384) (xy 82.621097 -516.792181) (xy 82.706679 -516.976504)
			(xy 82.784912 -517.164063) (xy 82.855674 -517.354567) (xy 82.918855 -517.547718) (xy 82.974355 -517.743214)
			(xy 83.022089 -517.94075) (xy 83.061982 -518.140018) (xy 83.093971 -518.340706) (xy 83.118007 -518.542501)
			(xy 83.134052 -518.745088) (xy 83.14208 -518.948151) (xy 83.142582 -519.049762) (xy 83.14208 -519.151373)
			(xy 83.134052 -519.354436) (xy 83.118007 -519.557023) (xy 83.093971 -519.758818) (xy 83.061982 -519.959506)
			(xy 83.022089 -520.158774) (xy 82.974355 -520.35631) (xy 82.918855 -520.551806) (xy 82.855674 -520.744957)
			(xy 82.784912 -520.935461) (xy 82.706679 -521.12302) (xy 82.621097 -521.307343) (xy 82.5283 -521.48814)
			(xy 82.428433 -521.66513) (xy 82.321652 -521.838037) (xy 82.208123 -522.00659) (xy 82.088023 -522.170527)
			(xy 81.961541 -522.32959) (xy 81.828873 -522.483533) (xy 81.690228 -522.632114) (xy 81.54582 -522.775102)
			(xy 81.395877 -522.912273) (xy 81.240631 -523.043413) (xy 81.080325 -523.168318) (xy 80.915211 -523.286792)
			(xy 80.745544 -523.39865) (xy 80.571591 -523.503719) (xy 80.393623 -523.601832) (xy 80.211917 -523.692839)
			(xy 80.026758 -523.776595) (xy 79.838435 -523.852972) (xy 79.647241 -523.921848) (xy 79.453476 -523.983118)
			(xy 79.257441 -524.036684) (xy 79.059443 -524.082464) (xy 78.859791 -524.120386) (xy 78.658797 -524.150391)
			(xy 78.456774 -524.172432) (xy 78.254038 -524.186475) (xy 78.050906 -524.192497) (xy 77.847694 -524.190489)
			(xy 77.644721 -524.180455) (xy 77.442302 -524.16241) (xy 77.240754 -524.136382) (xy 77.040392 -524.102412)
			(xy 76.841528 -524.060552) (xy 76.644473 -524.010869) (xy 76.449535 -523.95344) (xy 76.257018 -523.888354)
			(xy 76.067222 -523.815714) (xy 75.880444 -523.735632) (xy 75.696976 -523.648233) (xy 75.517104 -523.553655)
			(xy 75.341109 -523.452044) (xy 75.169266 -523.343559) (xy 75.001843 -523.228371) (xy 74.839101 -523.106658)
			(xy 74.681294 -522.97861) (xy 74.52867 -522.844428) (xy 74.381466 -522.704321) (xy 74.239911 -522.558508)
			(xy 74.104228 -522.407217) (xy 73.974628 -522.250683) (xy 73.851313 -522.089152) (xy 73.734476 -521.922874)
			(xy 73.624299 -521.752111) (xy 73.520955 -521.577129) (xy 73.424604 -521.3982) (xy 73.335397 -521.215604)
			(xy 73.253474 -521.029627) (xy 73.178962 -520.840558) (xy 73.111977 -520.648693) (xy 73.052625 -520.454332)
			(xy 73.000998 -520.257778) (xy 72.957176 -520.059337) (xy 72.921228 -519.85932) (xy 72.89321 -519.658039)
			(xy 72.873166 -519.455809) (xy 72.861127 -519.252944) (xy 72.857112 -519.049762) (xy 1.016 -519.049762)
			(xy 1.016 -520.371578) (xy 1.047496 -520.454382) (xy 1.059942 -520.469876) (xy 1.077482 -520.49257)
			(xy 1.106268 -520.542179) (xy 1.127305 -520.595537) (xy 1.14012 -520.651442) (xy 1.144423 -520.708636)
			(xy 1.14012 -520.76583) (xy 1.127305 -520.821735) (xy 1.106268 -520.875093) (xy 1.077482 -520.924702)
			(xy 1.059942 -520.947396) (xy 1.047496 -520.96289) (xy 1.016 -521.045694) (xy 1.016 -524.500094)
			(xy 1.016496 -524.531776) (xy 1.024766 -524.594598) (xy 1.041166 -524.655803) (xy 1.065414 -524.714344)
			(xy 1.097096 -524.769219) (xy 1.13567 -524.819489) (xy 1.180475 -524.864294) (xy 1.230745 -524.902868)
			(xy 1.28562 -524.93455) (xy 1.344161 -524.958798) (xy 1.405366 -524.975198) (xy 1.468188 -524.983468)
			(xy 1.49987 -524.983964) (xy 6.478778 -524.983964) (xy 6.494104 -524.9835) (xy 6.523871 -524.976184)
			(xy 6.551041 -524.961993) (xy 6.562852 -524.952214) (xy 6.58388 -524.934272) (xy 6.630136 -524.904011)
			(xy 6.680275 -524.880743) (xy 6.733248 -524.864955) (xy 6.787944 -524.856977) (xy 6.84322 -524.856977)
			(xy 6.897916 -524.864955) (xy 6.950889 -524.880743) (xy 7.001028 -524.904011) (xy 7.047284 -524.934272)
			(xy 7.068312 -524.952214) (xy 7.080084 -524.962052) (xy 7.10726 -524.976271) (xy 7.13705 -524.98357)
			(xy 7.152386 -524.983964) (xy 19.178778 -524.983964) (xy 19.194104 -524.9835) (xy 19.223871 -524.976184)
			(xy 19.251041 -524.961993) (xy 19.262852 -524.952214) (xy 19.28388 -524.934272) (xy 19.330136 -524.904011)
			(xy 19.380275 -524.880743) (xy 19.433248 -524.864955) (xy 19.487944 -524.856977) (xy 19.54322 -524.856977)
			(xy 19.597916 -524.864955) (xy 19.650889 -524.880743) (xy 19.701028 -524.904011) (xy 19.747284 -524.934272)
			(xy 19.768312 -524.952214) (xy 19.780084 -524.962052) (xy 19.80726 -524.976271) (xy 19.83705 -524.98357)
			(xy 19.852386 -524.983964) (xy 23.50008 -524.983964) (xy 23.570659 -524.984449) (xy 23.711596 -524.992364)
			(xy 23.851867 -525.008169) (xy 23.991032 -525.031814) (xy 24.128651 -525.063226) (xy 24.264293 -525.102306)
			(xy 24.397529 -525.14893) (xy 24.527942 -525.202952) (xy 24.65512 -525.264202) (xy 24.778663 -525.332488)
			(xy 24.898183 -525.407593) (xy 25.013303 -525.489282) (xy 25.123662 -525.577298) (xy 25.228911 -525.671364)
			(xy 25.32872 -525.771184) (xy 25.422775 -525.876443) (xy 25.510779 -525.986811) (xy 25.592456 -526.10194)
			(xy 25.667549 -526.221468) (xy 25.735821 -526.345018) (xy 25.797057 -526.472203) (xy 25.851065 -526.602621)
			(xy 25.897675 -526.735863) (xy 25.93674 -526.871508) (xy 25.968138 -527.009131) (xy 25.991769 -527.148298)
			(xy 26.007559 -527.288571) (xy 26.015458 -527.429509) (xy 26.01595 -527.500088) (xy 26.01595 -528.500086)
			(xy 26.016486 -528.531772) (xy 26.024792 -528.594597) (xy 26.041223 -528.655801) (xy 26.065499 -528.714339)
			(xy 26.097206 -528.769209) (xy 26.135801 -528.819472) (xy 26.180623 -528.864271) (xy 26.230908 -528.902839)
			(xy 26.285794 -528.934516) (xy 26.344345 -528.958761) (xy 26.405558 -528.975159) (xy 26.468388 -528.983431)
			(xy 26.500074 -528.983956) (xy 27.598878 -528.983956)
		)
		(stroke
			(width 0)
			(type solid)
		)
		(fill yes)
		(layer "In4.Cu")
		(net "P12V")
	)
	(gr_arc
		(start 1.500124 -3.999992)
		(mid 0.439376 -4.439368)
		(end 0 -5.500116)
		(stroke
			(width 0.2)
			(type default)
		)
		(layer "In4.Cu")
	)
	(gr_arc
		(start 1.500124 -3.999992)
		(mid 0.439376 -4.439368)
		(end 0 -5.500116)
		(stroke
			(width 2.032)
			(type default)
		)
		(layer "In4.Cu")
	)
	(gr_line
		(start 1.500124 -3.999992)
		(end 23.50008 -3.999992)
		(stroke
			(width 0.2)
			(type default)
		)
		(layer "In4.Cu")
	)
	(gr_line
		(start 1.500124 -3.999992)
		(end 23.50008 -3.999992)
		(stroke
			(width 2.032)
			(type default)
		)
		(layer "In4.Cu")
	)
	(gr_line
		(start 16.459708 -384.696462)
		(end 16.64716 -384.696462)
		(stroke
			(width 2.54)
			(type default)
		)
		(layer "In4.Cu")
	)
	(gr_line
		(start 16.459708 -29.096462)
		(end 16.64716 -29.096462)
		(stroke
			(width 2.54)
			(type default)
		)
		(layer "In4.Cu")
	)
	(gr_line
		(start 16.459962 -473.596462)
		(end 16.647414 -473.596462)
		(stroke
			(width 2.54)
			(type default)
		)
		(layer "In4.Cu")
	)
	(gr_line
		(start 16.459962 -295.796462)
		(end 16.647414 -295.796462)
		(stroke
			(width 2.54)
			(type default)
		)
		(layer "In4.Cu")
	)
	(gr_line
		(start 16.459962 -206.896462)
		(end 16.647414 -206.896462)
		(stroke
			(width 2.54)
			(type default)
		)
		(layer "In4.Cu")
	)
	(gr_line
		(start 16.459962 -117.996462)
		(end 16.647414 -117.996462)
		(stroke
			(width 2.54)
			(type default)
		)
		(layer "In4.Cu")
	)
	(gr_circle
		(center 16.599662 -384.800094)
		(end 17.732756 -384.800094)
		(stroke
			(width 0.508)
			(type default)
		)
		(fill no)
		(layer "In4.Cu")
	)
	(gr_circle
		(center 16.599662 -384.800094)
		(end 18.616676 -384.800094)
		(stroke
			(width 1.27)
			(type default)
		)
		(fill no)
		(layer "In4.Cu")
	)
	(gr_circle
		(center 16.599662 -384.800094)
		(end 20.472146 -384.800094)
		(stroke
			(width 2.54)
			(type default)
		)
		(fill no)
		(layer "In4.Cu")
	)
	(gr_circle
		(center 16.599662 -29.200094)
		(end 17.732756 -29.200094)
		(stroke
			(width 0.508)
			(type default)
		)
		(fill no)
		(layer "In4.Cu")
	)
	(gr_circle
		(center 16.599662 -29.200094)
		(end 18.616676 -29.200094)
		(stroke
			(width 1.27)
			(type default)
		)
		(fill no)
		(layer "In4.Cu")
	)
	(gr_circle
		(center 16.599662 -29.200094)
		(end 20.472146 -29.200094)
		(stroke
			(width 2.54)
			(type default)
		)
		(fill no)
		(layer "In4.Cu")
	)
	(gr_circle
		(center 16.599916 -473.700094)
		(end 17.73301 -473.700094)
		(stroke
			(width 0.508)
			(type default)
		)
		(fill no)
		(layer "In4.Cu")
	)
	(gr_circle
		(center 16.599916 -473.700094)
		(end 18.61693 -473.700094)
		(stroke
			(width 1.27)
			(type default)
		)
		(fill no)
		(layer "In4.Cu")
	)
	(gr_circle
		(center 16.599916 -473.700094)
		(end 20.4724 -473.700094)
		(stroke
			(width 2.54)
			(type default)
		)
		(fill no)
		(layer "In4.Cu")
	)
	(gr_circle
		(center 16.599916 -473.69984)
		(end 21.791422 -473.69984)
		(stroke
			(width 0.127)
			(type default)
		)
		(fill no)
		(layer "In4.Cu")
	)
	(gr_circle
		(center 16.599916 -384.79984)
		(end 21.791676 -384.79984)
		(stroke
			(width 0.127)
			(type default)
		)
		(fill no)
		(layer "In4.Cu")
	)
	(gr_circle
		(center 16.599916 -295.900094)
		(end 17.73301 -295.900094)
		(stroke
			(width 0.508)
			(type default)
		)
		(fill no)
		(layer "In4.Cu")
	)
	(gr_circle
		(center 16.599916 -295.900094)
		(end 18.61693 -295.900094)
		(stroke
			(width 1.27)
			(type default)
		)
		(fill no)
		(layer "In4.Cu")
	)
	(gr_circle
		(center 16.599916 -295.900094)
		(end 20.4724 -295.900094)
		(stroke
			(width 2.54)
			(type default)
		)
		(fill no)
		(layer "In4.Cu")
	)
	(gr_circle
		(center 16.599916 -295.89984)
		(end 21.792184 -295.89984)
		(stroke
			(width 0.127)
			(type default)
		)
		(fill no)
		(layer "In4.Cu")
	)
	(gr_circle
		(center 16.599916 -207.000094)
		(end 17.73301 -207.000094)
		(stroke
			(width 0.508)
			(type default)
		)
		(fill no)
		(layer "In4.Cu")
	)
	(gr_circle
		(center 16.599916 -207.000094)
		(end 18.61693 -207.000094)
		(stroke
			(width 1.27)
			(type default)
		)
		(fill no)
		(layer "In4.Cu")
	)
	(gr_circle
		(center 16.599916 -207.000094)
		(end 20.4724 -207.000094)
		(stroke
			(width 2.54)
			(type default)
		)
		(fill no)
		(layer "In4.Cu")
	)
	(gr_circle
		(center 16.599916 -206.99984)
		(end 21.791676 -206.99984)
		(stroke
			(width 0.127)
			(type default)
		)
		(fill no)
		(layer "In4.Cu")
	)
	(gr_circle
		(center 16.599916 -118.100094)
		(end 17.73301 -118.100094)
		(stroke
			(width 0.508)
			(type default)
		)
		(fill no)
		(layer "In4.Cu")
	)
	(gr_circle
		(center 16.599916 -118.100094)
		(end 18.61693 -118.100094)
		(stroke
			(width 1.27)
			(type default)
		)
		(fill no)
		(layer "In4.Cu")
	)
	(gr_circle
		(center 16.599916 -118.100094)
		(end 20.4724 -118.100094)
		(stroke
			(width 2.54)
			(type default)
		)
		(fill no)
		(layer "In4.Cu")
	)
	(gr_circle
		(center 16.599916 -118.09984)
		(end 21.791422 -118.09984)
		(stroke
			(width 0.127)
			(type default)
		)
		(fill no)
		(layer "In4.Cu")
	)
	(gr_circle
		(center 16.599916 -29.19984)
		(end 21.792438 -29.19984)
		(stroke
			(width 0.127)
			(type default)
		)
		(fill no)
		(layer "In4.Cu")
	)
	(gr_line
		(start 16.64716 -384.696462)
		(end 16.783558 -384.83286)
		(stroke
			(width 2.54)
			(type default)
		)
		(layer "In4.Cu")
	)
	(gr_line
		(start 16.64716 -29.096462)
		(end 16.783558 -29.23286)
		(stroke
			(width 2.54)
			(type default)
		)
		(layer "In4.Cu")
	)
	(gr_line
		(start 16.647414 -473.596462)
		(end 16.783812 -473.73286)
		(stroke
			(width 2.54)
			(type default)
		)
		(layer "In4.Cu")
	)
	(gr_line
		(start 16.647414 -295.796462)
		(end 16.783812 -295.93286)
		(stroke
			(width 2.54)
			(type default)
		)
		(layer "In4.Cu")
	)
	(gr_line
		(start 16.647414 -206.896462)
		(end 16.783812 -207.03286)
		(stroke
			(width 2.54)
			(type default)
		)
		(layer "In4.Cu")
	)
	(gr_line
		(start 16.647414 -117.996462)
		(end 16.783812 -118.13286)
		(stroke
			(width 2.54)
			(type default)
		)
		(layer "In4.Cu")
	)
	(gr_line
		(start 16.655542 -384.986276)
		(end 16.655542 -384.892296)
		(stroke
			(width 2.54)
			(type default)
		)
		(layer "In4.Cu")
	)
	(gr_line
		(start 16.655542 -384.892296)
		(end 16.459708 -384.696462)
		(stroke
			(width 2.54)
			(type default)
		)
		(layer "In4.Cu")
	)
	(gr_line
		(start 16.655542 -29.386276)
		(end 16.655542 -29.292296)
		(stroke
			(width 2.54)
			(type default)
		)
		(layer "In4.Cu")
	)
	(gr_line
		(start 16.655542 -29.292296)
		(end 16.459708 -29.096462)
		(stroke
			(width 2.54)
			(type default)
		)
		(layer "In4.Cu")
	)
	(gr_line
		(start 16.655796 -473.886276)
		(end 16.655796 -473.792296)
		(stroke
			(width 2.54)
			(type default)
		)
		(layer "In4.Cu")
	)
	(gr_line
		(start 16.655796 -473.792296)
		(end 16.459962 -473.596462)
		(stroke
			(width 2.54)
			(type default)
		)
		(layer "In4.Cu")
	)
	(gr_line
		(start 16.655796 -296.086276)
		(end 16.655796 -295.992296)
		(stroke
			(width 2.54)
			(type default)
		)
		(layer "In4.Cu")
	)
	(gr_line
		(start 16.655796 -295.992296)
		(end 16.459962 -295.796462)
		(stroke
			(width 2.54)
			(type default)
		)
		(layer "In4.Cu")
	)
	(gr_line
		(start 16.655796 -207.186276)
		(end 16.655796 -207.092296)
		(stroke
			(width 2.54)
			(type default)
		)
		(layer "In4.Cu")
	)
	(gr_line
		(start 16.655796 -207.092296)
		(end 16.459962 -206.896462)
		(stroke
			(width 2.54)
			(type default)
		)
		(layer "In4.Cu")
	)
	(gr_line
		(start 16.655796 -118.286276)
		(end 16.655796 -118.192296)
		(stroke
			(width 2.54)
			(type default)
		)
		(layer "In4.Cu")
	)
	(gr_line
		(start 16.655796 -118.192296)
		(end 16.459962 -117.996462)
		(stroke
			(width 2.54)
			(type default)
		)
		(layer "In4.Cu")
	)
	(gr_line
		(start 23.50008 -525.999964)
		(end 1.500124 -525.999964)
		(stroke
			(width 0.2)
			(type default)
		)
		(layer "In4.Cu")
	)
	(gr_line
		(start 23.50008 -525.999964)
		(end 1.500124 -525.999964)
		(stroke
			(width 2.032)
			(type default)
		)
		(layer "In4.Cu")
	)
	(gr_arc
		(start 23.50008 -3.999992)
		(mid 24.560648 -3.56069)
		(end 24.99995 -2.500122)
		(stroke
			(width 0.2)
			(type default)
		)
		(layer "In4.Cu")
	)
	(gr_arc
		(start 23.50008 -3.999992)
		(mid 24.560648 -3.56069)
		(end 24.99995 -2.500122)
		(stroke
			(width 2.032)
			(type default)
		)
		(layer "In4.Cu")
	)
	(gr_line
		(start 24.99995 -528.500086)
		(end 24.99995 -527.500088)
		(stroke
			(width 0.2)
			(type default)
		)
		(layer "In4.Cu")
	)
	(gr_line
		(start 24.99995 -528.500086)
		(end 24.99995 -527.500088)
		(stroke
			(width 2.032)
			(type default)
		)
		(layer "In4.Cu")
	)
	(gr_arc
		(start 24.99995 -528.500086)
		(mid 25.439426 -529.560658)
		(end 26.500074 -529.999956)
		(stroke
			(width 0.2)
			(type default)
		)
		(layer "In4.Cu")
	)
	(gr_arc
		(start 24.99995 -528.500086)
		(mid 25.439426 -529.560658)
		(end 26.500074 -529.999956)
		(stroke
			(width 2.032)
			(type default)
		)
		(layer "In4.Cu")
	)
	(gr_arc
		(start 24.99995 -527.500088)
		(mid 24.560738 -526.439356)
		(end 23.50008 -525.999964)
		(stroke
			(width 0.2)
			(type default)
		)
		(layer "In4.Cu")
	)
	(gr_arc
		(start 24.99995 -527.500088)
		(mid 24.560738 -526.439356)
		(end 23.50008 -525.999964)
		(stroke
			(width 2.032)
			(type default)
		)
		(layer "In4.Cu")
	)
	(gr_line
		(start 24.99995 -2.500122)
		(end 24.99995 -1.500124)
		(stroke
			(width 0.2)
			(type default)
		)
		(layer "In4.Cu")
	)
	(gr_line
		(start 24.99995 -2.500122)
		(end 24.99995 -1.500124)
		(stroke
			(width 2.032)
			(type default)
		)
		(layer "In4.Cu")
	)
	(gr_arc
		(start 26.500074 0)
		(mid 25.439325 -0.439375)
		(end 24.99995 -1.500124)
		(stroke
			(width 0.2)
			(type default)
		)
		(layer "In4.Cu")
	)
	(gr_arc
		(start 26.500074 0)
		(mid 25.439325 -0.439375)
		(end 24.99995 -1.500124)
		(stroke
			(width 2.032)
			(type default)
		)
		(layer "In4.Cu")
	)
	(gr_line
		(start 26.500074 0)
		(end 101.000052 0)
		(stroke
			(width 0.2)
			(type default)
		)
		(layer "In4.Cu")
	)
	(gr_line
		(start 26.500074 0)
		(end 101.000052 0)
		(stroke
			(width 2.032)
			(type default)
		)
		(layer "In4.Cu")
	)
	(gr_arc
		(start 75.3999 -478.799906)
		(mid 77.999844 -481.39985)
		(end 80.599788 -478.799906)
		(stroke
			(width 2.032)
			(type default)
		)
		(layer "In4.Cu")
	)
	(gr_line
		(start 75.3999 -477.799908)
		(end 75.3999 -478.799906)
		(stroke
			(width 2.032)
			(type default)
		)
		(layer "In4.Cu")
	)
	(gr_line
		(start 76.752196 -479.517202)
		(end 77.094334 -479.85934)
		(stroke
			(width 2.032)
			(type default)
		)
		(layer "In4.Cu")
	)
	(gr_line
		(start 76.752196 -479.22053)
		(end 76.752196 -479.517202)
		(stroke
			(width 2.032)
			(type default)
		)
		(layer "In4.Cu")
	)
	(gr_line
		(start 76.752196 -479.22053)
		(end 76.752196 -478.216468)
		(stroke
			(width 2.032)
			(type default)
		)
		(layer "In4.Cu")
	)
	(gr_line
		(start 76.752196 -478.216468)
		(end 78.029816 -476.938848)
		(stroke
			(width 2.032)
			(type default)
		)
		(layer "In4.Cu")
	)
	(gr_line
		(start 77.003148 -479.471482)
		(end 76.752196 -479.22053)
		(stroke
			(width 2.032)
			(type default)
		)
		(layer "In4.Cu")
	)
	(gr_line
		(start 77.094334 -479.85934)
		(end 78.143862 -478.809812)
		(stroke
			(width 2.032)
			(type default)
		)
		(layer "In4.Cu")
	)
	(gr_line
		(start 77.85989 -32.196024)
		(end 78.047342 -32.196024)
		(stroke
			(width 2.54)
			(type default)
		)
		(layer "In4.Cu")
	)
	(gr_line
		(start 77.860144 -518.94613)
		(end 78.047596 -518.94613)
		(stroke
			(width 2.54)
			(type default)
		)
		(layer "In4.Cu")
	)
	(gr_line
		(start 77.860144 -430.04613)
		(end 78.047596 -430.04613)
		(stroke
			(width 2.54)
			(type default)
		)
		(layer "In4.Cu")
	)
	(gr_line
		(start 77.860144 -341.14613)
		(end 78.047596 -341.14613)
		(stroke
			(width 2.54)
			(type default)
		)
		(layer "In4.Cu")
	)
	(gr_line
		(start 77.860144 -209.996024)
		(end 78.047596 -209.996024)
		(stroke
			(width 2.54)
			(type default)
		)
		(layer "In4.Cu")
	)
	(gr_line
		(start 77.860398 -121.096024)
		(end 78.04785 -121.096024)
		(stroke
			(width 2.54)
			(type default)
		)
		(layer "In4.Cu")
	)
	(gr_circle
		(center 77.999844 -32.299656)
		(end 79.132938 -32.299656)
		(stroke
			(width 0.508)
			(type default)
		)
		(fill no)
		(layer "In4.Cu")
	)
	(gr_circle
		(center 77.999844 -32.299656)
		(end 80.016858 -32.299656)
		(stroke
			(width 1.27)
			(type default)
		)
		(fill no)
		(layer "In4.Cu")
	)
	(gr_circle
		(center 77.999844 -32.299656)
		(end 81.872328 -32.299656)
		(stroke
			(width 2.54)
			(type default)
		)
		(fill no)
		(layer "In4.Cu")
	)
	(gr_circle
		(center 78.000098 -519.049762)
		(end 79.133192 -519.049762)
		(stroke
			(width 0.508)
			(type default)
		)
		(fill no)
		(layer "In4.Cu")
	)
	(gr_circle
		(center 78.000098 -519.049762)
		(end 80.017112 -519.049762)
		(stroke
			(width 1.27)
			(type default)
		)
		(fill no)
		(layer "In4.Cu")
	)
	(gr_circle
		(center 78.000098 -519.049762)
		(end 81.872582 -519.049762)
		(stroke
			(width 2.54)
			(type default)
		)
		(fill no)
		(layer "In4.Cu")
	)
	(gr_circle
		(center 78.000098 -430.149762)
		(end 79.133192 -430.149762)
		(stroke
			(width 0.508)
			(type default)
		)
		(fill no)
		(layer "In4.Cu")
	)
	(gr_circle
		(center 78.000098 -430.149762)
		(end 80.017112 -430.149762)
		(stroke
			(width 1.27)
			(type default)
		)
		(fill no)
		(layer "In4.Cu")
	)
	(gr_circle
		(center 78.000098 -430.149762)
		(end 81.872582 -430.149762)
		(stroke
			(width 2.54)
			(type default)
		)
		(fill no)
		(layer "In4.Cu")
	)
	(gr_circle
		(center 78.000098 -341.249762)
		(end 79.133192 -341.249762)
		(stroke
			(width 0.508)
			(type default)
		)
		(fill no)
		(layer "In4.Cu")
	)
	(gr_circle
		(center 78.000098 -341.249762)
		(end 80.017112 -341.249762)
		(stroke
			(width 1.27)
			(type default)
		)
		(fill no)
		(layer "In4.Cu")
	)
	(gr_circle
		(center 78.000098 -341.249762)
		(end 81.872582 -341.249762)
		(stroke
			(width 2.54)
			(type default)
		)
		(fill no)
		(layer "In4.Cu")
	)
	(gr_circle
		(center 78.000098 -210.099656)
		(end 79.133192 -210.099656)
		(stroke
			(width 0.508)
			(type default)
		)
		(fill no)
		(layer "In4.Cu")
	)
	(gr_circle
		(center 78.000098 -210.099656)
		(end 80.017112 -210.099656)
		(stroke
			(width 1.27)
			(type default)
		)
		(fill no)
		(layer "In4.Cu")
	)
	(gr_circle
		(center 78.000098 -210.099656)
		(end 81.872582 -210.099656)
		(stroke
			(width 2.54)
			(type default)
		)
		(fill no)
		(layer "In4.Cu")
	)
	(gr_circle
		(center 78.000352 -121.199656)
		(end 79.133446 -121.199656)
		(stroke
			(width 0.508)
			(type default)
		)
		(fill no)
		(layer "In4.Cu")
	)
	(gr_circle
		(center 78.000352 -121.199656)
		(end 80.017366 -121.199656)
		(stroke
			(width 1.27)
			(type default)
		)
		(fill no)
		(layer "In4.Cu")
	)
	(gr_circle
		(center 78.000352 -121.199656)
		(end 81.872836 -121.199656)
		(stroke
			(width 2.54)
			(type default)
		)
		(fill no)
		(layer "In4.Cu")
	)
	(gr_line
		(start 78.029816 -476.938848)
		(end 79.079344 -476.938848)
		(stroke
			(width 2.032)
			(type default)
		)
		(layer "In4.Cu")
	)
	(gr_line
		(start 78.047342 -32.196024)
		(end 78.18374 -32.332422)
		(stroke
			(width 2.54)
			(type default)
		)
		(layer "In4.Cu")
	)
	(gr_line
		(start 78.047596 -518.94613)
		(end 78.183994 -519.082528)
		(stroke
			(width 2.54)
			(type default)
		)
		(layer "In4.Cu")
	)
	(gr_line
		(start 78.047596 -430.04613)
		(end 78.183994 -430.182528)
		(stroke
			(width 2.54)
			(type default)
		)
		(layer "In4.Cu")
	)
	(gr_line
		(start 78.047596 -341.14613)
		(end 78.183994 -341.282528)
		(stroke
			(width 2.54)
			(type default)
		)
		(layer "In4.Cu")
	)
	(gr_line
		(start 78.047596 -209.996024)
		(end 78.183994 -210.132422)
		(stroke
			(width 2.54)
			(type default)
		)
		(layer "In4.Cu")
	)
	(gr_line
		(start 78.04785 -121.096024)
		(end 78.184248 -121.232422)
		(stroke
			(width 2.54)
			(type default)
		)
		(layer "In4.Cu")
	)
	(gr_line
		(start 78.052676 -478.307654)
		(end 78.052676 -478.581466)
		(stroke
			(width 2.032)
			(type default)
		)
		(layer "In4.Cu")
	)
	(gr_line
		(start 78.055724 -32.485838)
		(end 78.055724 -32.391858)
		(stroke
			(width 2.54)
			(type default)
		)
		(layer "In4.Cu")
	)
	(gr_line
		(start 78.055724 -32.391858)
		(end 77.85989 -32.196024)
		(stroke
			(width 2.54)
			(type default)
		)
		(layer "In4.Cu")
	)
	(gr_line
		(start 78.055978 -519.235944)
		(end 78.055978 -519.141964)
		(stroke
			(width 2.54)
			(type default)
		)
		(layer "In4.Cu")
	)
	(gr_line
		(start 78.055978 -519.141964)
		(end 77.860144 -518.94613)
		(stroke
			(width 2.54)
			(type default)
		)
		(layer "In4.Cu")
	)
	(gr_line
		(start 78.055978 -430.335944)
		(end 78.055978 -430.241964)
		(stroke
			(width 2.54)
			(type default)
		)
		(layer "In4.Cu")
	)
	(gr_line
		(start 78.055978 -430.241964)
		(end 77.860144 -430.04613)
		(stroke
			(width 2.54)
			(type default)
		)
		(layer "In4.Cu")
	)
	(gr_line
		(start 78.055978 -341.435944)
		(end 78.055978 -341.341964)
		(stroke
			(width 2.54)
			(type default)
		)
		(layer "In4.Cu")
	)
	(gr_line
		(start 78.055978 -341.341964)
		(end 77.860144 -341.14613)
		(stroke
			(width 2.54)
			(type default)
		)
		(layer "In4.Cu")
	)
	(gr_line
		(start 78.055978 -210.285838)
		(end 78.055978 -210.191858)
		(stroke
			(width 2.54)
			(type default)
		)
		(layer "In4.Cu")
	)
	(gr_line
		(start 78.055978 -210.191858)
		(end 77.860144 -209.996024)
		(stroke
			(width 2.54)
			(type default)
		)
		(layer "In4.Cu")
	)
	(gr_line
		(start 78.056232 -121.385838)
		(end 78.056232 -121.291858)
		(stroke
			(width 2.54)
			(type default)
		)
		(layer "In4.Cu")
	)
	(gr_line
		(start 78.056232 -121.291858)
		(end 77.860398 -121.096024)
		(stroke
			(width 2.54)
			(type default)
		)
		(layer "In4.Cu")
	)
	(gr_line
		(start 78.143862 -478.809812)
		(end 78.143862 -478.216468)
		(stroke
			(width 2.032)
			(type default)
		)
		(layer "In4.Cu")
	)
	(gr_line
		(start 78.143862 -478.216468)
		(end 78.052676 -478.307654)
		(stroke
			(width 2.032)
			(type default)
		)
		(layer "In4.Cu")
	)
	(gr_line
		(start 78.919578 -479.471482)
		(end 77.003148 -479.471482)
		(stroke
			(width 2.032)
			(type default)
		)
		(layer "In4.Cu")
	)
	(gr_line
		(start 79.079344 -476.938848)
		(end 79.330296 -477.1898)
		(stroke
			(width 2.032)
			(type default)
		)
		(layer "In4.Cu")
	)
	(gr_line
		(start 79.330296 -479.060764)
		(end 78.919578 -479.471482)
		(stroke
			(width 2.032)
			(type default)
		)
		(layer "In4.Cu")
	)
	(gr_line
		(start 79.330296 -477.1898)
		(end 79.330296 -479.060764)
		(stroke
			(width 2.032)
			(type default)
		)
		(layer "In4.Cu")
	)
	(gr_line
		(start 80.599788 -478.799906)
		(end 80.599788 -477.799908)
		(stroke
			(width 2.032)
			(type default)
		)
		(layer "In4.Cu")
	)
	(gr_arc
		(start 80.599788 -477.799908)
		(mid 77.999844 -475.199964)
		(end 75.3999 -477.799908)
		(stroke
			(width 2.032)
			(type default)
		)
		(layer "In4.Cu")
	)
	(gr_line
		(start 101.000052 -529.999956)
		(end 26.500074 -529.999956)
		(stroke
			(width 0.2)
			(type default)
		)
		(layer "In4.Cu")
	)
	(gr_line
		(start 101.000052 -529.999956)
		(end 26.500074 -529.999956)
		(stroke
			(width 2.032)
			(type default)
		)
		(layer "In4.Cu")
	)
	(gr_arc
		(start 101.000052 -529.999956)
		(mid 102.41428 -529.414185)
		(end 103.000048 -527.99996)
		(stroke
			(width 0.2)
			(type default)
		)
		(layer "In4.Cu")
	)
	(gr_arc
		(start 101.000052 -529.999956)
		(mid 102.41428 -529.414185)
		(end 103.000048 -527.99996)
		(stroke
			(width 2.032)
			(type default)
		)
		(layer "In4.Cu")
	)
	(gr_arc
		(start 103.000048 -1.999996)
		(mid 102.414258 -0.585805)
		(end 101.000052 0)
		(stroke
			(width 0.2)
			(type default)
		)
		(layer "In4.Cu")
	)
	(gr_arc
		(start 103.000048 -1.999996)
		(mid 102.414258 -0.585805)
		(end 101.000052 0)
		(stroke
			(width 2.032)
			(type default)
		)
		(layer "In4.Cu")
	)
	(gr_line
		(start 103.000048 -1.999996)
		(end 103.000048 -527.99996)
		(stroke
			(width 0.2)
			(type default)
		)
		(layer "In4.Cu")
	)
	(gr_line
		(start 103.000048 -1.999996)
		(end 103.000048 -527.99996)
		(stroke
			(width 2.032)
			(type default)
		)
		(layer "In4.Cu")
	)
	(gr_poly
		(pts
			(xy 1.015492 -204.183996) (xy 0.894588 -204.063092) (xy 0.894588 -201.99731) (xy 1.015492 -201.876406)
			(xy 1.015492 -135.69442) (xy 0.509016 -135.69442) (xy 0.509016 -405.647906) (xy 1.015492 -405.647906)
		)
		(stroke
			(width 0)
			(type solid)
		)
		(fill yes)
		(layer "In5.Cu")
		(net "GND")
	)
	(gr_poly
		(pts
			(arc
				(start 25.625806 -198.531226)
				(mid 25.764027 -198.558639)
				(end 25.842468 -198.441564)
			)
			(arc
				(start 25.842468 -191.901064)
				(mid 25.764035 -191.783971)
				(end 25.625806 -191.811402)
			)
			(xy 25.479248 -191.957706) (xy 25.479248 -198.384922)
		)
		(stroke
			(width 0)
			(type solid)
		)
		(fill yes)
		(layer "In5.Cu")
		(net "GND")
	)
	(gr_poly
		(pts
			(arc
				(start 7.079742 -335.172812)
				(mid 7.314647 -335.016048)
				(end 7.259574 -334.73898)
			)
			(xy 6.632448 -334.112108)
			(arc
				(start 5.9817 -334.112108)
				(mid 5.891897 -334.149305)
				(end 5.8547 -334.239108)
			)
			(xy 5.8547 -334.6196) (xy 6.407658 -335.172812)
		)
		(stroke
			(width 0)
			(type solid)
		)
		(fill yes)
		(layer "In5.Cu")
		(net "GND")
	)
	(gr_poly
		(pts
			(arc
				(start 8.319008 -63.147956)
				(mid 8.397441 -63.265049)
				(end 8.53567 -63.237618)
			)
			(xy 8.938768 -62.834774) (xy 8.938768 -61.028326)
			(arc
				(start 9.544812 -60.422028)
				(mid 9.581951 -60.332276)
				(end 9.544812 -60.24245)
			)
			(xy 9.514586 -60.212224)
			(arc
				(start 9.472422 -60.206382)
				(mid 9.406036 -60.194475)
				(end 9.34085 -60.177172)
			)
			(xy 9.307068 -60.166758) (xy 9.238488 -60.183776) (xy 7.60984 -61.81217) (xy 7.60984 -62.233048)
			(xy 8.319008 -62.941962)
		)
		(stroke
			(width 0)
			(type solid)
		)
		(fill yes)
		(layer "In5.Cu")
		(net "GND")
	)
	(gr_poly
		(pts
			(arc
				(start 9.635998 -226.67595)
				(mid 9.691202 -226.398828)
				(end 9.456166 -226.242118)
			)
			(xy 8.326628 -226.242118)
			(arc
				(start 7.916164 -226.652582)
				(mid 7.86096 -226.929704)
				(end 8.095996 -227.086414)
			)
			(xy 9.225534 -227.086414)
		)
		(stroke
			(width 0)
			(type solid)
		)
		(fill yes)
		(layer "In5.Cu")
		(net "GND")
	)
	(gr_poly
		(pts
			(arc
				(start 15.743174 -329.781916)
				(mid 16.020296 -329.83712)
				(end 16.177006 -329.602084)
			)
			(xy 16.176752 -322.701412)
			(arc
				(start 16.119094 -322.6435)
				(mid 15.842212 -322.588497)
				(end 15.685516 -322.823332)
			)
			(xy 15.685516 -329.724004)
		)
		(stroke
			(width 0)
			(type solid)
		)
		(fill yes)
		(layer "In5.Cu")
		(net "GND")
	)
	(gr_poly
		(pts
			(arc
				(start 74.65314 -353.473004)
				(mid 74.888011 -353.316323)
				(end 74.832972 -353.039426)
			)
			(xy 74.437748 -352.644456) (xy 67.458844 -352.644456)
			(arc
				(start 67.06362 -353.039426)
				(mid 67.008617 -353.316308)
				(end 67.243452 -353.473004)
			)
		)
		(stroke
			(width 0)
			(type solid)
		)
		(fill yes)
		(layer "In5.Cu")
		(net "GND")
	)
	(gr_poly
		(pts
			(arc
				(start 9.434068 -194.64782)
				(mid 9.489272 -194.370698)
				(end 9.254236 -194.213988)
			)
			(xy 8.310372 -194.213988) (xy 7.43331 -195.091304)
			(arc
				(start 7.06247 -195.091304)
				(mid 6.949129 -195.161008)
				(end 6.960362 -195.293488)
			)
			(arc
				(start 6.964934 -195.299838)
				(mid 7.010074 -195.338878)
				(end 7.068058 -195.352924)
			)
			(xy 8.728964 -195.352924)
		)
		(stroke
			(width 0)
			(type solid)
		)
		(fill yes)
		(layer "In5.Cu")
		(net "GND")
	)
	(gr_poly
		(pts
			(arc
				(start 7.038594 -278.430736)
				(mid 7.223588 -278.583915)
				(end 7.45363 -278.514556)
			)
			(xy 7.781544 -278.186896) (xy 9.196578 -278.186896) (xy 10.024364 -277.358856)
			(arc
				(start 10.024364 -277.26132)
				(mid 9.987151 -277.171607)
				(end 9.897364 -277.13432)
			)
			(xy 8.151876 -277.13432)
			(arc
				(start 7.20979 -278.076406)
				(mid 7.042475 -278.208968)
				(end 7.035292 -278.422354)
			)
		)
		(stroke
			(width 0)
			(type solid)
		)
		(fill yes)
		(layer "In5.Cu")
		(net "GND")
	)
	(gr_poly
		(pts
			(xy 7.624318 -255.268476)
			(arc
				(start 7.849108 -255.268476)
				(mid 7.96334 -255.196973)
				(end 7.94893 -255.06299)
			)
			(arc
				(start 7.94893 -255.06299)
				(mid 7.903239 -254.996408)
				(end 7.86638 -254.92456)
			)
			(arc
				(start 7.86638 -254.92456)
				(mid 7.680714 -254.776479)
				(end 7.453884 -254.846582)
			)
			(xy 7.052056 -255.248156) (xy 5.941314 -255.248156) (xy 5.884672 -255.305052)
			(arc
				(start 5.884672 -256.111756)
				(mid 5.92178 -256.201723)
				(end 6.011672 -256.238756)
			)
			(xy 6.653784 -256.238756)
		)
		(stroke
			(width 0)
			(type solid)
		)
		(fill yes)
		(layer "In5.Cu")
		(net "GND")
	)
	(gr_poly
		(pts
			(arc
				(start 7.035292 -237.425484)
				(mid 7.220398 -237.576876)
				(end 7.449058 -237.507272)
			)
			(xy 7.710424 -237.24616) (xy 18.405602 -237.24616) (xy 19.741388 -235.91012)
			(arc
				(start 19.741388 -235.597446)
				(mid 19.584707 -235.362575)
				(end 19.30781 -235.417614)
			)
			(xy 18.51025 -236.215428) (xy 8.168132 -236.215428) (xy 7.15518 -237.22838)
			(arc
				(start 7.142988 -237.22838)
				(mid 7.053185 -237.265577)
				(end 7.015988 -237.35538)
			)
			(xy 7.015988 -237.382812) (xy 7.027418 -237.407704)
		)
		(stroke
			(width 0)
			(type solid)
		)
		(fill yes)
		(layer "In5.Cu")
		(net "GND")
	)
	(gr_poly
		(pts
			(arc
				(start 7.89686 -221.172278)
				(mid 7.933443 -221.096016)
				(end 7.913878 -221.013782)
			)
			(arc
				(start 7.913878 -221.013782)
				(mid 7.878459 -220.950941)
				(end 7.850378 -220.884496)
			)
			(arc
				(start 7.850378 -220.884496)
				(mid 7.666892 -220.722007)
				(end 7.431532 -220.790262)
			)
			(xy 7.033514 -221.18828) (xy 4.880864 -221.18828)
			(arc
				(start 4.611624 -221.45752)
				(mid 4.580473 -221.50834)
				(end 4.576064 -221.567756)
			)
			(arc
				(start 4.576064 -221.567756)
				(mid 4.58412 -221.69095)
				(end 4.56819 -221.813374)
			)
			(arc
				(start 4.56819 -221.813374)
				(mid 4.616941 -222.028751)
				(end 4.81584 -222.124524)
			)
			(xy 6.944868 -222.124524)
		)
		(stroke
			(width 0)
			(type solid)
		)
		(fill yes)
		(layer "In5.Cu")
		(net "GND")
	)
	(gr_poly
		(pts
			(xy 7.841742 -292.28034)
			(arc
				(start 7.860284 -292.28034)
				(mid 7.9753 -292.207735)
				(end 7.958582 -292.072822)
			)
			(arc
				(start 7.958582 -292.072822)
				(mid 7.915094 -292.013168)
				(end 7.878826 -291.94887)
			)
			(arc
				(start 7.878826 -291.94887)
				(mid 7.692523 -291.80995)
				(end 7.471156 -291.880798)
			)
			(xy 7.229856 -292.121844) (xy 4.947412 -292.121844)
			(arc
				(start 4.61264 -292.45687)
				(mid 4.581489 -292.50769)
				(end 4.57708 -292.567106)
			)
			(arc
				(start 4.57708 -292.567106)
				(mid 4.585394 -292.663938)
				(end 4.578858 -292.760908)
			)
			(arc
				(start 4.578858 -292.760908)
				(mid 4.638141 -292.96373)
				(end 4.830318 -293.051484)
			)
			(xy 7.070852 -293.051484)
		)
		(stroke
			(width 0)
			(type solid)
		)
		(fill yes)
		(layer "In5.Cu")
		(net "GND")
	)
	(gr_poly
		(pts
			(arc
				(start 51.014376 -351.637092)
				(mid 51.239572 -351.500576)
				(end 51.222656 -351.237804)
			)
			(arc
				(start 51.222656 -351.237804)
				(mid 51.07476 -350.794958)
				(end 51.190652 -350.342708)
			)
			(arc
				(start 51.190652 -350.342708)
				(mid 51.193317 -350.087191)
				(end 50.972466 -349.95866)
			)
			(xy 46.388528 -349.95866)
			(arc
				(start 45.143928 -351.20326)
				(mid 45.088724 -351.480382)
				(end 45.32376 -351.637092)
			)
		)
		(stroke
			(width 0)
			(type solid)
		)
		(fill yes)
		(layer "In5.Cu")
		(net "GND")
	)
	(gr_poly
		(pts
			(arc
				(start 4.412488 -191.235584)
				(mid 4.593687 -191.315989)
				(end 4.777486 -191.24168)
			)
			(xy 5.939536 -190.079376) (xy 6.967982 -190.079376)
			(arc
				(start 7.888478 -189.15888)
				(mid 7.924906 -189.083984)
				(end 7.90702 -189.00267)
			)
			(arc
				(start 7.90702 -189.00267)
				(mid 7.86677 -188.925555)
				(end 7.837424 -188.843666)
			)
			(arc
				(start 7.837424 -188.843666)
				(mid 7.65695 -188.666805)
				(end 7.413244 -188.733176)
			)
			(xy 7.070852 -189.075568) (xy 6.385814 -189.075568) (xy 4.687316 -190.77432) (xy 3.880104 -190.77432)
			(arc
				(start 3.835908 -190.818516)
				(mid 3.798664 -190.908342)
				(end 3.835908 -190.998094)
			)
			(xy 3.854704 -191.01689) (xy 3.903218 -191.03594)
			(arc
				(start 3.929634 -191.035178)
				(mid 4.192609 -191.083453)
				(end 4.412488 -191.235584)
			)
		)
		(stroke
			(width 0)
			(type solid)
		)
		(fill yes)
		(layer "In5.Cu")
		(net "GND")
	)
	(gr_poly
		(pts
			(arc
				(start 24.702262 -190.8048)
				(mid 24.876463 -191.00182)
				(end 25.131776 -190.938912)
			)
			(xy 25.5524 -190.518288) (xy 25.5524 -181.353968)
			(arc
				(start 28.788614 -178.118008)
				(mid 28.843818 -177.840886)
				(end 28.608782 -177.684176)
			)
			(xy 28.212288 -177.684176) (xy 23.8125 -182.083964)
			(arc
				(start 23.8125 -190.293244)
				(mid 23.92844 -190.506701)
				(end 24.17064 -190.525146)
			)
			(arc
				(start 24.17064 -190.525146)
				(mid 24.504479 -190.535576)
				(end 24.702262 -190.8048)
			)
		)
		(stroke
			(width 0)
			(type solid)
		)
		(fill yes)
		(layer "In5.Cu")
		(net "GND")
	)
	(gr_poly
		(pts
			(arc
				(start 19.14652 -372.496842)
				(mid 19.423642 -372.552046)
				(end 19.580352 -372.31701)
			)
			(xy 19.580352 -351.589594) (xy 19.258788 -351.268284) (xy 19.258788 -335.25333) (xy 18.408396 -334.402684)
			(xy 18.408396 -333.77124) (xy 19.258788 -332.920594) (xy 19.258788 -325.10349)
			(arc
				(start 17.246346 -323.090794)
				(mid 16.969464 -323.035791)
				(end 16.812768 -323.270626)
			)
			(arc
				(start 16.812768 -331.56017)
				(mid 16.901094 -331.752955)
				(end 17.104868 -331.811376)
			)
			(arc
				(start 17.104868 -331.811376)
				(mid 17.543805 -332.188566)
				(end 17.104868 -332.565756)
			)
			(arc
				(start 17.104868 -332.565756)
				(mid 16.901206 -332.624308)
				(end 16.812768 -332.816962)
			)
			(xy 16.812768 -370.162836)
		)
		(stroke
			(width 0)
			(type solid)
		)
		(fill yes)
		(layer "In5.Cu")
		(net "GND")
	)
	(gr_poly
		(pts
			(arc
				(start 12.444222 -497.91874)
				(mid 12.662351 -497.794877)
				(end 12.667742 -497.54409)
			)
			(arc
				(start 12.667742 -497.54409)
				(mid 12.572628 -497.232344)
				(end 12.605512 -496.908074)
			)
			(xy 12.615926 -496.874292) (xy 12.598908 -496.805712) (xy 10.34542 -494.552224) (xy 10.34542 -493.83696)
			(arc
				(start 8.560308 -492.051594)
				(mid 8.283186 -491.99639)
				(end 8.126476 -492.231426)
			)
			(xy 8.126476 -492.66094) (xy 8.838692 -493.372902) (xy 8.838692 -494.686336)
			(arc
				(start 10.483596 -496.33124)
				(mid 10.542845 -496.364609)
				(end 10.61085 -496.362736)
			)
			(arc
				(start 10.61085 -496.362736)
				(mid 11.492851 -496.627499)
				(end 11.581638 -497.54409)
			)
			(arc
				(start 11.581638 -497.54409)
				(mid 11.587026 -497.794879)
				(end 11.805158 -497.91874)
			)
		)
		(stroke
			(width 0)
			(type solid)
		)
		(fill yes)
		(layer "In5.Cu")
		(net "GND")
	)
	(gr_poly
		(pts
			(arc
				(start 15.515844 -264.800588)
				(mid 15.750749 -264.643824)
				(end 15.695676 -264.366756)
			)
			(arc
				(start 8.661908 -257.333242)
				(mid 8.611088 -257.302091)
				(end 8.551672 -257.297682)
			)
			(arc
				(start 8.551672 -257.297682)
				(mid 8.145219 -257.228863)
				(end 7.866634 -256.925064)
			)
			(arc
				(start 7.866634 -256.925064)
				(mid 7.680945 -256.777318)
				(end 7.454138 -256.84734)
			)
			(xy 7.01929 -257.282188) (xy 7.005574 -257.361436)
			(arc
				(start 7.022846 -257.398012)
				(mid 7.078012 -257.581666)
				(end 7.075932 -257.773424)
			)
			(xy 7.070852 -257.80365) (xy 7.089648 -257.861816) (xy 7.83082 -258.603242)
			(arc
				(start 7.83082 -259.858764)
				(mid 7.94676 -260.072221)
				(end 8.18896 -260.090666)
			)
			(arc
				(start 8.18896 -260.090666)
				(mid 8.836417 -260.167025)
				(end 9.075928 -260.773418)
			)
			(xy 9.070848 -260.803644) (xy 9.089644 -260.86181) (xy 13.028168 -264.800588)
		)
		(stroke
			(width 0)
			(type solid)
		)
		(fill yes)
		(layer "In5.Cu")
		(net "GND")
	)
	(gr_poly
		(pts
			(arc
				(start 52.213764 -263.038336)
				(mid 52.432215 -262.913933)
				(end 52.436522 -262.66267)
			)
			(arc
				(start 52.436522 -262.66267)
				(mid 52.348189 -262.119949)
				(end 52.620164 -261.642098)
			)
			(arc
				(start 52.620164 -261.642098)
				(mid 52.691508 -261.361387)
				(end 52.45354 -261.196328)
			)
			(xy 48.649636 -261.196328) (xy 47.977298 -261.868412)
			(arc
				(start 45.197014 -261.868412)
				(mid 45.025121 -261.935412)
				(end 44.94403 -262.101076)
			)
			(arc
				(start 44.94403 -262.101076)
				(mid 44.563792 -262.450189)
				(end 44.183554 -262.101076)
			)
			(arc
				(start 44.183554 -262.101076)
				(mid 44.102383 -261.935499)
				(end 43.93057 -261.868412)
			)
			(arc
				(start 17.746218 -261.868412)
				(mid 17.511313 -262.025176)
				(end 17.566386 -262.302244)
			)
			(xy 18.302732 -263.038336)
		)
		(stroke
			(width 0)
			(type solid)
		)
		(fill yes)
		(layer "In5.Cu")
		(net "GND")
	)
	(gr_poly
		(pts
			(xy 19.16176 -324.107302) (xy 19.178701 -324.122421) (xy 19.216873 -324.146998) (xy 19.258805 -324.164402)
			(xy 19.303163 -324.174077) (xy 19.348534 -324.175717) (xy 19.393474 -324.169268) (xy 19.436553 -324.154936)
			(xy 19.476399 -324.133177) (xy 19.511745 -324.104683) (xy 19.541466 -324.070363) (xy 19.564614 -324.031307)
			(xy 19.580455 -323.98876) (xy 19.588482 -323.944075) (xy 19.588988 -323.921374) (xy 19.588988 -320.570098)
			(xy 12.208002 -313.189112) (xy 9.309862 -313.189112) (xy 9.286869 -313.189611) (xy 9.241633 -313.197889)
			(xy 9.198624 -313.214168) (xy 9.159245 -313.237918) (xy 9.124779 -313.268363) (xy 9.096352 -313.30451)
			(xy 9.074889 -313.345181) (xy 9.061092 -313.389049) (xy 9.05541 -313.434684) (xy 9.058028 -313.480596)
			(xy 9.062974 -313.503056) (xy 9.071479 -313.53601) (xy 9.082232 -313.603218) (xy 9.085752 -313.671189)
			(xy 9.081999 -313.739148) (xy 9.076944 -313.772804) (xy 9.074962 -313.78773) (xy 9.077247 -313.817746)
			(xy 9.086487 -313.846395) (xy 9.102169 -313.87209) (xy 9.112504 -313.88304) (xy 9.925812 -314.696348)
			(xy 12.175996 -314.696348) (xy 12.180067 -314.640726) (xy 12.192193 -314.586289) (xy 12.212116 -314.534198)
			(xy 12.239412 -314.485563) (xy 12.273498 -314.44142) (xy 12.313647 -314.402711) (xy 12.359005 -314.37026)
			(xy 12.408605 -314.344759) (xy 12.461389 -314.326752) (xy 12.516232 -314.316622) (xy 12.571966 -314.314585)
			(xy 12.627403 -314.320685) (xy 12.68136 -314.334791) (xy 12.732689 -314.356603) (xy 12.780295 -314.385657)
			(xy 12.823163 -314.421332) (xy 12.86038 -314.462869) (xy 12.891153 -314.509382) (xy 12.914825 -314.559879)
			(xy 12.930893 -314.613286) (xy 12.939013 -314.668462) (xy 12.939522 -314.696348) (xy 12.939013 -314.724234)
			(xy 12.930893 -314.77941) (xy 12.914825 -314.832817) (xy 12.891153 -314.883314) (xy 12.86038 -314.929827)
			(xy 12.823163 -314.971364) (xy 12.780295 -315.007039) (xy 12.732689 -315.036093) (xy 12.68136 -315.057905)
			(xy 12.627403 -315.072011) (xy 12.571966 -315.078111) (xy 12.516232 -315.076074) (xy 12.461389 -315.065944)
			(xy 12.408605 -315.047937) (xy 12.359005 -315.022436) (xy 12.313647 -314.989985) (xy 12.273498 -314.951276)
			(xy 12.239412 -314.907133) (xy 12.212116 -314.858498) (xy 12.192193 -314.806407) (xy 12.180067 -314.75197)
			(xy 12.175996 -314.696348) (xy 9.925812 -314.696348) (xy 12.115292 -316.885828) (xy 12.115292 -317.060834)
			(xy 14.31544 -319.260982) (xy 14.331512 -319.27643) (xy 14.368021 -319.302004) (xy 14.408432 -319.320815)
			(xy 14.451505 -319.332285) (xy 14.49592 -319.336064) (xy 14.540312 -319.332034) (xy 14.58332 -319.32032)
			(xy 14.623624 -319.301281) (xy 14.659987 -319.275501) (xy 14.691294 -319.243771) (xy 14.704314 -319.225676)
			(xy 14.720555 -319.20303) (xy 14.758538 -319.162253) (xy 14.802051 -319.127437) (xy 14.850166 -319.099323)
			(xy 14.90186 -319.078508) (xy 14.956033 -319.065438) (xy 15.01153 -319.060388) (xy 15.067172 -319.063468)
			(xy 15.121774 -319.07461) (xy 15.174173 -319.093579) (xy 15.223254 -319.119971) (xy 15.267973 -319.153223)
			(xy 15.307378 -319.192627) (xy 15.34063 -319.237347) (xy 15.367021 -319.286428) (xy 15.38599 -319.338827)
			(xy 15.397133 -319.393429) (xy 15.400212 -319.449071) (xy 15.395162 -319.504568) (xy 15.382091 -319.558741)
			(xy 15.361277 -319.610435) (xy 15.333163 -319.65855) (xy 15.298347 -319.702062) (xy 15.25757 -319.740046)
			(xy 15.23492 -319.756282) (xy 15.216856 -319.769325) (xy 15.185175 -319.800649) (xy 15.159438 -319.837015)
			(xy 15.140431 -319.87731) (xy 15.128737 -319.9203) (xy 15.124713 -319.96467) (xy 15.128482 -320.009062)
			(xy 15.13993 -320.052118) (xy 15.158705 -320.092521) (xy 15.184233 -320.129034) (xy 15.199614 -320.145156)
		)
		(stroke
			(width 0)
			(type solid)
		)
		(fill yes)
		(layer "In5.Cu")
		(net "GND")
	)
	(gr_poly
		(pts
			(xy 12.28344 -174.9171) (xy 12.283914 -174.940147) (xy 12.292174 -174.985493) (xy 12.308477 -175.028606)
			(xy 12.332289 -175.068071) (xy 12.362828 -175.102595) (xy 12.399093 -175.131044) (xy 12.439895 -175.152485)
			(xy 12.483894 -175.166216) (xy 12.529649 -175.171786) (xy 12.575658 -175.169012) (xy 12.620412 -175.157986)
			(xy 12.662443 -175.139068) (xy 12.700373 -175.112879) (xy 12.717018 -175.096932) (xy 21.964396 -165.849554)
			(xy 21.964396 -162.925252) (xy 21.963891 -162.902206) (xy 21.955574 -162.856871) (xy 21.939221 -162.813778)
			(xy 21.915367 -162.774339) (xy 21.884795 -162.739846) (xy 21.848506 -162.711429) (xy 21.807688 -162.690019)
			(xy 21.76368 -162.676317) (xy 21.717923 -162.670774) (xy 21.671917 -162.673569) (xy 21.627167 -162.684612)
			(xy 21.585142 -162.703541) (xy 21.547217 -162.729735) (xy 21.530564 -162.745674) (xy 13.903915 -170.372532)
			(xy 14.663926 -170.372532) (xy 14.667997 -170.31691) (xy 14.680123 -170.262473) (xy 14.700046 -170.210382)
			(xy 14.727342 -170.161747) (xy 14.761428 -170.117604) (xy 14.801577 -170.078895) (xy 14.846935 -170.046444)
			(xy 14.896535 -170.020943) (xy 14.949319 -170.002936) (xy 15.004162 -169.992806) (xy 15.059896 -169.990769)
			(xy 15.115333 -169.996869) (xy 15.16929 -170.010975) (xy 15.220619 -170.032787) (xy 15.268225 -170.061841)
			(xy 15.311093 -170.097516) (xy 15.34831 -170.139053) (xy 15.379083 -170.185566) (xy 15.402755 -170.236063)
			(xy 15.418823 -170.28947) (xy 15.426943 -170.344646) (xy 15.427452 -170.372532) (xy 15.426943 -170.400418)
			(xy 15.418823 -170.455594) (xy 15.402755 -170.509001) (xy 15.379083 -170.559498) (xy 15.34831 -170.606011)
			(xy 15.311093 -170.647548) (xy 15.268225 -170.683223) (xy 15.220619 -170.712277) (xy 15.16929 -170.734089)
			(xy 15.115333 -170.748195) (xy 15.059896 -170.754295) (xy 15.004162 -170.752258) (xy 14.949319 -170.742128)
			(xy 14.896535 -170.724121) (xy 14.846935 -170.69862) (xy 14.801577 -170.666169) (xy 14.761428 -170.62746)
			(xy 14.727342 -170.583317) (xy 14.700046 -170.534682) (xy 14.680123 -170.482591) (xy 14.667997 -170.428154)
			(xy 14.663926 -170.372532) (xy 13.903915 -170.372532) (xy 12.743421 -171.533058) (xy 14.127478 -171.533058)
			(xy 14.131549 -171.477436) (xy 14.143675 -171.422999) (xy 14.163598 -171.370908) (xy 14.190894 -171.322273)
			(xy 14.22498 -171.27813) (xy 14.265129 -171.239421) (xy 14.310487 -171.20697) (xy 14.360087 -171.181469)
			(xy 14.412871 -171.163462) (xy 14.467714 -171.153332) (xy 14.523448 -171.151295) (xy 14.578885 -171.157395)
			(xy 14.632842 -171.171501) (xy 14.684171 -171.193313) (xy 14.731777 -171.222367) (xy 14.774645 -171.258042)
			(xy 14.811862 -171.299579) (xy 14.842635 -171.346092) (xy 14.866307 -171.396589) (xy 14.882375 -171.449996)
			(xy 14.890495 -171.505172) (xy 14.891004 -171.533058) (xy 14.890495 -171.560944) (xy 14.882375 -171.61612)
			(xy 14.866307 -171.669527) (xy 14.842635 -171.720024) (xy 14.811862 -171.766537) (xy 14.774645 -171.808074)
			(xy 14.731777 -171.843749) (xy 14.684171 -171.872803) (xy 14.632842 -171.894615) (xy 14.578885 -171.908721)
			(xy 14.523448 -171.914821) (xy 14.467714 -171.912784) (xy 14.412871 -171.902654) (xy 14.360087 -171.884647)
			(xy 14.310487 -171.859146) (xy 14.265129 -171.826695) (xy 14.22498 -171.787986) (xy 14.190894 -171.743843)
			(xy 14.163598 -171.695208) (xy 14.143675 -171.643117) (xy 14.131549 -171.58868) (xy 14.127478 -171.533058)
			(xy 12.743421 -171.533058) (xy 12.28344 -171.993052) (xy 12.28344 -172.67174) (xy 13.456664 -172.67174)
			(xy 13.460735 -172.616118) (xy 13.472861 -172.561681) (xy 13.492784 -172.50959) (xy 13.52008 -172.460955)
			(xy 13.554166 -172.416812) (xy 13.594315 -172.378103) (xy 13.639673 -172.345652) (xy 13.689273 -172.320151)
			(xy 13.742057 -172.302144) (xy 13.7969 -172.292014) (xy 13.852634 -172.289977) (xy 13.908071 -172.296077)
			(xy 13.962028 -172.310183) (xy 14.013357 -172.331995) (xy 14.060963 -172.361049) (xy 14.103831 -172.396724)
			(xy 14.141048 -172.438261) (xy 14.171821 -172.484774) (xy 14.195493 -172.535271) (xy 14.211561 -172.588678)
			(xy 14.219681 -172.643854) (xy 14.22019 -172.67174) (xy 14.219681 -172.699626) (xy 14.211561 -172.754802)
			(xy 14.195493 -172.808209) (xy 14.171821 -172.858706) (xy 14.141048 -172.905219) (xy 14.103831 -172.946756)
			(xy 14.060963 -172.982431) (xy 14.013357 -173.011485) (xy 13.962028 -173.033297) (xy 13.908071 -173.047403)
			(xy 13.852634 -173.053503) (xy 13.7969 -173.051466) (xy 13.742057 -173.041336) (xy 13.689273 -173.023329)
			(xy 13.639673 -172.997828) (xy 13.594315 -172.965377) (xy 13.554166 -172.926668) (xy 13.52008 -172.882525)
			(xy 13.492784 -172.83389) (xy 13.472861 -172.781799) (xy 13.460735 -172.727362) (xy 13.456664 -172.67174)
			(xy 12.28344 -172.67174)
		)
		(stroke
			(width 0)
			(type solid)
		)
		(fill yes)
		(layer "In5.Cu")
		(net "GND")
	)
	(gr_poly
		(pts
			(xy 17.192752 -409.915868) (xy 17.193241 -409.938922) (xy 17.20153 -409.984279) (xy 17.217861 -410.027398)
			(xy 17.241699 -410.066866) (xy 17.272261 -410.10139) (xy 17.308547 -410.129838) (xy 17.349367 -410.151278)
			(xy 17.393384 -410.165007) (xy 17.439154 -410.170575) (xy 17.485179 -410.1678) (xy 17.529949 -410.156772)
			(xy 17.571997 -410.137854) (xy 17.609945 -410.111664) (xy 17.626584 -410.0957) (xy 18.501868 -409.220162)
			(xy 18.501868 -400.169888) (xy 11.96848 -393.636246) (xy 11.951833 -393.62028) (xy 11.913894 -393.594052)
			(xy 11.871846 -393.575101) (xy 11.827068 -393.564047) (xy 11.781031 -393.561255) (xy 11.735246 -393.566815)
			(xy 11.691216 -393.580545) (xy 11.650385 -393.601994) (xy 11.614095 -393.630459) (xy 11.583537 -393.665004)
			(xy 11.559713 -393.704497) (xy 11.543406 -393.747639) (xy 11.535152 -393.793016) (xy 11.534648 -393.816078)
			(xy 11.534648 -399.279927) (xy 12.292327 -399.279927) (xy 12.292327 -399.200061) (xy 12.300407 -399.120606)
			(xy 12.316484 -399.042376) (xy 12.340393 -398.966174) (xy 12.371888 -398.892781) (xy 12.410647 -398.822951)
			(xy 12.456271 -398.757401) (xy 12.508293 -398.696802) (xy 12.566178 -398.641778) (xy 12.629334 -398.592892)
			(xy 12.697111 -398.550646) (xy 12.768814 -398.515474) (xy 12.843708 -398.487737) (xy 12.921023 -398.467718)
			(xy 12.999967 -398.455625) (xy 13.07973 -398.45158) (xy 13.159493 -398.455625) (xy 13.238437 -398.467718)
			(xy 13.315752 -398.487737) (xy 13.390646 -398.515474) (xy 13.462349 -398.550646) (xy 13.530126 -398.592892)
			(xy 13.593282 -398.641778) (xy 13.651167 -398.696802) (xy 13.703189 -398.757401) (xy 13.748813 -398.822951)
			(xy 13.787572 -398.892781) (xy 13.819067 -398.966174) (xy 13.842976 -399.042376) (xy 13.859053 -399.120606)
			(xy 13.867133 -399.200061) (xy 13.867638 -399.239994) (xy 13.867133 -399.279927) (xy 14.782289 -399.279927)
			(xy 14.782289 -399.200061) (xy 14.790369 -399.120606) (xy 14.806446 -399.042376) (xy 14.830355 -398.966174)
			(xy 14.86185 -398.892781) (xy 14.900609 -398.822951) (xy 14.946233 -398.757401) (xy 14.998255 -398.696802)
			(xy 15.05614 -398.641778) (xy 15.119296 -398.592892) (xy 15.187073 -398.550646) (xy 15.258776 -398.515474)
			(xy 15.33367 -398.487737) (xy 15.410985 -398.467718) (xy 15.489929 -398.455625) (xy 15.569692 -398.45158)
			(xy 15.649455 -398.455625) (xy 15.728399 -398.467718) (xy 15.805714 -398.487737) (xy 15.880608 -398.515474)
			(xy 15.952311 -398.550646) (xy 16.020088 -398.592892) (xy 16.083244 -398.641778) (xy 16.141129 -398.696802)
			(xy 16.193151 -398.757401) (xy 16.238775 -398.822951) (xy 16.277534 -398.892781) (xy 16.309029 -398.966174)
			(xy 16.332938 -399.042376) (xy 16.349015 -399.120606) (xy 16.357095 -399.200061) (xy 16.3576 -399.239994)
			(xy 16.357095 -399.279927) (xy 16.349015 -399.359382) (xy 16.332938 -399.437612) (xy 16.309029 -399.513814)
			(xy 16.277534 -399.587207) (xy 16.238775 -399.657037) (xy 16.193151 -399.722587) (xy 16.141129 -399.783186)
			(xy 16.083244 -399.83821) (xy 16.020088 -399.887096) (xy 15.952311 -399.929342) (xy 15.880608 -399.964514)
			(xy 15.805714 -399.992251) (xy 15.728399 -400.01227) (xy 15.649455 -400.024363) (xy 15.569692 -400.028409)
			(xy 15.489929 -400.024363) (xy 15.410985 -400.01227) (xy 15.33367 -399.992251) (xy 15.258776 -399.964514)
			(xy 15.187073 -399.929342) (xy 15.119296 -399.887096) (xy 15.05614 -399.83821) (xy 14.998255 -399.783186)
			(xy 14.946233 -399.722587) (xy 14.900609 -399.657037) (xy 14.86185 -399.587207) (xy 14.830355 -399.513814)
			(xy 14.806446 -399.437612) (xy 14.790369 -399.359382) (xy 14.782289 -399.279927) (xy 13.867133 -399.279927)
			(xy 13.859053 -399.359382) (xy 13.842976 -399.437612) (xy 13.819067 -399.513814) (xy 13.787572 -399.587207)
			(xy 13.748813 -399.657037) (xy 13.703189 -399.722587) (xy 13.651167 -399.783186) (xy 13.593282 -399.83821)
			(xy 13.530126 -399.887096) (xy 13.462349 -399.929342) (xy 13.390646 -399.964514) (xy 13.315752 -399.992251)
			(xy 13.238437 -400.01227) (xy 13.159493 -400.024363) (xy 13.07973 -400.028409) (xy 12.999967 -400.024363)
			(xy 12.921023 -400.01227) (xy 12.843708 -399.992251) (xy 12.768814 -399.964514) (xy 12.697111 -399.929342)
			(xy 12.629334 -399.887096) (xy 12.566178 -399.83821) (xy 12.508293 -399.783186) (xy 12.456271 -399.722587)
			(xy 12.410647 -399.657037) (xy 12.371888 -399.587207) (xy 12.340393 -399.513814) (xy 12.316484 -399.437612)
			(xy 12.300407 -399.359382) (xy 12.292327 -399.279927) (xy 11.534648 -399.279927) (xy 11.534648 -403.413036)
			(xy 12.977863 -403.413036) (xy 12.977863 -403.2869) (xy 12.985783 -403.161012) (xy 13.001593 -403.03587)
			(xy 13.025228 -402.911967) (xy 13.056597 -402.789794) (xy 13.095575 -402.669831) (xy 13.142009 -402.552552)
			(xy 13.195716 -402.43842) (xy 13.256483 -402.327885) (xy 13.32407 -402.221385) (xy 13.398211 -402.119338)
			(xy 13.478614 -402.022148) (xy 13.56496 -401.930198) (xy 13.65691 -401.843852) (xy 13.7541 -401.763449)
			(xy 13.856147 -401.689308) (xy 13.962647 -401.621721) (xy 14.073182 -401.560954) (xy 14.187314 -401.507247)
			(xy 14.304593 -401.460813) (xy 14.424556 -401.421835) (xy 14.546729 -401.390466) (xy 14.670632 -401.366831)
			(xy 14.795774 -401.351021) (xy 14.921662 -401.343101) (xy 15.047798 -401.343101) (xy 15.173686 -401.351021)
			(xy 15.298828 -401.366831) (xy 15.422731 -401.390466) (xy 15.544904 -401.421835) (xy 15.664867 -401.460813)
			(xy 15.782146 -401.507247) (xy 15.896278 -401.560954) (xy 16.006813 -401.621721) (xy 16.113313 -401.689308)
			(xy 16.21536 -401.763449) (xy 16.31255 -401.843852) (xy 16.4045 -401.930198) (xy 16.490846 -402.022148)
			(xy 16.571249 -402.119338) (xy 16.64539 -402.221385) (xy 16.712977 -402.327885) (xy 16.773744 -402.43842)
			(xy 16.827451 -402.552552) (xy 16.873885 -402.669831) (xy 16.912863 -402.789794) (xy 16.944232 -402.911967)
			(xy 16.967867 -403.03587) (xy 16.983677 -403.161012) (xy 16.991597 -403.2869) (xy 16.992092 -403.349968)
			(xy 16.991597 -403.413036) (xy 16.983677 -403.538924) (xy 16.967867 -403.664066) (xy 16.944232 -403.787969)
			(xy 16.912863 -403.910142) (xy 16.873885 -404.030105) (xy 16.827451 -404.147384) (xy 16.773744 -404.261516)
			(xy 16.712977 -404.372051) (xy 16.64539 -404.478551) (xy 16.571249 -404.580598) (xy 16.490846 -404.677788)
			(xy 16.4045 -404.769738) (xy 16.31255 -404.856084) (xy 16.21536 -404.936487) (xy 16.113313 -405.010628)
			(xy 16.006813 -405.078215) (xy 15.896278 -405.138982) (xy 15.782146 -405.192689) (xy 15.664867 -405.239123)
			(xy 15.544904 -405.278101) (xy 15.422731 -405.30947) (xy 15.298828 -405.333105) (xy 15.173686 -405.348915)
			(xy 15.047798 -405.356835) (xy 14.921662 -405.356835) (xy 14.795774 -405.348915) (xy 14.670632 -405.333105)
			(xy 14.546729 -405.30947) (xy 14.424556 -405.278101) (xy 14.304593 -405.239123) (xy 14.187314 -405.192689)
			(xy 14.073182 -405.138982) (xy 13.962647 -405.078215) (xy 13.856147 -405.010628) (xy 13.7541 -404.936487)
			(xy 13.65691 -404.856084) (xy 13.56496 -404.769738) (xy 13.478614 -404.677788) (xy 13.398211 -404.580598)
			(xy 13.32407 -404.478551) (xy 13.256483 -404.372051) (xy 13.195716 -404.261516) (xy 13.142009 -404.147384)
			(xy 13.095575 -404.030105) (xy 13.056597 -403.910142) (xy 13.025228 -403.787969) (xy 13.001593 -403.664066)
			(xy 12.985783 -403.538924) (xy 12.977863 -403.413036) (xy 11.534648 -403.413036) (xy 11.534648 -404.149306)
			(xy 17.192752 -409.80741)
		)
		(stroke
			(width 0)
			(type solid)
		)
		(fill yes)
		(layer "In5.Cu")
		(net "GND")
	)
	(gr_poly
		(pts
			(arc
				(start 101.000052 -529.49094)
				(mid 102.054334 -529.054242)
				(end 102.491032 -527.99996)
			)
			(arc
				(start 102.491032 -1.999996)
				(mid 102.054334 -0.945714)
				(end 101.000052 -0.509016)
			)
			(arc
				(start 26.500074 -0.509016)
				(mid 25.799255 -0.799305)
				(end 25.508966 -1.500124)
			)
			(arc
				(start 25.508966 -2.500122)
				(mid 24.920577 -3.920619)
				(end 23.50008 -4.509008)
			)
			(arc
				(start 1.500124 -4.509008)
				(mid 0.799305 -4.799297)
				(end 0.509016 -5.500116)
			)
			(xy 0.509016 -132.496306) (xy 1.015492 -132.496306) (xy 1.015492 -110.497874) (xy 0.924306 -110.406688)
			(xy 0.924306 -104.056688) (xy 1.015492 -103.965502)
			(arc
				(start 1.015492 -5.516372)
				(mid 1.15147 -5.163213)
				(end 1.49987 -5.01523)
			)
			(xy 1.500124 -5.01523) (xy 1.500124 -5.015484) (xy 23.266908 -5.015484) (xy 23.266908 -5.01523)
			(arc
				(start 23.50008 -5.01523)
				(mid 25.278456 -4.278498)
				(end 26.015188 -2.500122)
			)
			(arc
				(start 26.015188 -1.500124)
				(mid 26.157044 -1.157273)
				(end 26.49982 -1.015238)
			)
			(xy 26.500074 -1.015238) (xy 26.500074 -1.015492)
			(arc
				(start 101.000052 -1.015492)
				(mid 101.696201 -1.303847)
				(end 101.984556 -1.999996)
			)
			(xy 101.984556 -485.361234) (xy 101.98608 -485.381046) (xy 101.984556 -485.381046) (xy 101.984556 -486.544366)
			(xy 101.98481 -486.544366) (xy 101.98481 -486.547414) (xy 101.984556 -486.549954)
			(arc
				(start 101.984556 -527.99996)
				(mid 101.696201 -528.696109)
				(end 101.000052 -528.984464)
			)
			(xy 26.500074 -528.984464) (xy 26.500074 -528.984718)
			(arc
				(start 26.49982 -528.984718)
				(mid 26.157133 -528.842773)
				(end 26.015188 -528.500086)
			)
			(arc
				(start 26.015188 -527.500088)
				(mid 25.8238 -526.537447)
				(end 25.278588 -525.721326)
			)
			(arc
				(start 25.278588 -525.721326)
				(mid 24.462617 -525.176018)
				(end 23.50008 -524.984472)
			)
			(arc
				(start 1.516634 -524.984472)
				(mid 1.322224 -524.950922)
				(end 1.157224 -524.84274)
			)
			(arc
				(start 1.157224 -524.84274)
				(mid 1.052318 -524.685503)
				(end 1.015492 -524.500094)
			)
			(xy 1.015492 -408.489404) (xy 0.509016 -408.489404)
			(arc
				(start 0.509016 -524.500094)
				(mid 0.79923 -525.200734)
				(end 1.49987 -525.490948)
			)
			(arc
				(start 23.50008 -525.490948)
				(mid 24.920667 -526.079427)
				(end 25.508966 -527.500088)
			)
			(arc
				(start 25.508966 -528.500086)
				(mid 25.799345 -529.200741)
				(end 26.500074 -529.49094)
			)
		)
		(stroke
			(width 0)
			(type solid)
		)
		(fill yes)
		(layer "In5.Cu")
		(net "GND")
	)
	(gr_poly
		(pts
			(xy 36.677854 -285.585916) (xy 36.677854 -284.033214) (xy 36.19627 -283.55163) (xy 34.670492 -283.55163)
			(xy 34.349436 -283.230574) (xy 34.349436 -276.699726) (xy 31.271464 -273.621754) (xy 24.580088 -273.621754)
			(xy 23.964392 -274.23745) (xy 23.964392 -274.774914) (xy 26.855672 -274.774914) (xy 26.859743 -274.719292)
			(xy 26.871869 -274.664855) (xy 26.891792 -274.612764) (xy 26.919088 -274.564129) (xy 26.953174 -274.519986)
			(xy 26.993323 -274.481277) (xy 27.038681 -274.448826) (xy 27.088281 -274.423325) (xy 27.141065 -274.405318)
			(xy 27.195908 -274.395188) (xy 27.251642 -274.393151) (xy 27.307079 -274.399251) (xy 27.361036 -274.413357)
			(xy 27.412365 -274.435169) (xy 27.459971 -274.464223) (xy 27.502839 -274.499898) (xy 27.540056 -274.541435)
			(xy 27.570829 -274.587948) (xy 27.594501 -274.638445) (xy 27.610569 -274.691852) (xy 27.618689 -274.747028)
			(xy 27.619198 -274.774914) (xy 27.618689 -274.8028) (xy 27.610569 -274.857976) (xy 27.594501 -274.911383)
			(xy 27.593574 -274.91336) (xy 29.519874 -274.91336) (xy 29.519874 -274.82646) (xy 29.527892 -274.739931)
			(xy 29.54386 -274.654511) (xy 29.567641 -274.570929) (xy 29.599033 -274.489897) (xy 29.637767 -274.412108)
			(xy 29.683514 -274.338224) (xy 29.735883 -274.268877) (xy 29.794427 -274.204657) (xy 29.858647 -274.146113)
			(xy 29.927994 -274.093744) (xy 30.001878 -274.047997) (xy 30.079667 -274.009263) (xy 30.160699 -273.977871)
			(xy 30.244281 -273.95409) (xy 30.329701 -273.938122) (xy 30.41623 -273.930104) (xy 30.50313 -273.930104)
			(xy 30.589659 -273.938122) (xy 30.675079 -273.95409) (xy 30.758661 -273.977871) (xy 30.839693 -274.009263)
			(xy 30.917482 -274.047997) (xy 30.991366 -274.093744) (xy 31.060713 -274.146113) (xy 31.124933 -274.204657)
			(xy 31.183477 -274.268877) (xy 31.235846 -274.338224) (xy 31.281593 -274.412108) (xy 31.320327 -274.489897)
			(xy 31.351719 -274.570929) (xy 31.3755 -274.654511) (xy 31.391468 -274.739931) (xy 31.399486 -274.82646)
			(xy 31.399988 -274.86991) (xy 31.399486 -274.91336) (xy 31.391468 -274.999889) (xy 31.3755 -275.085309)
			(xy 31.351719 -275.168891) (xy 31.320327 -275.249923) (xy 31.281593 -275.327712) (xy 31.235846 -275.401596)
			(xy 31.183477 -275.470943) (xy 31.124933 -275.535163) (xy 31.060713 -275.593707) (xy 30.991366 -275.646076)
			(xy 30.917482 -275.691823) (xy 30.839693 -275.730557) (xy 30.758661 -275.761949) (xy 30.675079 -275.78573)
			(xy 30.589659 -275.801698) (xy 30.50313 -275.809716) (xy 30.41623 -275.809716) (xy 30.329701 -275.801698)
			(xy 30.244281 -275.78573) (xy 30.160699 -275.761949) (xy 30.079667 -275.730557) (xy 30.001878 -275.691823)
			(xy 29.927994 -275.646076) (xy 29.858647 -275.593707) (xy 29.794427 -275.535163) (xy 29.735883 -275.470943)
			(xy 29.683514 -275.401596) (xy 29.637767 -275.327712) (xy 29.599033 -275.249923) (xy 29.567641 -275.168891)
			(xy 29.54386 -275.085309) (xy 29.527892 -274.999889) (xy 29.519874 -274.91336) (xy 27.593574 -274.91336)
			(xy 27.570829 -274.96188) (xy 27.540056 -275.008393) (xy 27.502839 -275.04993) (xy 27.459971 -275.085605)
			(xy 27.412365 -275.114659) (xy 27.361036 -275.136471) (xy 27.307079 -275.150577) (xy 27.251642 -275.156677)
			(xy 27.195908 -275.15464) (xy 27.141065 -275.14451) (xy 27.088281 -275.126503) (xy 27.038681 -275.101002)
			(xy 26.993323 -275.068551) (xy 26.953174 -275.029842) (xy 26.919088 -274.985699) (xy 26.891792 -274.937064)
			(xy 26.871869 -274.884973) (xy 26.859743 -274.830536) (xy 26.855672 -274.774914) (xy 23.964392 -274.774914)
			(xy 23.964392 -275.200618) (xy 24.433022 -275.669248) (xy 27.51074 -275.669248) (xy 29.125418 -277.283926)
			(xy 29.141452 -277.299301) (xy 29.177853 -277.324758) (xy 29.218125 -277.343501) (xy 29.261041 -277.354959)
			(xy 29.305296 -277.358782) (xy 29.349542 -277.354856) (xy 29.392432 -277.343298) (xy 29.43266 -277.324462)
			(xy 29.469001 -277.29892) (xy 29.50035 -277.26745) (xy 29.525752 -277.231011) (xy 29.544433 -277.19071)
			(xy 29.550614 -277.169372) (xy 29.562221 -277.127417) (xy 29.592172 -277.045676) (xy 29.629549 -276.967053)
			(xy 29.674033 -276.892221) (xy 29.725243 -276.821821) (xy 29.782741 -276.756455) (xy 29.846034 -276.696683)
			(xy 29.91458 -276.643017) (xy 29.987794 -276.595916) (xy 30.065047 -276.555784) (xy 30.145679 -276.522964)
			(xy 30.228999 -276.497737) (xy 30.314294 -276.480318) (xy 30.400835 -276.470858) (xy 30.487878 -276.469437)
			(xy 30.574681 -276.476067) (xy 30.6605 -276.490692) (xy 30.744599 -276.513185) (xy 30.826259 -276.543356)
			(xy 30.904782 -276.580945) (xy 30.979494 -276.62563) (xy 31.049756 -276.67703) (xy 31.114966 -276.734703)
			(xy 31.174567 -276.798157) (xy 31.228048 -276.866848) (xy 31.274952 -276.940188) (xy 31.314876 -277.017549)
			(xy 31.347479 -277.098269) (xy 31.372481 -277.181657) (xy 31.38967 -277.266999) (xy 31.398897 -277.353564)
			(xy 31.400084 -277.440612) (xy 31.39322 -277.527396) (xy 31.378364 -277.613175) (xy 31.355644 -277.697213)
			(xy 31.325254 -277.778792) (xy 31.287453 -277.857213) (xy 31.242567 -277.931804) (xy 31.190978 -278.001928)
			(xy 31.133129 -278.066983) (xy 31.069515 -278.126413) (xy 31.00068 -278.179708) (xy 30.927214 -278.226414)
			(xy 30.849746 -278.266129) (xy 30.768938 -278.298515) (xy 30.685483 -278.323293) (xy 30.600096 -278.340251)
			(xy 30.513506 -278.349245) (xy 30.426455 -278.350198) (xy 30.33969 -278.3431) (xy 30.253951 -278.328013)
			(xy 30.169974 -278.305067) (xy 30.088478 -278.274457) (xy 30.010159 -278.236446) (xy 29.935689 -278.191358)
			(xy 29.865705 -278.139581) (xy 29.800806 -278.081557) (xy 29.770832 -278.04999) (xy 29.754513 -278.033234)
			(xy 29.716929 -278.005404) (xy 29.674888 -277.98492) (xy 29.629808 -277.972474) (xy 29.583213 -277.968487)
			(xy 29.536674 -277.973092) (xy 29.491763 -277.986134) (xy 29.449997 -278.007174) (xy 29.412785 -278.0355)
			(xy 29.381384 -278.070156) (xy 29.356855 -278.109973) (xy 29.340024 -278.153606) (xy 29.331461 -278.199581)
			(xy 29.330904 -278.222964) (xy 29.330904 -279.136856) (xy 29.331433 -279.160246) (xy 29.339986 -279.206239)
			(xy 29.356812 -279.249889) (xy 29.381342 -279.289722) (xy 29.412747 -279.324394) (xy 29.449967 -279.352733)
			(xy 29.491745 -279.373781) (xy 29.53667 -279.386829) (xy 29.583223 -279.391434) (xy 29.629833 -279.387443)
			(xy 29.674925 -279.374988) (xy 29.716977 -279.354492) (xy 29.754567 -279.326646) (xy 29.770832 -279.30983)
			(xy 29.800653 -279.278461) (xy 29.865151 -279.220733) (xy 29.934681 -279.169177) (xy 30.008654 -279.12423)
			(xy 30.086446 -279.086271) (xy 30.167397 -279.055623) (xy 30.250822 -279.032543) (xy 30.336015 -279.017229)
			(xy 30.422255 -279.009809) (xy 30.508812 -279.010346) (xy 30.594953 -279.018836) (xy 30.679949 -279.035207)
			(xy 30.763082 -279.05932) (xy 30.843646 -279.090971) (xy 30.92096 -279.129893) (xy 30.99437 -279.175755)
			(xy 31.063255 -279.22817) (xy 31.127031 -279.286693) (xy 31.185158 -279.350831) (xy 31.237145 -279.420039)
			(xy 31.282551 -279.493732) (xy 31.320992 -279.571286) (xy 31.352144 -279.652045) (xy 31.375741 -279.735325)
			(xy 31.391584 -279.820421) (xy 31.39954 -279.906613) (xy 31.399541 -279.993172) (xy 31.391586 -280.079364)
			(xy 31.375744 -280.164461) (xy 31.352148 -280.247741) (xy 31.320998 -280.328501) (xy 31.282558 -280.406055)
			(xy 31.237153 -280.479749) (xy 31.185167 -280.548958) (xy 31.127041 -280.613096) (xy 31.063266 -280.671621)
			(xy 30.994382 -280.724037) (xy 30.920973 -280.7699) (xy 30.843659 -280.808823) (xy 30.763095 -280.840475)
			(xy 30.679964 -280.86459) (xy 30.594968 -280.880962) (xy 30.508826 -280.889453) (xy 30.42227 -280.889992)
			(xy 30.336029 -280.882573) (xy 30.250836 -280.86726) (xy 30.167411 -280.844182) (xy 30.086459 -280.813534)
			(xy 30.008667 -280.775577) (xy 29.934693 -280.730631) (xy 29.865162 -280.679076) (xy 29.800664 -280.621349)
			(xy 29.770832 -280.58999) (xy 29.754513 -280.573234) (xy 29.716929 -280.545404) (xy 29.674888 -280.52492)
			(xy 29.629808 -280.512474) (xy 29.583213 -280.508487) (xy 29.536674 -280.513092) (xy 29.491763 -280.526134)
			(xy 29.449997 -280.547174) (xy 29.412785 -280.5755) (xy 29.381384 -280.610156) (xy 29.356855 -280.649973)
			(xy 29.340024 -280.693606) (xy 29.331461 -280.739581) (xy 29.330904 -280.762964) (xy 29.330904 -281.676856)
			(xy 29.331433 -281.700246) (xy 29.339986 -281.746239) (xy 29.356812 -281.789889) (xy 29.381342 -281.829722)
			(xy 29.412747 -281.864394) (xy 29.449967 -281.892733) (xy 29.491745 -281.913781) (xy 29.53667 -281.926829)
			(xy 29.583223 -281.931434) (xy 29.629833 -281.927443) (xy 29.674925 -281.914988) (xy 29.716977 -281.894492)
			(xy 29.754567 -281.866646) (xy 29.770832 -281.84983) (xy 29.800653 -281.818461) (xy 29.865151 -281.760733)
			(xy 29.934681 -281.709177) (xy 30.008654 -281.66423) (xy 30.086446 -281.626271) (xy 30.167397 -281.595623)
			(xy 30.250822 -281.572543) (xy 30.336015 -281.557229) (xy 30.422255 -281.549809) (xy 30.508812 -281.550346)
			(xy 30.594953 -281.558836) (xy 30.679949 -281.575207) (xy 30.763082 -281.59932) (xy 30.843646 -281.630971)
			(xy 30.92096 -281.669893) (xy 30.99437 -281.715755) (xy 31.063255 -281.76817) (xy 31.127031 -281.826693)
			(xy 31.185158 -281.890831) (xy 31.237145 -281.960039) (xy 31.282551 -282.033732) (xy 31.320992 -282.111286)
			(xy 31.352144 -282.192045) (xy 31.375741 -282.275325) (xy 31.391584 -282.360421) (xy 31.39954 -282.446613)
			(xy 31.399541 -282.533172) (xy 31.391586 -282.619364) (xy 31.375744 -282.704461) (xy 31.352148 -282.787741)
			(xy 31.320998 -282.868501) (xy 31.282558 -282.946055) (xy 31.237153 -283.019749) (xy 31.185167 -283.088958)
			(xy 31.127041 -283.153096) (xy 31.063266 -283.211621) (xy 30.994382 -283.264037) (xy 30.920973 -283.3099)
			(xy 30.843659 -283.348823) (xy 30.763095 -283.380475) (xy 30.679964 -283.40459) (xy 30.594968 -283.420962)
			(xy 30.508826 -283.429453) (xy 30.42227 -283.429992) (xy 30.336029 -283.422573) (xy 30.250836 -283.40726)
			(xy 30.167411 -283.384182) (xy 30.086459 -283.353534) (xy 30.008667 -283.315577) (xy 29.934693 -283.270631)
			(xy 29.865162 -283.219076) (xy 29.800664 -283.161349) (xy 29.770832 -283.12999) (xy 29.754513 -283.113234)
			(xy 29.716929 -283.085404) (xy 29.674888 -283.06492) (xy 29.629808 -283.052474) (xy 29.583213 -283.048487)
			(xy 29.536674 -283.053092) (xy 29.491763 -283.066134) (xy 29.449997 -283.087174) (xy 29.412785 -283.1155)
			(xy 29.381384 -283.150156) (xy 29.356855 -283.189973) (xy 29.340024 -283.233606) (xy 29.331461 -283.279581)
			(xy 29.330904 -283.302964) (xy 29.330904 -284.216856) (xy 29.331433 -284.240246) (xy 29.339986 -284.286239)
			(xy 29.356812 -284.329889) (xy 29.381342 -284.369722) (xy 29.412747 -284.404394) (xy 29.449967 -284.432733)
			(xy 29.491745 -284.453781) (xy 29.53667 -284.466829) (xy 29.583223 -284.471434) (xy 29.629833 -284.467443)
			(xy 29.674925 -284.454988) (xy 29.716977 -284.434492) (xy 29.754567 -284.406646) (xy 29.770832 -284.38983)
			(xy 29.800988 -284.358115) (xy 29.866267 -284.299816) (xy 29.936681 -284.247835) (xy 30.01162 -284.202622)
			(xy 30.090436 -284.164568) (xy 30.172447 -284.134002) (xy 30.256943 -284.111189) (xy 30.343194 -284.096327)
			(xy 30.430453 -284.089543) (xy 30.517964 -284.090897) (xy 30.604971 -284.100377) (xy 30.690721 -284.1179)
			(xy 30.774471 -284.143316) (xy 30.855497 -284.176404) (xy 30.933099 -284.216878) (xy 31.006603 -284.264387)
			(xy 31.075375 -284.318521) (xy 31.138819 -284.378812) (xy 31.196386 -284.444736) (xy 31.247579 -284.515725)
			(xy 31.291953 -284.591164) (xy 31.329126 -284.670399) (xy 31.358775 -284.752746) (xy 31.380644 -284.837492)
			(xy 31.394544 -284.923903) (xy 31.400354 -285.011232) (xy 31.398025 -285.098723) (xy 31.387575 -285.185619)
			(xy 31.369097 -285.271167) (xy 31.342749 -285.354629) (xy 31.308759 -285.435282) (xy 31.267422 -285.512427)
			(xy 31.219096 -285.585397) (xy 31.164198 -285.653561) (xy 31.103204 -285.716328) (xy 31.036641 -285.773157)
			(xy 30.965086 -285.823555) (xy 30.889157 -285.867085) (xy 30.809512 -285.903372) (xy 30.72684 -285.932101)
			(xy 30.641856 -285.953023) (xy 30.555295 -285.965959) (xy 30.467907 -285.970795) (xy 30.380447 -285.967489)
			(xy 30.293673 -285.956072) (xy 30.250892 -285.94685) (xy 30.218888 -285.939484) (xy 30.15615 -285.957518)
			(xy 30.133036 -285.980886) (xy 30.121575 -285.992995) (xy 30.10486 -286.021831) (xy 30.096204 -286.054017)
			(xy 30.096199 -286.087348) (xy 30.104847 -286.119536) (xy 30.121554 -286.148377) (xy 30.133036 -286.160464)
			(xy 30.200854 -286.228282) (xy 36.035488 -286.228282)
		)
		(stroke
			(width 0)
			(type solid)
		)
		(fill yes)
		(layer "In5.Cu")
		(net "P12V_STBY")
	)
	(gr_poly
		(pts
			(xy 9.004808 -114.458496) (xy 9.01698 -114.469898) (xy 9.045852 -114.486567) (xy 9.078055 -114.495196)
			(xy 9.111393 -114.495196) (xy 9.143596 -114.486567) (xy 9.172468 -114.469898) (xy 9.18464 -114.458496)
			(xy 14.553692 -109.089444) (xy 14.553692 -106.31424) (xy 10.238232 -101.99878) (xy 10.238232 -100.93833)
			(xy 10.237747 -100.915275) (xy 10.229465 -100.869915) (xy 10.213138 -100.826792) (xy 10.189304 -100.78732)
			(xy 10.158742 -100.752794) (xy 10.122456 -100.724344) (xy 10.081634 -100.702903) (xy 10.037615 -100.689176)
			(xy 9.991842 -100.683611) (xy 9.945816 -100.686391) (xy 9.901046 -100.697425) (xy 9.859 -100.716351)
			(xy 9.821055 -100.742549) (xy 9.8044 -100.758498) (xy 6.25983 -104.303068) (xy 4.705604 -104.303068)
			(xy 4.60883 -104.400096) (xy 4.593522 -104.416088) (xy 4.568124 -104.452342) (xy 4.549392 -104.492449)
			(xy 4.537891 -104.535194) (xy 4.53397 -104.579285) (xy 4.537747 -104.623389) (xy 4.549109 -104.666171)
			(xy 4.56771 -104.706339) (xy 4.592989 -104.742676) (xy 4.624181 -104.774084) (xy 4.660344 -104.799612)
			(xy 4.700382 -104.81849) (xy 4.721606 -104.824784) (xy 4.760562 -104.835907) (xy 4.836275 -104.86475)
			(xy 4.908801 -104.900867) (xy 4.977441 -104.943911) (xy 5.041538 -104.993468) (xy 5.100475 -105.049063)
			(xy 5.153685 -105.110161) (xy 5.200658 -105.176176) (xy 5.240942 -105.246472) (xy 5.274149 -105.320375)
			(xy 5.299962 -105.397173) (xy 5.318131 -105.47613) (xy 5.328483 -105.556487) (xy 5.330918 -105.637471)
			(xy 5.32922 -105.662391) (xy 6.21918 -105.662391) (xy 6.21918 -105.581281) (xy 6.22713 -105.500562)
			(xy 6.242953 -105.421011) (xy 6.266498 -105.343395) (xy 6.297537 -105.268459) (xy 6.335772 -105.196927)
			(xy 6.380834 -105.129487) (xy 6.432289 -105.066788) (xy 6.489642 -105.009435) (xy 6.552341 -104.95798)
			(xy 6.619781 -104.912918) (xy 6.691313 -104.874683) (xy 6.766249 -104.843644) (xy 6.843865 -104.820099)
			(xy 6.923416 -104.804276) (xy 7.004135 -104.796326) (xy 7.085245 -104.796326) (xy 7.165964 -104.804276)
			(xy 7.245515 -104.820099) (xy 7.323131 -104.843644) (xy 7.398067 -104.874683) (xy 7.469599 -104.912918)
			(xy 7.537039 -104.95798) (xy 7.599738 -105.009435) (xy 7.657091 -105.066788) (xy 7.708546 -105.129487)
			(xy 7.753608 -105.196927) (xy 7.791843 -105.268459) (xy 7.822882 -105.343395) (xy 7.846427 -105.421011)
			(xy 7.86225 -105.500562) (xy 7.8702 -105.581281) (xy 7.870698 -105.621836) (xy 7.8702 -105.662391)
			(xy 11.29918 -105.662391) (xy 11.29918 -105.581281) (xy 11.30713 -105.500562) (xy 11.322953 -105.421011)
			(xy 11.346498 -105.343395) (xy 11.377537 -105.268459) (xy 11.415772 -105.196927) (xy 11.460834 -105.129487)
			(xy 11.512289 -105.066788) (xy 11.569642 -105.009435) (xy 11.632341 -104.95798) (xy 11.699781 -104.912918)
			(xy 11.771313 -104.874683) (xy 11.846249 -104.843644) (xy 11.923865 -104.820099) (xy 12.003416 -104.804276)
			(xy 12.084135 -104.796326) (xy 12.165245 -104.796326) (xy 12.245964 -104.804276) (xy 12.325515 -104.820099)
			(xy 12.403131 -104.843644) (xy 12.478067 -104.874683) (xy 12.549599 -104.912918) (xy 12.617039 -104.95798)
			(xy 12.679738 -105.009435) (xy 12.737091 -105.066788) (xy 12.788546 -105.129487) (xy 12.833608 -105.196927)
			(xy 12.871843 -105.268459) (xy 12.902882 -105.343395) (xy 12.926427 -105.421011) (xy 12.94225 -105.500562)
			(xy 12.9502 -105.581281) (xy 12.950698 -105.621836) (xy 12.9502 -105.662391) (xy 12.94225 -105.74311)
			(xy 12.926427 -105.822661) (xy 12.902882 -105.900277) (xy 12.871843 -105.975213) (xy 12.833608 -106.046745)
			(xy 12.788546 -106.114185) (xy 12.737091 -106.176884) (xy 12.679738 -106.234237) (xy 12.617039 -106.285692)
			(xy 12.549599 -106.330754) (xy 12.478067 -106.368989) (xy 12.403131 -106.400028) (xy 12.325515 -106.423573)
			(xy 12.245964 -106.439396) (xy 12.165245 -106.447346) (xy 12.084135 -106.447346) (xy 12.003416 -106.439396)
			(xy 11.923865 -106.423573) (xy 11.846249 -106.400028) (xy 11.771313 -106.368989) (xy 11.699781 -106.330754)
			(xy 11.632341 -106.285692) (xy 11.569642 -106.234237) (xy 11.512289 -106.176884) (xy 11.460834 -106.114185)
			(xy 11.415772 -106.046745) (xy 11.377537 -105.975213) (xy 11.346498 -105.900277) (xy 11.322953 -105.822661)
			(xy 11.30713 -105.74311) (xy 11.29918 -105.662391) (xy 7.8702 -105.662391) (xy 7.86225 -105.74311)
			(xy 7.846427 -105.822661) (xy 7.822882 -105.900277) (xy 7.791843 -105.975213) (xy 7.753608 -106.046745)
			(xy 7.708546 -106.114185) (xy 7.657091 -106.176884) (xy 7.599738 -106.234237) (xy 7.537039 -106.285692)
			(xy 7.469599 -106.330754) (xy 7.398067 -106.368989) (xy 7.323131 -106.400028) (xy 7.245515 -106.423573)
			(xy 7.165964 -106.439396) (xy 7.085245 -106.447346) (xy 7.004135 -106.447346) (xy 6.923416 -106.439396)
			(xy 6.843865 -106.423573) (xy 6.766249 -106.400028) (xy 6.691313 -106.368989) (xy 6.619781 -106.330754)
			(xy 6.552341 -106.285692) (xy 6.489642 -106.234237) (xy 6.432289 -106.176884) (xy 6.380834 -106.114185)
			(xy 6.335772 -106.046745) (xy 6.297537 -105.975213) (xy 6.266498 -105.900277) (xy 6.242953 -105.822661)
			(xy 6.22713 -105.74311) (xy 6.21918 -105.662391) (xy 5.32922 -105.662391) (xy 5.325411 -105.718304)
			(xy 5.312018 -105.79821) (xy 5.290865 -105.876421) (xy 5.262156 -105.952184) (xy 5.226167 -106.024773)
			(xy 5.183245 -106.09349) (xy 5.133801 -106.157674) (xy 5.07831 -106.216709) (xy 5.017306 -106.270027)
			(xy 4.951374 -106.317117) (xy 4.881149 -106.357524) (xy 4.807306 -106.390863) (xy 4.730553 -106.416811)
			(xy 4.651628 -106.43512) (xy 4.57129 -106.445613) (xy 4.49031 -106.448191) (xy 4.409467 -106.442828)
			(xy 4.329538 -106.429575) (xy 4.25129 -106.40856) (xy 4.175476 -106.379986) (xy 4.13893 -106.3625)
			(xy 4.117662 -106.352591) (xy 4.072503 -106.339877) (xy 4.025779 -106.335668) (xy 3.979075 -106.340106)
			(xy 3.933979 -106.353039) (xy 3.892023 -106.37403) (xy 3.854631 -106.402364) (xy 3.823075 -106.437079)
			(xy 3.798427 -106.476996) (xy 3.781523 -106.520759) (xy 3.772938 -106.566881) (xy 3.772408 -106.590338)
			(xy 3.772408 -108.202391) (xy 4.94918 -108.202391) (xy 4.94918 -108.121281) (xy 4.95713 -108.040562)
			(xy 4.972953 -107.961011) (xy 4.996498 -107.883395) (xy 5.027537 -107.808459) (xy 5.065772 -107.736927)
			(xy 5.110834 -107.669487) (xy 5.162289 -107.606788) (xy 5.219642 -107.549435) (xy 5.282341 -107.49798)
			(xy 5.349781 -107.452918) (xy 5.421313 -107.414683) (xy 5.496249 -107.383644) (xy 5.573865 -107.360099)
			(xy 5.653416 -107.344276) (xy 5.734135 -107.336326) (xy 5.815245 -107.336326) (xy 5.895964 -107.344276)
			(xy 5.975515 -107.360099) (xy 6.053131 -107.383644) (xy 6.128067 -107.414683) (xy 6.199599 -107.452918)
			(xy 6.267039 -107.49798) (xy 6.329738 -107.549435) (xy 6.387091 -107.606788) (xy 6.438546 -107.669487)
			(xy 6.483608 -107.736927) (xy 6.521843 -107.808459) (xy 6.552882 -107.883395) (xy 6.576427 -107.961011)
			(xy 6.59225 -108.040562) (xy 6.6002 -108.121281) (xy 6.600698 -108.161836) (xy 6.6002 -108.202391)
			(xy 7.48918 -108.202391) (xy 7.48918 -108.121281) (xy 7.49713 -108.040562) (xy 7.512953 -107.961011)
			(xy 7.536498 -107.883395) (xy 7.567537 -107.808459) (xy 7.605772 -107.736927) (xy 7.650834 -107.669487)
			(xy 7.702289 -107.606788) (xy 7.759642 -107.549435) (xy 7.822341 -107.49798) (xy 7.889781 -107.452918)
			(xy 7.961313 -107.414683) (xy 8.036249 -107.383644) (xy 8.113865 -107.360099) (xy 8.193416 -107.344276)
			(xy 8.274135 -107.336326) (xy 8.355245 -107.336326) (xy 8.435964 -107.344276) (xy 8.515515 -107.360099)
			(xy 8.593131 -107.383644) (xy 8.668067 -107.414683) (xy 8.739599 -107.452918) (xy 8.807039 -107.49798)
			(xy 8.869738 -107.549435) (xy 8.927091 -107.606788) (xy 8.978546 -107.669487) (xy 9.023608 -107.736927)
			(xy 9.061843 -107.808459) (xy 9.092882 -107.883395) (xy 9.116427 -107.961011) (xy 9.13225 -108.040562)
			(xy 9.1402 -108.121281) (xy 9.140698 -108.161836) (xy 9.1402 -108.202391) (xy 10.02918 -108.202391)
			(xy 10.02918 -108.121281) (xy 10.03713 -108.040562) (xy 10.052953 -107.961011) (xy 10.076498 -107.883395)
			(xy 10.107537 -107.808459) (xy 10.145772 -107.736927) (xy 10.190834 -107.669487) (xy 10.242289 -107.606788)
			(xy 10.299642 -107.549435) (xy 10.362341 -107.49798) (xy 10.429781 -107.452918) (xy 10.501313 -107.414683)
			(xy 10.576249 -107.383644) (xy 10.653865 -107.360099) (xy 10.733416 -107.344276) (xy 10.814135 -107.336326)
			(xy 10.895245 -107.336326) (xy 10.975964 -107.344276) (xy 11.055515 -107.360099) (xy 11.133131 -107.383644)
			(xy 11.208067 -107.414683) (xy 11.279599 -107.452918) (xy 11.347039 -107.49798) (xy 11.409738 -107.549435)
			(xy 11.467091 -107.606788) (xy 11.518546 -107.669487) (xy 11.563608 -107.736927) (xy 11.601843 -107.808459)
			(xy 11.632882 -107.883395) (xy 11.656427 -107.961011) (xy 11.67225 -108.040562) (xy 11.6802 -108.121281)
			(xy 11.680698 -108.161836) (xy 11.6802 -108.202391) (xy 12.56918 -108.202391) (xy 12.56918 -108.121281)
			(xy 12.57713 -108.040562) (xy 12.592953 -107.961011) (xy 12.616498 -107.883395) (xy 12.647537 -107.808459)
			(xy 12.685772 -107.736927) (xy 12.730834 -107.669487) (xy 12.782289 -107.606788) (xy 12.839642 -107.549435)
			(xy 12.902341 -107.49798) (xy 12.969781 -107.452918) (xy 13.041313 -107.414683) (xy 13.116249 -107.383644)
			(xy 13.193865 -107.360099) (xy 13.273416 -107.344276) (xy 13.354135 -107.336326) (xy 13.435245 -107.336326)
			(xy 13.515964 -107.344276) (xy 13.595515 -107.360099) (xy 13.673131 -107.383644) (xy 13.748067 -107.414683)
			(xy 13.819599 -107.452918) (xy 13.887039 -107.49798) (xy 13.949738 -107.549435) (xy 14.007091 -107.606788)
			(xy 14.058546 -107.669487) (xy 14.103608 -107.736927) (xy 14.141843 -107.808459) (xy 14.172882 -107.883395)
			(xy 14.196427 -107.961011) (xy 14.21225 -108.040562) (xy 14.2202 -108.121281) (xy 14.220698 -108.161836)
			(xy 14.2202 -108.202391) (xy 14.21225 -108.28311) (xy 14.196427 -108.362661) (xy 14.172882 -108.440277)
			(xy 14.141843 -108.515213) (xy 14.103608 -108.586745) (xy 14.058546 -108.654185) (xy 14.007091 -108.716884)
			(xy 13.949738 -108.774237) (xy 13.887039 -108.825692) (xy 13.819599 -108.870754) (xy 13.748067 -108.908989)
			(xy 13.673131 -108.940028) (xy 13.595515 -108.963573) (xy 13.515964 -108.979396) (xy 13.435245 -108.987346)
			(xy 13.354135 -108.987346) (xy 13.273416 -108.979396) (xy 13.193865 -108.963573) (xy 13.116249 -108.940028)
			(xy 13.041313 -108.908989) (xy 12.969781 -108.870754) (xy 12.902341 -108.825692) (xy 12.839642 -108.774237)
			(xy 12.782289 -108.716884) (xy 12.730834 -108.654185) (xy 12.685772 -108.586745) (xy 12.647537 -108.515213)
			(xy 12.616498 -108.440277) (xy 12.592953 -108.362661) (xy 12.57713 -108.28311) (xy 12.56918 -108.202391)
			(xy 11.6802 -108.202391) (xy 11.67225 -108.28311) (xy 11.656427 -108.362661) (xy 11.632882 -108.440277)
			(xy 11.601843 -108.515213) (xy 11.563608 -108.586745) (xy 11.518546 -108.654185) (xy 11.467091 -108.716884)
			(xy 11.409738 -108.774237) (xy 11.347039 -108.825692) (xy 11.279599 -108.870754) (xy 11.208067 -108.908989)
			(xy 11.133131 -108.940028) (xy 11.055515 -108.963573) (xy 10.975964 -108.979396) (xy 10.895245 -108.987346)
			(xy 10.814135 -108.987346) (xy 10.733416 -108.979396) (xy 10.653865 -108.963573) (xy 10.576249 -108.940028)
			(xy 10.501313 -108.908989) (xy 10.429781 -108.870754) (xy 10.362341 -108.825692) (xy 10.299642 -108.774237)
			(xy 10.242289 -108.716884) (xy 10.190834 -108.654185) (xy 10.145772 -108.586745) (xy 10.107537 -108.515213)
			(xy 10.076498 -108.440277) (xy 10.052953 -108.362661) (xy 10.03713 -108.28311) (xy 10.02918 -108.202391)
			(xy 9.1402 -108.202391) (xy 9.13225 -108.28311) (xy 9.116427 -108.362661) (xy 9.092882 -108.440277)
			(xy 9.061843 -108.515213) (xy 9.023608 -108.586745) (xy 8.978546 -108.654185) (xy 8.927091 -108.716884)
			(xy 8.869738 -108.774237) (xy 8.807039 -108.825692) (xy 8.739599 -108.870754) (xy 8.668067 -108.908989)
			(xy 8.593131 -108.940028) (xy 8.515515 -108.963573) (xy 8.435964 -108.979396) (xy 8.355245 -108.987346)
			(xy 8.274135 -108.987346) (xy 8.193416 -108.979396) (xy 8.113865 -108.963573) (xy 8.036249 -108.940028)
			(xy 7.961313 -108.908989) (xy 7.889781 -108.870754) (xy 7.822341 -108.825692) (xy 7.759642 -108.774237)
			(xy 7.702289 -108.716884) (xy 7.650834 -108.654185) (xy 7.605772 -108.586745) (xy 7.567537 -108.515213)
			(xy 7.536498 -108.440277) (xy 7.512953 -108.362661) (xy 7.49713 -108.28311) (xy 7.48918 -108.202391)
			(xy 6.6002 -108.202391) (xy 6.59225 -108.28311) (xy 6.576427 -108.362661) (xy 6.552882 -108.440277)
			(xy 6.521843 -108.515213) (xy 6.483608 -108.586745) (xy 6.438546 -108.654185) (xy 6.387091 -108.716884)
			(xy 6.329738 -108.774237) (xy 6.267039 -108.825692) (xy 6.199599 -108.870754) (xy 6.128067 -108.908989)
			(xy 6.053131 -108.940028) (xy 5.975515 -108.963573) (xy 5.895964 -108.979396) (xy 5.815245 -108.987346)
			(xy 5.734135 -108.987346) (xy 5.653416 -108.979396) (xy 5.573865 -108.963573) (xy 5.496249 -108.940028)
			(xy 5.421313 -108.908989) (xy 5.349781 -108.870754) (xy 5.282341 -108.825692) (xy 5.219642 -108.774237)
			(xy 5.162289 -108.716884) (xy 5.110834 -108.654185) (xy 5.065772 -108.586745) (xy 5.027537 -108.515213)
			(xy 4.996498 -108.440277) (xy 4.972953 -108.362661) (xy 4.95713 -108.28311) (xy 4.94918 -108.202391)
			(xy 3.772408 -108.202391) (xy 3.772408 -109.226096)
		)
		(stroke
			(width 0)
			(type solid)
		)
		(fill yes)
		(layer "In5.Cu")
		(net "GND")
	)
	(gr_poly
		(pts
			(xy 45.119544 -347.765116) (xy 60.53709 -347.765116) (xy 79.153512 -329.148694) (xy 79.153512 -322.915534)
			(xy 80.601312 -321.467734) (xy 80.601312 -316.050422) (xy 90.02522 -306.626514) (xy 90.02522 -298.86656)
			(xy 82.627724 -291.469064) (xy 82.627724 -286.310832) (xy 82.611976 -286.28213) (xy 82.599064 -286.257789)
			(xy 82.579606 -286.206242) (xy 82.567769 -286.15243) (xy 82.563798 -286.097475) (xy 82.567776 -286.042521)
			(xy 82.57962 -285.988711) (xy 82.599085 -285.937166) (xy 82.611976 -285.912814) (xy 82.627724 -285.884112)
			(xy 82.627724 -281.974798) (xy 85.284818 -279.317704) (xy 85.296219 -279.305577) (xy 85.312911 -279.276795)
			(xy 85.321597 -279.244677) (xy 85.322156 -279.228042) (xy 85.322156 -276.226016) (xy 85.321686 -276.209921)
			(xy 85.313628 -276.178756) (xy 85.298022 -276.150602) (xy 85.275862 -276.127254) (xy 85.262466 -276.11832)
			(xy 85.231463 -276.098364) (xy 85.173342 -276.052992) (xy 85.120223 -276.001854) (xy 85.072676 -275.945498)
			(xy 85.03121 -275.884528) (xy 84.996269 -275.819598) (xy 84.968229 -275.751404) (xy 84.947388 -275.680676)
			(xy 84.933972 -275.608173) (xy 84.928123 -275.534671) (xy 84.929905 -275.460958) (xy 84.939297 -275.387825)
			(xy 84.9562 -275.316054) (xy 84.980433 -275.246416) (xy 85.011735 -275.179656) (xy 85.049772 -275.11649)
			(xy 85.094135 -275.057595) (xy 85.144349 -275.003601) (xy 85.199876 -274.955089) (xy 85.2297 -274.93341)
			(xy 85.261482 -274.911634) (xy 85.328875 -274.874292) (xy 85.399907 -274.844448) (xy 85.473747 -274.82245)
			(xy 85.54953 -274.808556) (xy 85.626371 -274.802928) (xy 85.70337 -274.805633) (xy 85.779627 -274.816639)
			(xy 85.854249 -274.835817) (xy 85.926363 -274.862942) (xy 85.995125 -274.897697) (xy 86.059732 -274.939676)
			(xy 86.119426 -274.988387) (xy 86.17351 -275.043261) (xy 86.221351 -275.103655) (xy 86.262388 -275.168864)
			(xy 86.296143 -275.238123) (xy 86.32222 -275.310622) (xy 86.331806 -275.347938) (xy 86.341712 -275.388832)
			(xy 86.383622 -275.423884) (xy 86.396216 -275.433774) (xy 86.425141 -275.447492) (xy 86.456571 -275.453575)
			(xy 86.488526 -275.45164) (xy 86.518993 -275.441809) (xy 86.546051 -275.424701) (xy 86.567998 -275.401394)
			(xy 86.583449 -275.373356) (xy 86.591433 -275.342354) (xy 86.591902 -275.326348) (xy 86.592156 -274.956016)
			(xy 86.591686 -274.939921) (xy 86.583628 -274.908756) (xy 86.568022 -274.880602) (xy 86.545862 -274.857254)
			(xy 86.532466 -274.84832) (xy 86.501311 -274.828259) (xy 86.442921 -274.78263) (xy 86.389589 -274.73118)
			(xy 86.341892 -274.674466) (xy 86.300348 -274.613102) (xy 86.265405 -274.547754) (xy 86.237443 -274.479127)
			(xy 86.216764 -274.407967) (xy 86.203592 -274.335043) (xy 86.19807 -274.261145) (xy 86.200257 -274.187073)
			(xy 86.210131 -274.113629) (xy 86.227583 -274.041609) (xy 86.252425 -273.971793) (xy 86.284388 -273.904937)
			(xy 86.323126 -273.841764) (xy 86.368219 -273.782959) (xy 86.419179 -273.729158) (xy 86.475454 -273.680944)
			(xy 86.536435 -273.63884) (xy 86.601461 -273.603301) (xy 86.669828 -273.574712) (xy 86.740797 -273.553383)
			(xy 86.813597 -273.539545) (xy 86.850474 -273.535902) (xy 86.897718 -273.531838) (xy 87.0204 -273.406616)
			(xy 87.0204 -272.543524) (xy 86.897718 -272.418302) (xy 86.850474 -272.414238) (xy 86.813627 -272.410675)
			(xy 86.740895 -272.396869) (xy 86.669988 -272.375588) (xy 86.601674 -272.347061) (xy 86.53669 -272.311597)
			(xy 86.475738 -272.269579) (xy 86.419478 -272.221461) (xy 86.368516 -272.167762) (xy 86.323404 -272.109064)
			(xy 86.284628 -272.046) (xy 86.252609 -271.979251) (xy 86.227691 -271.909539) (xy 86.210144 -271.837618)
			(xy 86.200158 -271.764263) (xy 86.197841 -271.690268) (xy 86.203217 -271.616432) (xy 86.216228 -271.543553)
			(xy 86.236735 -271.472419) (xy 86.264514 -271.403798) (xy 86.299267 -271.33843) (xy 86.340618 -271.277024)
			(xy 86.364064 -271.248378) (xy 86.388577 -271.219838) (xy 86.442671 -271.167546) (xy 86.501981 -271.121252)
			(xy 86.565843 -271.081474) (xy 86.633546 -271.048656) (xy 86.704333 -271.023163) (xy 86.777414 -271.005281)
			(xy 86.851975 -270.995208) (xy 86.927182 -270.993058) (xy 87.002196 -270.998855) (xy 87.076179 -271.012533)
			(xy 87.148307 -271.03394) (xy 87.183214 -271.047972) (xy 87.219649 -271.06372) (xy 87.289091 -271.102173)
			(xy 87.353824 -271.148113) (xy 87.413044 -271.20097) (xy 87.466016 -271.260086) (xy 87.512083 -271.324729)
			(xy 87.550672 -271.394096) (xy 87.5665 -271.430496) (xy 87.576023 -271.450784) (xy 87.6011 -271.487924)
			(xy 87.632298 -271.520093) (xy 87.668653 -271.546295) (xy 87.709038 -271.565719) (xy 87.752202 -271.577764)
			(xy 87.796809 -271.582055) (xy 87.841478 -271.578462) (xy 87.884826 -271.567093) (xy 87.925509 -271.548303)
			(xy 87.962269 -271.522672) (xy 87.978488 -271.507204) (xy 87.99195 -271.493742) (xy 88.09863 -271.387316)
			(xy 88.738964 -271.387316) (xy 88.755062 -271.386849) (xy 88.786233 -271.378797) (xy 88.814396 -271.363198)
			(xy 88.837757 -271.341044) (xy 88.84666 -271.327626) (xy 88.866969 -271.296082) (xy 88.913239 -271.23702)
			(xy 88.965465 -271.183154) (xy 89.02307 -271.135083) (xy 89.085412 -271.093338) (xy 89.1518 -271.058385)
			(xy 89.221497 -271.03061) (xy 89.29373 -271.010323) (xy 89.367696 -270.997748) (xy 89.442575 -270.993025)
			(xy 89.517535 -270.996207) (xy 89.591744 -271.007257) (xy 89.664379 -271.026054) (xy 89.734633 -271.052389)
			(xy 89.801726 -271.085969) (xy 89.864914 -271.126422) (xy 89.923495 -271.173299) (xy 89.976818 -271.226079)
			(xy 90.024293 -271.284176) (xy 90.065391 -271.346946) (xy 90.099658 -271.413691) (xy 90.126711 -271.483672)
			(xy 90.146252 -271.55611) (xy 90.158063 -271.630202) (xy 90.162009 -271.70507) (xy 91.277697 -271.70507)
			(xy 91.281732 -271.629366) (xy 91.293791 -271.554521) (xy 91.313737 -271.48138) (xy 91.341344 -271.410775)
			(xy 91.3763 -271.343504) (xy 91.418208 -271.280329) (xy 91.466594 -271.221967) (xy 91.52091 -271.169079)
			(xy 91.580539 -271.122264) (xy 91.644807 -271.082052) (xy 91.712984 -271.0489) (xy 91.7843 -271.023182)
			(xy 91.857945 -271.00519) (xy 91.933085 -270.995128) (xy 92.008869 -270.993109) (xy 92.084439 -270.999158)
			(xy 92.158937 -271.013205) (xy 92.23152 -271.035091) (xy 92.301366 -271.064568) (xy 92.367683 -271.101303)
			(xy 92.429719 -271.144878) (xy 92.486772 -271.1948) (xy 92.538196 -271.250504) (xy 92.583407 -271.311359)
			(xy 92.621894 -271.376674) (xy 92.65322 -271.44571) (xy 92.67703 -271.517685) (xy 92.693055 -271.591783)
			(xy 92.701114 -271.667164) (xy 92.701618 -271.70507) (xy 92.701114 -271.742976) (xy 92.693055 -271.818357)
			(xy 92.67703 -271.892455) (xy 92.65322 -271.96443) (xy 92.621894 -272.033466) (xy 92.583407 -272.098781)
			(xy 92.538196 -272.159636) (xy 92.486772 -272.21534) (xy 92.429719 -272.265262) (xy 92.367683 -272.308837)
			(xy 92.301366 -272.345572) (xy 92.23152 -272.375049) (xy 92.158937 -272.396935) (xy 92.084439 -272.410982)
			(xy 92.008869 -272.417031) (xy 91.933085 -272.415012) (xy 91.857945 -272.40495) (xy 91.7843 -272.386958)
			(xy 91.712984 -272.36124) (xy 91.644807 -272.328088) (xy 91.580539 -272.287876) (xy 91.52091 -272.241061)
			(xy 91.466594 -272.188173) (xy 91.418208 -272.129811) (xy 91.3763 -272.066636) (xy 91.341344 -271.999365)
			(xy 91.313737 -271.92876) (xy 91.293791 -271.855619) (xy 91.281732 -271.780774) (xy 91.277697 -271.70507)
			(xy 90.162009 -271.70507) (xy 90.162012 -271.705125) (xy 90.158057 -271.780049) (xy 90.146241 -271.85414)
			(xy 90.126695 -271.926577) (xy 90.099637 -271.996555) (xy 90.065366 -272.063298) (xy 90.024263 -272.126065)
			(xy 89.976784 -272.184159) (xy 89.923457 -272.236935) (xy 89.864872 -272.283807) (xy 89.801682 -272.324256)
			(xy 89.734586 -272.357831) (xy 89.66433 -272.384161) (xy 89.591694 -272.402953) (xy 89.517484 -272.413998)
			(xy 89.442524 -272.417174) (xy 89.367646 -272.412446) (xy 89.29368 -272.399866) (xy 89.221449 -272.379573)
			(xy 89.151754 -272.351794) (xy 89.085368 -272.316836) (xy 89.023029 -272.275087) (xy 88.965428 -272.227011)
			(xy 88.913205 -272.173142) (xy 88.86694 -272.114077) (xy 88.84666 -272.082514) (xy 88.83773 -272.069116)
			(xy 88.814379 -272.046962) (xy 88.786223 -272.031362) (xy 88.755058 -272.02331) (xy 88.738964 -272.022824)
			(xy 88.361774 -272.022824) (xy 88.315038 -272.069814) (xy 88.308942 -272.07591) (xy 88.297643 -272.088078)
			(xy 88.281152 -272.116883) (xy 88.27264 -272.148965) (xy 88.272682 -272.182157) (xy 88.281276 -272.214218)
			(xy 88.297841 -272.242981) (xy 88.321257 -272.266505) (xy 88.349945 -272.2832) (xy 88.365838 -272.288)
			(xy 88.400416 -272.297825) (xy 88.46756 -272.323507) (xy 88.531771 -272.35583) (xy 88.592394 -272.394464)
			(xy 88.648812 -272.439015) (xy 88.700449 -272.48903) (xy 88.746779 -272.543997) (xy 88.787328 -272.603357)
			(xy 88.821684 -272.666504) (xy 88.835992 -272.69948) (xy 88.850471 -272.73525) (xy 88.872486 -272.809215)
			(xy 88.886369 -272.885128) (xy 88.891956 -272.962097) (xy 88.89149 -272.97507) (xy 90.007697 -272.97507)
			(xy 90.011732 -272.899366) (xy 90.023791 -272.824521) (xy 90.043737 -272.75138) (xy 90.071344 -272.680775)
			(xy 90.1063 -272.613504) (xy 90.148208 -272.550329) (xy 90.196594 -272.491967) (xy 90.25091 -272.439079)
			(xy 90.310539 -272.392264) (xy 90.374807 -272.352052) (xy 90.442984 -272.3189) (xy 90.5143 -272.293182)
			(xy 90.587945 -272.27519) (xy 90.663085 -272.265128) (xy 90.738869 -272.263109) (xy 90.814439 -272.269158)
			(xy 90.888937 -272.283205) (xy 90.96152 -272.305091) (xy 91.031366 -272.334568) (xy 91.097683 -272.371303)
			(xy 91.159719 -272.414878) (xy 91.216772 -272.4648) (xy 91.268196 -272.520504) (xy 91.313407 -272.581359)
			(xy 91.351894 -272.646674) (xy 91.38322 -272.71571) (xy 91.40703 -272.787685) (xy 91.423055 -272.861783)
			(xy 91.431114 -272.937164) (xy 91.431618 -272.97507) (xy 91.431114 -273.012976) (xy 91.423055 -273.088357)
			(xy 91.40703 -273.162455) (xy 91.38322 -273.23443) (xy 91.351894 -273.303466) (xy 91.313407 -273.368781)
			(xy 91.268196 -273.429636) (xy 91.216772 -273.48534) (xy 91.159719 -273.535262) (xy 91.097683 -273.578837)
			(xy 91.031366 -273.615572) (xy 90.96152 -273.645049) (xy 90.888937 -273.666935) (xy 90.814439 -273.680982)
			(xy 90.738869 -273.687031) (xy 90.663085 -273.685012) (xy 90.587945 -273.67495) (xy 90.5143 -273.656958)
			(xy 90.442984 -273.63124) (xy 90.374807 -273.598088) (xy 90.310539 -273.557876) (xy 90.25091 -273.511061)
			(xy 90.196594 -273.458173) (xy 90.148208 -273.399811) (xy 90.1063 -273.336636) (xy 90.071344 -273.269365)
			(xy 90.043737 -273.19876) (xy 90.023791 -273.125619) (xy 90.011732 -273.050774) (xy 90.007697 -272.97507)
			(xy 88.89149 -272.97507) (xy 88.889183 -273.039219) (xy 88.878081 -273.115588) (xy 88.858781 -273.190307)
			(xy 88.831509 -273.2625) (xy 88.796587 -273.331317) (xy 88.754423 -273.395952) (xy 88.705513 -273.455646)
			(xy 88.650431 -273.509697) (xy 88.589825 -273.55747) (xy 88.557354 -273.57832) (xy 88.54396 -273.587253)
			(xy 88.521812 -273.610607) (xy 88.506216 -273.638761) (xy 88.498163 -273.669923) (xy 88.497664 -273.686016)
			(xy 88.497664 -274.068286) (xy 88.498171 -274.085029) (xy 88.50689 -274.117359) (xy 88.52373 -274.146301)
			(xy 88.535256 -274.158456) (xy 88.539574 -274.162774) (xy 88.551777 -274.174092) (xy 88.580663 -274.190598)
			(xy 88.61283 -274.19909) (xy 88.646099 -274.198995) (xy 88.678216 -274.190317) (xy 88.707007 -274.173646)
			(xy 88.719152 -274.162266) (xy 88.745568 -274.135596) (xy 88.753442 -274.098766) (xy 88.761197 -274.063948)
			(xy 88.78277 -273.99595) (xy 88.811044 -273.930455) (xy 88.845736 -273.868121) (xy 88.886497 -273.809575)
			(xy 88.932916 -273.755406) (xy 88.95842 -273.730466) (xy 88.98556 -273.705207) (xy 89.044214 -273.659852)
			(xy 89.107266 -273.620842) (xy 89.174033 -273.588599) (xy 89.24379 -273.563473) (xy 89.315782 -273.545737)
			(xy 89.389228 -273.535582) (xy 89.463332 -273.53312) (xy 89.537289 -273.538376) (xy 89.6103 -273.551293)
			(xy 89.681572 -273.571732) (xy 89.750332 -273.599471) (xy 89.815835 -273.634209) (xy 89.877371 -273.67557)
			(xy 89.934273 -273.723105) (xy 89.985924 -273.776298) (xy 90.009218 -273.805142) (xy 90.031924 -273.834775)
			(xy 90.071684 -273.897965) (xy 90.10461 -273.96497) (xy 90.13034 -274.035054) (xy 90.148592 -274.107446)
			(xy 90.159164 -274.181352) (xy 90.161535 -274.24507) (xy 91.277697 -274.24507) (xy 91.281732 -274.169366)
			(xy 91.293791 -274.094521) (xy 91.313737 -274.02138) (xy 91.341344 -273.950775) (xy 91.3763 -273.883504)
			(xy 91.418208 -273.820329) (xy 91.466594 -273.761967) (xy 91.52091 -273.709079) (xy 91.580539 -273.662264)
			(xy 91.644807 -273.622052) (xy 91.712984 -273.5889) (xy 91.7843 -273.563182) (xy 91.857945 -273.54519)
			(xy 91.933085 -273.535128) (xy 92.008869 -273.533109) (xy 92.084439 -273.539158) (xy 92.158937 -273.553205)
			(xy 92.23152 -273.575091) (xy 92.301366 -273.604568) (xy 92.367683 -273.641303) (xy 92.429719 -273.684878)
			(xy 92.486772 -273.7348) (xy 92.538196 -273.790504) (xy 92.583407 -273.851359) (xy 92.621894 -273.916674)
			(xy 92.65322 -273.98571) (xy 92.67703 -274.057685) (xy 92.693055 -274.131783) (xy 92.701114 -274.207164)
			(xy 92.701618 -274.24507) (xy 92.701114 -274.282976) (xy 92.693055 -274.358357) (xy 92.67703 -274.432455)
			(xy 92.65322 -274.50443) (xy 92.621894 -274.573466) (xy 92.583407 -274.638781) (xy 92.538196 -274.699636)
			(xy 92.486772 -274.75534) (xy 92.429719 -274.805262) (xy 92.367683 -274.848837) (xy 92.301366 -274.885572)
			(xy 92.23152 -274.915049) (xy 92.158937 -274.936935) (xy 92.084439 -274.950982) (xy 92.008869 -274.957031)
			(xy 91.933085 -274.955012) (xy 91.857945 -274.94495) (xy 91.7843 -274.926958) (xy 91.712984 -274.90124)
			(xy 91.644807 -274.868088) (xy 91.580539 -274.827876) (xy 91.52091 -274.781061) (xy 91.466594 -274.728173)
			(xy 91.418208 -274.669811) (xy 91.3763 -274.606636) (xy 91.341344 -274.539365) (xy 91.313737 -274.46876)
			(xy 91.293791 -274.395619) (xy 91.281732 -274.320774) (xy 91.277697 -274.24507) (xy 90.161535 -274.24507)
			(xy 90.16194 -274.255958) (xy 90.15689 -274.330445) (xy 90.14407 -274.403994) (xy 90.123619 -274.475796)
			(xy 90.095764 -274.545063) (xy 90.06081 -274.611033) (xy 90.019142 -274.672981) (xy 89.971217 -274.730226)
			(xy 89.917562 -274.782139) (xy 89.858767 -274.828149) (xy 89.827354 -274.84832) (xy 89.81396 -274.857253)
			(xy 89.791812 -274.880607) (xy 89.776216 -274.908761) (xy 89.768163 -274.939923) (xy 89.767664 -274.956016)
			(xy 89.767664 -275.364194) (xy 89.768206 -275.380845) (xy 89.776823 -275.413012) (xy 89.793469 -275.441853)
			(xy 89.817013 -275.465405) (xy 89.845849 -275.482061) (xy 89.878014 -275.490688) (xy 89.894664 -275.491194)
			(xy 89.940892 -275.491194) (xy 90.011504 -275.43252) (xy 90.019632 -275.387054) (xy 90.02695 -275.349741)
			(xy 90.048513 -275.27682) (xy 90.077726 -275.206613) (xy 90.114256 -275.13992) (xy 90.157686 -275.0775)
			(xy 90.207523 -275.020066) (xy 90.263198 -274.96827) (xy 90.324076 -274.922705) (xy 90.389464 -274.883888)
			(xy 90.458618 -274.852262) (xy 90.530749 -274.828187) (xy 90.605034 -274.811938) (xy 90.680629 -274.8037)
			(xy 90.756671 -274.803566) (xy 90.832294 -274.811539) (xy 90.906636 -274.827527) (xy 90.978851 -274.851348)
			(xy 91.048115 -274.88273) (xy 91.11364 -274.921317) (xy 91.16581 -274.96008) (xy 93.154506 -274.96008)
			(xy 93.158522 -274.84381) (xy 93.170549 -274.728095) (xy 93.190531 -274.613485) (xy 93.218373 -274.500526)
			(xy 93.253942 -274.389758) (xy 93.297068 -274.281707) (xy 93.347545 -274.176889) (xy 93.405134 -274.075804)
			(xy 93.46956 -273.978932) (xy 93.540515 -273.886736) (xy 93.617662 -273.799655) (xy 93.700633 -273.718104)
			(xy 93.789033 -273.642472) (xy 93.88244 -273.573118) (xy 93.980409 -273.510375) (xy 94.082473 -273.454539)
			(xy 94.188147 -273.405878) (xy 94.296926 -273.364624) (xy 94.408291 -273.330973) (xy 94.521714 -273.305085)
			(xy 94.636651 -273.287084) (xy 94.752557 -273.277055) (xy 94.868879 -273.275047) (xy 94.985062 -273.281069)
			(xy 95.100553 -273.295092) (xy 95.214801 -273.31705) (xy 95.327262 -273.346837) (xy 95.4374 -273.384312)
			(xy 95.54469 -273.429297) (xy 95.648621 -273.481576) (xy 95.748697 -273.540901) (xy 95.844443 -273.606989)
			(xy 95.9354 -273.679525) (xy 96.021136 -273.758164) (xy 96.101243 -273.84253) (xy 96.175339 -273.932222)
			(xy 96.243069 -274.026812) (xy 96.304113 -274.12585) (xy 96.358178 -274.228863) (xy 96.405008 -274.33536)
			(xy 96.444379 -274.444835) (xy 96.476103 -274.556765) (xy 96.500029 -274.670617) (xy 96.516043 -274.785849)
			(xy 96.52407 -274.901911) (xy 96.524572 -274.96008) (xy 96.52407 -275.018249) (xy 96.516043 -275.134311)
			(xy 96.500029 -275.249543) (xy 96.476103 -275.363395) (xy 96.444379 -275.475325) (xy 96.405008 -275.5848)
			(xy 96.358178 -275.691297) (xy 96.304113 -275.79431) (xy 96.243069 -275.893348) (xy 96.175339 -275.987938)
			(xy 96.101243 -276.07763) (xy 96.021136 -276.161996) (xy 95.9354 -276.240635) (xy 95.844443 -276.313171)
			(xy 95.748697 -276.379259) (xy 95.648621 -276.438584) (xy 95.54469 -276.490863) (xy 95.4374 -276.535848)
			(xy 95.327262 -276.573323) (xy 95.214801 -276.60311) (xy 95.100553 -276.625068) (xy 94.985062 -276.639091)
			(xy 94.868879 -276.645113) (xy 94.752557 -276.643105) (xy 94.636651 -276.633076) (xy 94.521714 -276.615075)
			(xy 94.408291 -276.589187) (xy 94.296926 -276.555536) (xy 94.188147 -276.514282) (xy 94.082473 -276.465621)
			(xy 93.980409 -276.409785) (xy 93.88244 -276.347042) (xy 93.789033 -276.277688) (xy 93.700633 -276.202056)
			(xy 93.617662 -276.120505) (xy 93.540515 -276.033424) (xy 93.46956 -275.941228) (xy 93.405134 -275.844356)
			(xy 93.347545 -275.743271) (xy 93.297068 -275.638453) (xy 93.253942 -275.530402) (xy 93.218373 -275.419634)
			(xy 93.190531 -275.306675) (xy 93.170549 -275.192065) (xy 93.158522 -275.07635) (xy 93.154506 -274.96008)
			(xy 91.16581 -274.96008) (xy 91.174678 -274.966669) (xy 91.230534 -275.018268) (xy 91.280573 -275.075527)
			(xy 91.324222 -275.137793) (xy 91.360986 -275.204358) (xy 91.390446 -275.274462) (xy 91.412265 -275.347306)
			(xy 91.426195 -275.422062) (xy 91.432078 -275.497876) (xy 91.429846 -275.573885) (xy 91.419524 -275.649224)
			(xy 91.401232 -275.723033) (xy 91.375176 -275.794472) (xy 91.341653 -275.862726) (xy 91.301046 -275.927018)
			(xy 91.253818 -275.986616) (xy 91.200506 -276.04084) (xy 91.141718 -276.089073) (xy 91.078124 -276.130764)
			(xy 91.010448 -276.16544) (xy 90.939462 -276.192704) (xy 90.865974 -276.212247) (xy 90.790821 -276.223844)
			(xy 90.714861 -276.227366) (xy 90.638957 -276.22277) (xy 90.563977 -276.21011) (xy 90.490772 -276.18953)
			(xy 90.420179 -276.161264) (xy 90.353 -276.125635) (xy 90.290002 -276.083048) (xy 90.231902 -276.033988)
			(xy 90.205306 -276.006814) (xy 90.189091 -275.990561) (xy 90.151931 -275.96361) (xy 90.110536 -275.943767)
			(xy 90.066251 -275.931678) (xy 90.020515 -275.927735) (xy 89.974815 -275.932067) (xy 89.930635 -275.944533)
			(xy 89.88941 -275.964728) (xy 89.852481 -275.991995) (xy 89.821046 -276.025449) (xy 89.796128 -276.064003)
			(xy 89.778536 -276.106403) (xy 89.768842 -276.151273) (xy 89.767664 -276.1742) (xy 89.767664 -280.03754)
			(xy 89.298018 -280.50744) (xy 89.23909 -280.566368) (xy 89.229946 -280.597864) (xy 89.221868 -280.624263)
			(xy 89.199162 -280.674583) (xy 89.16944 -280.721105) (xy 89.133324 -280.762857) (xy 89.091567 -280.798969)
			(xy 89.045041 -280.828684) (xy 88.994719 -280.851385) (xy 88.968326 -280.859484) (xy 88.93683 -280.868628)
			(xy 85.962998 -283.84246) (xy 85.95161 -283.854593) (xy 85.934943 -283.883378) (xy 85.926279 -283.915492)
			(xy 85.92566 -283.932122) (xy 85.92566 -286.709866) (xy 86.877404 -286.709866) (xy 86.881424 -286.519215)
			(xy 86.893478 -286.328902) (xy 86.913544 -286.139267) (xy 86.941587 -285.950646) (xy 86.977556 -285.763376)
			(xy 87.021388 -285.577788) (xy 87.073005 -285.394213) (xy 87.132315 -285.212977) (xy 87.199213 -285.034402)
			(xy 87.273579 -284.858807) (xy 87.355281 -284.686502) (xy 87.444175 -284.517795) (xy 87.540101 -284.352985)
			(xy 87.64289 -284.192366) (xy 87.752359 -284.036223) (xy 87.868313 -283.884834) (xy 87.990547 -283.738467)
			(xy 88.118841 -283.597383) (xy 88.252969 -283.461834) (xy 88.392693 -283.332059) (xy 88.537763 -283.208289)
			(xy 88.687921 -283.090746) (xy 88.842902 -282.979637) (xy 89.002429 -282.87516) (xy 89.166218 -282.777501)
			(xy 89.333978 -282.686834) (xy 89.505412 -282.60332) (xy 89.680214 -282.527107) (xy 89.858073 -282.458331)
			(xy 90.038674 -282.397113) (xy 90.221694 -282.343564) (xy 90.40681 -282.297778) (xy 90.593691 -282.259836)
			(xy 90.782006 -282.229807) (xy 90.971419 -282.207742) (xy 91.161593 -282.193683) (xy 91.352192 -282.187653)
			(xy 91.542875 -282.189663) (xy 91.733304 -282.19971) (xy 91.92314 -282.217776) (xy 92.112046 -282.243829)
			(xy 92.299685 -282.277822) (xy 92.485725 -282.319695) (xy 92.669834 -282.369374) (xy 92.851685 -282.42677)
			(xy 93.030955 -282.491781) (xy 93.207325 -282.564292) (xy 93.380481 -282.644173) (xy 93.550116 -282.731283)
			(xy 93.715928 -282.825467) (xy 93.877622 -282.926558) (xy 94.03491 -283.034374) (xy 94.187513 -283.148726)
			(xy 94.335161 -283.269409) (xy 94.477589 -283.39621) (xy 94.614545 -283.528901) (xy 94.745786 -283.667249)
			(xy 94.871078 -283.811006) (xy 94.990198 -283.959917) (xy 95.102934 -284.113718) (xy 95.209087 -284.272134)
			(xy 95.308467 -284.434885) (xy 95.400897 -284.60168) (xy 95.486214 -284.772224) (xy 95.564266 -284.946212)
			(xy 95.634913 -285.123337) (xy 95.698031 -285.303282) (xy 95.753507 -285.485728) (xy 95.801242 -285.670351)
			(xy 95.841152 -285.856821) (xy 95.873165 -286.044809) (xy 95.897225 -286.233979) (xy 95.913288 -286.423995)
			(xy 95.921327 -286.614519) (xy 95.92183 -286.709866) (xy 95.921327 -286.805213) (xy 95.913288 -286.995737)
			(xy 95.897225 -287.185753) (xy 95.873165 -287.374923) (xy 95.841152 -287.562911) (xy 95.801242 -287.749381)
			(xy 95.753507 -287.934004) (xy 95.698031 -288.11645) (xy 95.634913 -288.296395) (xy 95.564266 -288.47352)
			(xy 95.486214 -288.647508) (xy 95.400897 -288.818052) (xy 95.308467 -288.984847) (xy 95.209087 -289.147598)
			(xy 95.102934 -289.306014) (xy 94.990198 -289.459815) (xy 94.871078 -289.608726) (xy 94.745786 -289.752483)
			(xy 94.614545 -289.890831) (xy 94.477589 -290.023522) (xy 94.335161 -290.150323) (xy 94.187513 -290.271006)
			(xy 94.03491 -290.385358) (xy 93.877622 -290.493174) (xy 93.715928 -290.594265) (xy 93.550116 -290.688449)
			(xy 93.380481 -290.775559) (xy 93.207325 -290.85544) (xy 93.030955 -290.927951) (xy 92.851685 -290.992962)
			(xy 92.669834 -291.050358) (xy 92.485725 -291.100037) (xy 92.299685 -291.14191) (xy 92.112046 -291.175903)
			(xy 91.92314 -291.201956) (xy 91.733304 -291.220022) (xy 91.542875 -291.230069) (xy 91.352192 -291.232079)
			(xy 91.161593 -291.226049) (xy 90.971419 -291.21199) (xy 90.782006 -291.189925) (xy 90.593691 -291.159896)
			(xy 90.40681 -291.121954) (xy 90.221694 -291.076168) (xy 90.038674 -291.022619) (xy 89.858073 -290.961401)
			(xy 89.680214 -290.892625) (xy 89.505412 -290.816412) (xy 89.333978 -290.732898) (xy 89.166218 -290.642231)
			(xy 89.002429 -290.544572) (xy 88.842902 -290.440095) (xy 88.687921 -290.328986) (xy 88.537763 -290.211443)
			(xy 88.392693 -290.087673) (xy 88.252969 -289.957898) (xy 88.118841 -289.822349) (xy 87.990547 -289.681265)
			(xy 87.868313 -289.534898) (xy 87.752359 -289.383509) (xy 87.64289 -289.227366) (xy 87.540101 -289.066747)
			(xy 87.444175 -288.901937) (xy 87.355281 -288.73323) (xy 87.273579 -288.560925) (xy 87.199213 -288.38533)
			(xy 87.132315 -288.206755) (xy 87.073005 -288.025519) (xy 87.021388 -287.841944) (xy 86.977556 -287.656356)
			(xy 86.941587 -287.469086) (xy 86.913544 -287.280465) (xy 86.893478 -287.09083) (xy 86.881424 -286.900517)
			(xy 86.877404 -286.709866) (xy 85.92566 -286.709866) (xy 85.92566 -290.961826) (xy 92.715588 -297.751754)
			(xy 92.715588 -307.38826) (xy 92.716779 -307.41062) (xy 92.726032 -307.454427) (xy 92.742814 -307.495937)
			(xy 92.766607 -307.533866) (xy 92.796675 -307.567041) (xy 92.832089 -307.594437) (xy 92.871753 -307.615208)
			(xy 92.914442 -307.628711) (xy 92.958836 -307.634529) (xy 93.003563 -307.632482) (xy 93.04724 -307.622632)
			(xy 93.088517 -307.605286) (xy 93.126118 -307.580978) (xy 93.142816 -307.56606) (xy 94.049088 -306.660042)
			(xy 94.049088 -306.21351) (xy 94.033086 -306.184808) (xy 94.020168 -306.160467) (xy 94.000699 -306.108918)
			(xy 93.98885 -306.055103) (xy 93.984869 -306.000144) (xy 93.988838 -305.945183) (xy 94.000674 -305.891366)
			(xy 94.020131 -305.839812) (xy 94.033086 -305.815492) (xy 94.049088 -305.78679) (xy 94.049088 -292.77945)
			(xy 98.481896 -288.346388) (xy 98.481896 -274.320254) (xy 94.39148 -270.229838) (xy 94.37935 -270.218443)
			(xy 94.350567 -270.201762) (xy 94.31845 -270.193085) (xy 94.301818 -270.1925) (xy 71.981314 -270.1925)
			(xy 70.815454 -269.02664) (xy 36.612068 -269.02664) (xy 36.589195 -269.027826) (xy 36.544412 -269.037404)
			(xy 36.502071 -269.054856) (xy 36.463544 -269.079615) (xy 36.43008 -269.11088) (xy 36.402764 -269.147638)
			(xy 36.382479 -269.188697) (xy 36.369884 -269.232728) (xy 36.365387 -269.278303) (xy 36.369133 -269.323946)
			(xy 36.381 -269.368178) (xy 36.390326 -269.389098) (xy 36.408215 -269.428191) (xy 36.437609 -269.508988)
			(xy 36.459504 -269.59213) (xy 36.473718 -269.676925) (xy 36.480132 -269.762663) (xy 36.478693 -269.848628)
			(xy 36.469412 -269.934103) (xy 36.452367 -270.018374) (xy 36.4277 -270.100737) (xy 36.395617 -270.180505)
			(xy 36.356387 -270.25701) (xy 36.310337 -270.329615) (xy 36.25785 -270.397713) (xy 36.199367 -270.460735)
			(xy 36.135374 -270.518156) (xy 36.066407 -270.569494) (xy 35.993041 -270.614323) (xy 35.91589 -270.652267)
			(xy 35.835596 -270.68301) (xy 35.752832 -270.706294) (xy 35.668287 -270.721926) (xy 35.582669 -270.729774)
			(xy 35.496691 -270.729774) (xy 35.411073 -270.721926) (xy 35.326528 -270.706294) (xy 35.243764 -270.68301)
			(xy 35.16347 -270.652267) (xy 35.086319 -270.614323) (xy 35.012953 -270.569494) (xy 34.943986 -270.518156)
			(xy 34.879993 -270.460735) (xy 34.82151 -270.397713) (xy 34.769023 -270.329615) (xy 34.722973 -270.25701)
			(xy 34.683743 -270.180505) (xy 34.65166 -270.100737) (xy 34.626993 -270.018374) (xy 34.609948 -269.934103)
			(xy 34.600667 -269.848628) (xy 34.599228 -269.762663) (xy 34.605642 -269.676925) (xy 34.619856 -269.59213)
			(xy 34.641751 -269.508988) (xy 34.671145 -269.428191) (xy 34.689034 -269.389098) (xy 34.698356 -269.368193)
			(xy 34.710155 -269.323971) (xy 34.713847 -269.278352) (xy 34.709314 -269.232808) (xy 34.696702 -269.188811)
			(xy 34.676418 -269.147783) (xy 34.649118 -269.111048) (xy 34.615683 -269.079792) (xy 34.577194 -269.055027)
			(xy 34.534893 -269.037551) (xy 34.490147 -269.027929) (xy 34.467292 -269.02664) (xy 31.532068 -269.02664)
			(xy 31.509195 -269.027826) (xy 31.464412 -269.037404) (xy 31.422071 -269.054856) (xy 31.383544 -269.079615)
			(xy 31.35008 -269.11088) (xy 31.322764 -269.147638) (xy 31.302479 -269.188697) (xy 31.289884 -269.232728)
			(xy 31.285387 -269.278303) (xy 31.289133 -269.323946) (xy 31.301 -269.368178) (xy 31.310326 -269.389098)
			(xy 31.328215 -269.428191) (xy 31.357609 -269.508988) (xy 31.379504 -269.59213) (xy 31.393718 -269.676925)
			(xy 31.400132 -269.762663) (xy 31.398693 -269.848628) (xy 31.389412 -269.934103) (xy 31.372367 -270.018374)
			(xy 31.3477 -270.100737) (xy 31.315617 -270.180505) (xy 31.276387 -270.25701) (xy 31.230337 -270.329615)
			(xy 31.17785 -270.397713) (xy 31.119367 -270.460735) (xy 31.055374 -270.518156) (xy 30.986407 -270.569494)
			(xy 30.913041 -270.614323) (xy 30.83589 -270.652267) (xy 30.755596 -270.68301) (xy 30.672832 -270.706294)
			(xy 30.588287 -270.721926) (xy 30.502669 -270.729774) (xy 30.416691 -270.729774) (xy 30.331073 -270.721926)
			(xy 30.246528 -270.706294) (xy 30.163764 -270.68301) (xy 30.08347 -270.652267) (xy 30.006319 -270.614323)
			(xy 29.932953 -270.569494) (xy 29.863986 -270.518156) (xy 29.799993 -270.460735) (xy 29.74151 -270.397713)
			(xy 29.689023 -270.329615) (xy 29.642973 -270.25701) (xy 29.603743 -270.180505) (xy 29.57166 -270.100737)
			(xy 29.546993 -270.018374) (xy 29.529948 -269.934103) (xy 29.520667 -269.848628) (xy 29.519228 -269.762663)
			(xy 29.525642 -269.676925) (xy 29.539856 -269.59213) (xy 29.561751 -269.508988) (xy 29.591145 -269.428191)
			(xy 29.609034 -269.389098) (xy 29.618356 -269.368193) (xy 29.630155 -269.323971) (xy 29.633847 -269.278352)
			(xy 29.629314 -269.232808) (xy 29.616702 -269.188811) (xy 29.596418 -269.147783) (xy 29.569118 -269.111048)
			(xy 29.535683 -269.079792) (xy 29.497194 -269.055027) (xy 29.454893 -269.037551) (xy 29.410147 -269.027929)
			(xy 29.387292 -269.02664) (xy 21.648674 -269.02664) (xy 21.624928 -269.027927) (xy 21.578511 -269.038246)
			(xy 21.534824 -269.05702) (xy 21.495393 -269.083595) (xy 21.461595 -269.117041) (xy 21.434609 -269.156192)
			(xy 21.415378 -269.19968) (xy 21.404573 -269.245986) (xy 21.403056 -269.269718) (xy 21.401338 -269.297429)
			(xy 21.390888 -269.351955) (xy 21.372647 -269.404392) (xy 21.347 -269.453632) (xy 21.314489 -269.498636)
			(xy 21.2758 -269.538454) (xy 21.23175 -269.572246) (xy 21.183268 -269.599298) (xy 21.131377 -269.61904)
			(xy 21.077174 -269.631054) (xy 21.021802 -269.635087) (xy 20.96643 -269.631054) (xy 20.912227 -269.61904)
			(xy 20.860336 -269.599298) (xy 20.811854 -269.572246) (xy 20.767804 -269.538454) (xy 20.729115 -269.498636)
			(xy 20.696604 -269.453632) (xy 20.670957 -269.404392) (xy 20.652716 -269.351955) (xy 20.642266 -269.297429)
			(xy 20.640548 -269.269718) (xy 20.638981 -269.245999) (xy 20.628129 -269.199726) (xy 20.608875 -269.156272)
			(xy 20.581886 -269.117148) (xy 20.548103 -269.083716) (xy 20.5087 -269.057138) (xy 20.465048 -269.038338)
			(xy 20.418663 -269.02797) (xy 20.39493 -269.02664) (xy 19.09953 -269.02664) (xy 19.082891 -269.02717)
			(xy 19.050765 -269.035853) (xy 19.021981 -269.052557) (xy 19.009868 -269.063978) (xy 15.733014 -272.340832)
			(xy 26.850592 -272.340832) (xy 26.854663 -272.28521) (xy 26.866789 -272.230773) (xy 26.886712 -272.178682)
			(xy 26.914008 -272.130047) (xy 26.948094 -272.085904) (xy 26.988243 -272.047195) (xy 27.033601 -272.014744)
			(xy 27.083201 -271.989243) (xy 27.135985 -271.971236) (xy 27.190828 -271.961106) (xy 27.246562 -271.959069)
			(xy 27.301999 -271.965169) (xy 27.355956 -271.979275) (xy 27.407285 -272.001087) (xy 27.454891 -272.030141)
			(xy 27.497759 -272.065816) (xy 27.534976 -272.107353) (xy 27.565749 -272.153866) (xy 27.589421 -272.204363)
			(xy 27.605489 -272.25777) (xy 27.613609 -272.312946) (xy 27.614118 -272.340832) (xy 27.613609 -272.368718)
			(xy 27.605489 -272.423894) (xy 27.589421 -272.477301) (xy 27.565749 -272.527798) (xy 27.534976 -272.574311)
			(xy 27.497759 -272.615848) (xy 27.454891 -272.651523) (xy 27.407285 -272.680577) (xy 27.355956 -272.702389)
			(xy 27.301999 -272.716495) (xy 27.246562 -272.722595) (xy 27.190828 -272.720558) (xy 27.135985 -272.710428)
			(xy 27.083201 -272.692421) (xy 27.033601 -272.66692) (xy 26.988243 -272.634469) (xy 26.948094 -272.59576)
			(xy 26.914008 -272.551617) (xy 26.886712 -272.502982) (xy 26.866789 -272.450891) (xy 26.854663 -272.396454)
			(xy 26.850592 -272.340832) (xy 15.733014 -272.340832) (xy 12.767818 -275.306028) (xy 23.709884 -275.306028)
			(xy 23.709884 -274.13204) (xy 24.474678 -273.3675) (xy 29.558234 -273.3675) (xy 29.580588 -273.367032)
			(xy 29.624609 -273.35922) (xy 29.666583 -273.343826) (xy 29.705216 -273.321324) (xy 29.739315 -273.29241)
			(xy 29.767829 -273.257974) (xy 29.789877 -273.219081) (xy 29.804779 -273.17693) (xy 29.812075 -273.132821)
			(xy 29.81154 -273.088116) (xy 29.803191 -273.044194) (xy 29.787286 -273.002411) (xy 29.764314 -272.964056)
			(xy 29.750004 -272.946876) (xy 29.722149 -272.914102) (xy 29.671878 -272.844302) (xy 29.628191 -272.770202)
			(xy 29.591454 -272.692423) (xy 29.561975 -272.611613) (xy 29.539999 -272.528449) (xy 29.52571 -272.443625)
			(xy 29.519228 -272.357851) (xy 29.520606 -272.271843) (xy 29.529834 -272.18632) (xy 29.546834 -272.101998)
			(xy 29.571464 -272.019581) (xy 29.603519 -271.939757) (xy 29.642729 -271.863195) (xy 29.688768 -271.790534)
			(xy 29.741251 -271.722381) (xy 29.799739 -271.659306) (xy 29.863743 -271.601837) (xy 29.932728 -271.550453)
			(xy 30.006118 -271.505584) (xy 30.083299 -271.467606) (xy 30.163626 -271.436835) (xy 30.246427 -271.413529)
			(xy 30.331011 -271.397882) (xy 30.416671 -271.390026) (xy 30.502689 -271.390026) (xy 30.588349 -271.397882)
			(xy 30.672933 -271.413529) (xy 30.755734 -271.436835) (xy 30.836061 -271.467606) (xy 30.913242 -271.505584)
			(xy 30.986632 -271.550453) (xy 31.055617 -271.601837) (xy 31.119621 -271.659306) (xy 31.178109 -271.722381)
			(xy 31.230592 -271.790534) (xy 31.276631 -271.863195) (xy 31.315841 -271.939757) (xy 31.347896 -272.019581)
			(xy 31.372526 -272.101998) (xy 31.389526 -272.18632) (xy 31.398754 -272.271843) (xy 31.400132 -272.357851)
			(xy 31.39896 -272.37336) (xy 34.599874 -272.37336) (xy 34.599874 -272.28646) (xy 34.607892 -272.199931)
			(xy 34.62386 -272.114511) (xy 34.647641 -272.030929) (xy 34.679033 -271.949897) (xy 34.717767 -271.872108)
			(xy 34.763514 -271.798224) (xy 34.815883 -271.728877) (xy 34.874427 -271.664657) (xy 34.938647 -271.606113)
			(xy 35.007994 -271.553744) (xy 35.081878 -271.507997) (xy 35.159667 -271.469263) (xy 35.240699 -271.437871)
			(xy 35.324281 -271.41409) (xy 35.409701 -271.398122) (xy 35.49623 -271.390104) (xy 35.58313 -271.390104)
			(xy 35.669659 -271.398122) (xy 35.755079 -271.41409) (xy 35.838661 -271.437871) (xy 35.919693 -271.469263)
			(xy 35.997482 -271.507997) (xy 36.071366 -271.553744) (xy 36.140713 -271.606113) (xy 36.204933 -271.664657)
			(xy 36.263477 -271.728877) (xy 36.315846 -271.798224) (xy 36.361593 -271.872108) (xy 36.400327 -271.949897)
			(xy 36.431719 -272.030929) (xy 36.4555 -272.114511) (xy 36.471468 -272.199931) (xy 36.479486 -272.28646)
			(xy 36.479988 -272.32991) (xy 36.479486 -272.37336) (xy 36.471468 -272.459889) (xy 36.4555 -272.545309)
			(xy 36.431719 -272.628891) (xy 36.400327 -272.709923) (xy 36.361593 -272.787712) (xy 36.315846 -272.861596)
			(xy 36.263477 -272.930943) (xy 36.204933 -272.995163) (xy 36.140713 -273.053707) (xy 36.071366 -273.106076)
			(xy 35.997482 -273.151823) (xy 35.919693 -273.190557) (xy 35.838661 -273.221949) (xy 35.755079 -273.24573)
			(xy 35.669659 -273.261698) (xy 35.58313 -273.269716) (xy 35.49623 -273.269716) (xy 35.409701 -273.261698)
			(xy 35.324281 -273.24573) (xy 35.240699 -273.221949) (xy 35.159667 -273.190557) (xy 35.081878 -273.151823)
			(xy 35.007994 -273.106076) (xy 34.938647 -273.053707) (xy 34.874427 -272.995163) (xy 34.815883 -272.930943)
			(xy 34.763514 -272.861596) (xy 34.717767 -272.787712) (xy 34.679033 -272.709923) (xy 34.647641 -272.628891)
			(xy 34.62386 -272.545309) (xy 34.607892 -272.459889) (xy 34.599874 -272.37336) (xy 31.39896 -272.37336)
			(xy 31.39365 -272.443625) (xy 31.379361 -272.528449) (xy 31.357385 -272.611613) (xy 31.327906 -272.692423)
			(xy 31.291169 -272.770202) (xy 31.247482 -272.844302) (xy 31.197211 -272.914102) (xy 31.169356 -272.946876)
			(xy 31.155134 -272.964121) (xy 31.132182 -273.002468) (xy 31.116292 -273.044239) (xy 31.107953 -273.088145)
			(xy 31.107422 -273.132833) (xy 31.114716 -273.176924) (xy 31.12961 -273.219061) (xy 31.151644 -273.257942)
			(xy 31.18014 -273.29237) (xy 31.214219 -273.321283) (xy 31.252829 -273.343789) (xy 31.294781 -273.359194)
			(xy 31.338781 -273.367024) (xy 31.361126 -273.3675) (xy 31.376874 -273.3675) (xy 31.619463 -273.61007)
			(xy 39.818317 -273.61007) (xy 39.822323 -273.494063) (xy 39.834324 -273.378609) (xy 39.854261 -273.264258)
			(xy 39.88204 -273.151555) (xy 39.917528 -273.041038) (xy 39.960556 -272.933231) (xy 40.01092 -272.828651)
			(xy 40.068378 -272.727794) (xy 40.132658 -272.631141) (xy 40.203453 -272.539154) (xy 40.280426 -272.45227)
			(xy 40.363209 -272.370903) (xy 40.451409 -272.295441) (xy 40.544604 -272.226245) (xy 40.642352 -272.163643)
			(xy 40.744186 -272.107934) (xy 40.84962 -272.059383) (xy 40.958153 -272.018222) (xy 41.069267 -271.984647)
			(xy 41.182433 -271.958817) (xy 41.297111 -271.940857) (xy 41.412755 -271.930851) (xy 41.528813 -271.928847)
			(xy 41.644734 -271.934856) (xy 41.759963 -271.948847) (xy 41.873953 -271.970755) (xy 41.98616 -272.000475)
			(xy 42.096049 -272.037865) (xy 42.203096 -272.082748) (xy 42.306792 -272.134909) (xy 42.406642 -272.1941)
			(xy 42.502171 -272.260039) (xy 42.502197 -272.26006) (xy 63.647577 -272.26006) (xy 63.651612 -272.184356)
			(xy 63.663671 -272.109511) (xy 63.683617 -272.03637) (xy 63.711224 -271.965765) (xy 63.74618 -271.898494)
			(xy 63.788088 -271.835319) (xy 63.836474 -271.776957) (xy 63.89079 -271.724069) (xy 63.950419 -271.677254)
			(xy 64.014687 -271.637042) (xy 64.082864 -271.60389) (xy 64.15418 -271.578172) (xy 64.227825 -271.56018)
			(xy 64.302965 -271.550118) (xy 64.378749 -271.548099) (xy 64.454319 -271.554148) (xy 64.528817 -271.568195)
			(xy 64.6014 -271.590081) (xy 64.671246 -271.619558) (xy 64.737563 -271.656293) (xy 64.799599 -271.699868)
			(xy 64.856652 -271.74979) (xy 64.908076 -271.805494) (xy 64.953287 -271.866349) (xy 64.991774 -271.931664)
			(xy 65.0231 -272.0007) (xy 65.04691 -272.072675) (xy 65.062935 -272.146773) (xy 65.070994 -272.222154)
			(xy 65.071498 -272.26006) (xy 66.187577 -272.26006) (xy 66.191612 -272.184356) (xy 66.203671 -272.109511)
			(xy 66.223617 -272.03637) (xy 66.251224 -271.965765) (xy 66.28618 -271.898494) (xy 66.328088 -271.835319)
			(xy 66.376474 -271.776957) (xy 66.43079 -271.724069) (xy 66.490419 -271.677254) (xy 66.554687 -271.637042)
			(xy 66.622864 -271.60389) (xy 66.69418 -271.578172) (xy 66.767825 -271.56018) (xy 66.842965 -271.550118)
			(xy 66.918749 -271.548099) (xy 66.994319 -271.554148) (xy 67.068817 -271.568195) (xy 67.1414 -271.590081)
			(xy 67.211246 -271.619558) (xy 67.277563 -271.656293) (xy 67.339599 -271.699868) (xy 67.396652 -271.74979)
			(xy 67.448076 -271.805494) (xy 67.493287 -271.866349) (xy 67.531774 -271.931664) (xy 67.5631 -272.0007)
			(xy 67.58691 -272.072675) (xy 67.602935 -272.146773) (xy 67.610994 -272.222154) (xy 67.611498 -272.26006)
			(xy 68.727577 -272.26006) (xy 68.731612 -272.184356) (xy 68.743671 -272.109511) (xy 68.763617 -272.03637)
			(xy 68.791224 -271.965765) (xy 68.82618 -271.898494) (xy 68.868088 -271.835319) (xy 68.916474 -271.776957)
			(xy 68.97079 -271.724069) (xy 69.030419 -271.677254) (xy 69.094687 -271.637042) (xy 69.162864 -271.60389)
			(xy 69.23418 -271.578172) (xy 69.307825 -271.56018) (xy 69.382965 -271.550118) (xy 69.458749 -271.548099)
			(xy 69.534319 -271.554148) (xy 69.608817 -271.568195) (xy 69.6814 -271.590081) (xy 69.751246 -271.619558)
			(xy 69.817563 -271.656293) (xy 69.879599 -271.699868) (xy 69.936652 -271.74979) (xy 69.988076 -271.805494)
			(xy 70.033287 -271.866349) (xy 70.071774 -271.931664) (xy 70.1031 -272.0007) (xy 70.12691 -272.072675)
			(xy 70.142935 -272.146773) (xy 70.150994 -272.222154) (xy 70.151498 -272.26006) (xy 71.267577 -272.26006)
			(xy 71.271612 -272.184356) (xy 71.283671 -272.109511) (xy 71.303617 -272.03637) (xy 71.331224 -271.965765)
			(xy 71.36618 -271.898494) (xy 71.408088 -271.835319) (xy 71.456474 -271.776957) (xy 71.51079 -271.724069)
			(xy 71.570419 -271.677254) (xy 71.634687 -271.637042) (xy 71.702864 -271.60389) (xy 71.77418 -271.578172)
			(xy 71.847825 -271.56018) (xy 71.922965 -271.550118) (xy 71.998749 -271.548099) (xy 72.074319 -271.554148)
			(xy 72.148817 -271.568195) (xy 72.2214 -271.590081) (xy 72.291246 -271.619558) (xy 72.357563 -271.656293)
			(xy 72.419599 -271.699868) (xy 72.476652 -271.74979) (xy 72.528076 -271.805494) (xy 72.573287 -271.866349)
			(xy 72.611774 -271.931664) (xy 72.6431 -272.0007) (xy 72.66691 -272.072675) (xy 72.682935 -272.146773)
			(xy 72.690994 -272.222154) (xy 72.691498 -272.26006) (xy 73.807577 -272.26006) (xy 73.811612 -272.184356)
			(xy 73.823671 -272.109511) (xy 73.843617 -272.03637) (xy 73.871224 -271.965765) (xy 73.90618 -271.898494)
			(xy 73.948088 -271.835319) (xy 73.996474 -271.776957) (xy 74.05079 -271.724069) (xy 74.110419 -271.677254)
			(xy 74.174687 -271.637042) (xy 74.242864 -271.60389) (xy 74.31418 -271.578172) (xy 74.387825 -271.56018)
			(xy 74.462965 -271.550118) (xy 74.538749 -271.548099) (xy 74.614319 -271.554148) (xy 74.688817 -271.568195)
			(xy 74.7614 -271.590081) (xy 74.831246 -271.619558) (xy 74.897563 -271.656293) (xy 74.959599 -271.699868)
			(xy 75.016652 -271.74979) (xy 75.068076 -271.805494) (xy 75.113287 -271.866349) (xy 75.151774 -271.931664)
			(xy 75.1831 -272.0007) (xy 75.20691 -272.072675) (xy 75.222935 -272.146773) (xy 75.230994 -272.222154)
			(xy 75.231498 -272.26006) (xy 76.347577 -272.26006) (xy 76.351612 -272.184356) (xy 76.363671 -272.109511)
			(xy 76.383617 -272.03637) (xy 76.411224 -271.965765) (xy 76.44618 -271.898494) (xy 76.488088 -271.835319)
			(xy 76.536474 -271.776957) (xy 76.59079 -271.724069) (xy 76.650419 -271.677254) (xy 76.714687 -271.637042)
			(xy 76.782864 -271.60389) (xy 76.85418 -271.578172) (xy 76.927825 -271.56018) (xy 77.002965 -271.550118)
			(xy 77.078749 -271.548099) (xy 77.154319 -271.554148) (xy 77.228817 -271.568195) (xy 77.3014 -271.590081)
			(xy 77.371246 -271.619558) (xy 77.437563 -271.656293) (xy 77.499599 -271.699868) (xy 77.556652 -271.74979)
			(xy 77.608076 -271.805494) (xy 77.653287 -271.866349) (xy 77.691774 -271.931664) (xy 77.7231 -272.0007)
			(xy 77.74691 -272.072675) (xy 77.762935 -272.146773) (xy 77.770994 -272.222154) (xy 77.771498 -272.26006)
			(xy 78.887577 -272.26006) (xy 78.891612 -272.184356) (xy 78.903671 -272.109511) (xy 78.923617 -272.03637)
			(xy 78.951224 -271.965765) (xy 78.98618 -271.898494) (xy 79.028088 -271.835319) (xy 79.076474 -271.776957)
			(xy 79.13079 -271.724069) (xy 79.190419 -271.677254) (xy 79.254687 -271.637042) (xy 79.322864 -271.60389)
			(xy 79.39418 -271.578172) (xy 79.467825 -271.56018) (xy 79.542965 -271.550118) (xy 79.618749 -271.548099)
			(xy 79.694319 -271.554148) (xy 79.768817 -271.568195) (xy 79.8414 -271.590081) (xy 79.911246 -271.619558)
			(xy 79.977563 -271.656293) (xy 80.039599 -271.699868) (xy 80.096652 -271.74979) (xy 80.148076 -271.805494)
			(xy 80.193287 -271.866349) (xy 80.231774 -271.931664) (xy 80.2631 -272.0007) (xy 80.28691 -272.072675)
			(xy 80.302935 -272.146773) (xy 80.310994 -272.222154) (xy 80.311498 -272.26006) (xy 81.427577 -272.26006)
			(xy 81.431612 -272.184356) (xy 81.443671 -272.109511) (xy 81.463617 -272.03637) (xy 81.491224 -271.965765)
			(xy 81.52618 -271.898494) (xy 81.568088 -271.835319) (xy 81.616474 -271.776957) (xy 81.67079 -271.724069)
			(xy 81.730419 -271.677254) (xy 81.794687 -271.637042) (xy 81.862864 -271.60389) (xy 81.93418 -271.578172)
			(xy 82.007825 -271.56018) (xy 82.082965 -271.550118) (xy 82.158749 -271.548099) (xy 82.234319 -271.554148)
			(xy 82.308817 -271.568195) (xy 82.3814 -271.590081) (xy 82.451246 -271.619558) (xy 82.517563 -271.656293)
			(xy 82.579599 -271.699868) (xy 82.636652 -271.74979) (xy 82.688076 -271.805494) (xy 82.733287 -271.866349)
			(xy 82.771774 -271.931664) (xy 82.8031 -272.0007) (xy 82.82691 -272.072675) (xy 82.842935 -272.146773)
			(xy 82.850994 -272.222154) (xy 82.851498 -272.26006) (xy 82.850994 -272.297966) (xy 82.842935 -272.373347)
			(xy 82.82691 -272.447445) (xy 82.8031 -272.51942) (xy 82.771774 -272.588456) (xy 82.733287 -272.653771)
			(xy 82.688076 -272.714626) (xy 82.636652 -272.77033) (xy 82.579599 -272.820252) (xy 82.517563 -272.863827)
			(xy 82.451246 -272.900562) (xy 82.3814 -272.930039) (xy 82.308817 -272.951925) (xy 82.234319 -272.965972)
			(xy 82.158749 -272.972021) (xy 82.082965 -272.970002) (xy 82.007825 -272.95994) (xy 81.93418 -272.941948)
			(xy 81.862864 -272.91623) (xy 81.794687 -272.883078) (xy 81.730419 -272.842866) (xy 81.67079 -272.796051)
			(xy 81.616474 -272.743163) (xy 81.568088 -272.684801) (xy 81.52618 -272.621626) (xy 81.491224 -272.554355)
			(xy 81.463617 -272.48375) (xy 81.443671 -272.410609) (xy 81.431612 -272.335764) (xy 81.427577 -272.26006)
			(xy 80.311498 -272.26006) (xy 80.310994 -272.297966) (xy 80.302935 -272.373347) (xy 80.28691 -272.447445)
			(xy 80.2631 -272.51942) (xy 80.231774 -272.588456) (xy 80.193287 -272.653771) (xy 80.148076 -272.714626)
			(xy 80.096652 -272.77033) (xy 80.039599 -272.820252) (xy 79.977563 -272.863827) (xy 79.911246 -272.900562)
			(xy 79.8414 -272.930039) (xy 79.768817 -272.951925) (xy 79.694319 -272.965972) (xy 79.618749 -272.972021)
			(xy 79.542965 -272.970002) (xy 79.467825 -272.95994) (xy 79.39418 -272.941948) (xy 79.322864 -272.91623)
			(xy 79.254687 -272.883078) (xy 79.190419 -272.842866) (xy 79.13079 -272.796051) (xy 79.076474 -272.743163)
			(xy 79.028088 -272.684801) (xy 78.98618 -272.621626) (xy 78.951224 -272.554355) (xy 78.923617 -272.48375)
			(xy 78.903671 -272.410609) (xy 78.891612 -272.335764) (xy 78.887577 -272.26006) (xy 77.771498 -272.26006)
			(xy 77.770994 -272.297966) (xy 77.762935 -272.373347) (xy 77.74691 -272.447445) (xy 77.7231 -272.51942)
			(xy 77.691774 -272.588456) (xy 77.653287 -272.653771) (xy 77.608076 -272.714626) (xy 77.556652 -272.77033)
			(xy 77.499599 -272.820252) (xy 77.437563 -272.863827) (xy 77.371246 -272.900562) (xy 77.3014 -272.930039)
			(xy 77.228817 -272.951925) (xy 77.154319 -272.965972) (xy 77.078749 -272.972021) (xy 77.002965 -272.970002)
			(xy 76.927825 -272.95994) (xy 76.85418 -272.941948) (xy 76.782864 -272.91623) (xy 76.714687 -272.883078)
			(xy 76.650419 -272.842866) (xy 76.59079 -272.796051) (xy 76.536474 -272.743163) (xy 76.488088 -272.684801)
			(xy 76.44618 -272.621626) (xy 76.411224 -272.554355) (xy 76.383617 -272.48375) (xy 76.363671 -272.410609)
			(xy 76.351612 -272.335764) (xy 76.347577 -272.26006) (xy 75.231498 -272.26006) (xy 75.230994 -272.297966)
			(xy 75.222935 -272.373347) (xy 75.20691 -272.447445) (xy 75.1831 -272.51942) (xy 75.151774 -272.588456)
			(xy 75.113287 -272.653771) (xy 75.068076 -272.714626) (xy 75.016652 -272.77033) (xy 74.959599 -272.820252)
			(xy 74.897563 -272.863827) (xy 74.831246 -272.900562) (xy 74.7614 -272.930039) (xy 74.688817 -272.951925)
			(xy 74.614319 -272.965972) (xy 74.538749 -272.972021) (xy 74.462965 -272.970002) (xy 74.387825 -272.95994)
			(xy 74.31418 -272.941948) (xy 74.242864 -272.91623) (xy 74.174687 -272.883078) (xy 74.110419 -272.842866)
			(xy 74.05079 -272.796051) (xy 73.996474 -272.743163) (xy 73.948088 -272.684801) (xy 73.90618 -272.621626)
			(xy 73.871224 -272.554355) (xy 73.843617 -272.48375) (xy 73.823671 -272.410609) (xy 73.811612 -272.335764)
			(xy 73.807577 -272.26006) (xy 72.691498 -272.26006) (xy 72.690994 -272.297966) (xy 72.682935 -272.373347)
			(xy 72.66691 -272.447445) (xy 72.6431 -272.51942) (xy 72.611774 -272.588456) (xy 72.573287 -272.653771)
			(xy 72.528076 -272.714626) (xy 72.476652 -272.77033) (xy 72.419599 -272.820252) (xy 72.357563 -272.863827)
			(xy 72.291246 -272.900562) (xy 72.2214 -272.930039) (xy 72.148817 -272.951925) (xy 72.074319 -272.965972)
			(xy 71.998749 -272.972021) (xy 71.922965 -272.970002) (xy 71.847825 -272.95994) (xy 71.77418 -272.941948)
			(xy 71.702864 -272.91623) (xy 71.634687 -272.883078) (xy 71.570419 -272.842866) (xy 71.51079 -272.796051)
			(xy 71.456474 -272.743163) (xy 71.408088 -272.684801) (xy 71.36618 -272.621626) (xy 71.331224 -272.554355)
			(xy 71.303617 -272.48375) (xy 71.283671 -272.410609) (xy 71.271612 -272.335764) (xy 71.267577 -272.26006)
			(xy 70.151498 -272.26006) (xy 70.150994 -272.297966) (xy 70.142935 -272.373347) (xy 70.12691 -272.447445)
			(xy 70.1031 -272.51942) (xy 70.071774 -272.588456) (xy 70.033287 -272.653771) (xy 69.988076 -272.714626)
			(xy 69.936652 -272.77033) (xy 69.879599 -272.820252) (xy 69.817563 -272.863827) (xy 69.751246 -272.900562)
			(xy 69.6814 -272.930039) (xy 69.608817 -272.951925) (xy 69.534319 -272.965972) (xy 69.458749 -272.972021)
			(xy 69.382965 -272.970002) (xy 69.307825 -272.95994) (xy 69.23418 -272.941948) (xy 69.162864 -272.91623)
			(xy 69.094687 -272.883078) (xy 69.030419 -272.842866) (xy 68.97079 -272.796051) (xy 68.916474 -272.743163)
			(xy 68.868088 -272.684801) (xy 68.82618 -272.621626) (xy 68.791224 -272.554355) (xy 68.763617 -272.48375)
			(xy 68.743671 -272.410609) (xy 68.731612 -272.335764) (xy 68.727577 -272.26006) (xy 67.611498 -272.26006)
			(xy 67.610994 -272.297966) (xy 67.602935 -272.373347) (xy 67.58691 -272.447445) (xy 67.5631 -272.51942)
			(xy 67.531774 -272.588456) (xy 67.493287 -272.653771) (xy 67.448076 -272.714626) (xy 67.396652 -272.77033)
			(xy 67.339599 -272.820252) (xy 67.277563 -272.863827) (xy 67.211246 -272.900562) (xy 67.1414 -272.930039)
			(xy 67.068817 -272.951925) (xy 66.994319 -272.965972) (xy 66.918749 -272.972021) (xy 66.842965 -272.970002)
			(xy 66.767825 -272.95994) (xy 66.69418 -272.941948) (xy 66.622864 -272.91623) (xy 66.554687 -272.883078)
			(xy 66.490419 -272.842866) (xy 66.43079 -272.796051) (xy 66.376474 -272.743163) (xy 66.328088 -272.684801)
			(xy 66.28618 -272.621626) (xy 66.251224 -272.554355) (xy 66.223617 -272.48375) (xy 66.203671 -272.410609)
			(xy 66.191612 -272.335764) (xy 66.187577 -272.26006) (xy 65.071498 -272.26006) (xy 65.070994 -272.297966)
			(xy 65.062935 -272.373347) (xy 65.04691 -272.447445) (xy 65.0231 -272.51942) (xy 64.991774 -272.588456)
			(xy 64.953287 -272.653771) (xy 64.908076 -272.714626) (xy 64.856652 -272.77033) (xy 64.799599 -272.820252)
			(xy 64.737563 -272.863827) (xy 64.671246 -272.900562) (xy 64.6014 -272.930039) (xy 64.528817 -272.951925)
			(xy 64.454319 -272.965972) (xy 64.378749 -272.972021) (xy 64.302965 -272.970002) (xy 64.227825 -272.95994)
			(xy 64.15418 -272.941948) (xy 64.082864 -272.91623) (xy 64.014687 -272.883078) (xy 63.950419 -272.842866)
			(xy 63.89079 -272.796051) (xy 63.836474 -272.743163) (xy 63.788088 -272.684801) (xy 63.74618 -272.621626)
			(xy 63.711224 -272.554355) (xy 63.683617 -272.48375) (xy 63.663671 -272.410609) (xy 63.651612 -272.335764)
			(xy 63.647577 -272.26006) (xy 42.502197 -272.26006) (xy 42.592922 -272.332411) (xy 42.678465 -272.410872)
			(xy 42.758391 -272.495047) (xy 42.832318 -272.584536) (xy 42.899896 -272.678912) (xy 42.960802 -272.777726)
			(xy 43.014745 -272.880506) (xy 43.056327 -272.97507) (xy 84.927697 -272.97507) (xy 84.931732 -272.899366)
			(xy 84.943791 -272.824521) (xy 84.963737 -272.75138) (xy 84.991344 -272.680775) (xy 85.0263 -272.613504)
			(xy 85.068208 -272.550329) (xy 85.116594 -272.491967) (xy 85.17091 -272.439079) (xy 85.230539 -272.392264)
			(xy 85.294807 -272.352052) (xy 85.362984 -272.3189) (xy 85.4343 -272.293182) (xy 85.507945 -272.27519)
			(xy 85.583085 -272.265128) (xy 85.658869 -272.263109) (xy 85.734439 -272.269158) (xy 85.808937 -272.283205)
			(xy 85.88152 -272.305091) (xy 85.951366 -272.334568) (xy 86.017683 -272.371303) (xy 86.079719 -272.414878)
			(xy 86.136772 -272.4648) (xy 86.188196 -272.520504) (xy 86.233407 -272.581359) (xy 86.271894 -272.646674)
			(xy 86.30322 -272.71571) (xy 86.32703 -272.787685) (xy 86.343055 -272.861783) (xy 86.351114 -272.937164)
			(xy 86.351618 -272.97507) (xy 86.351114 -273.012976) (xy 86.343055 -273.088357) (xy 86.32703 -273.162455)
			(xy 86.30322 -273.23443) (xy 86.271894 -273.303466) (xy 86.233407 -273.368781) (xy 86.188196 -273.429636)
			(xy 86.136772 -273.48534) (xy 86.079719 -273.535262) (xy 86.017683 -273.578837) (xy 85.951366 -273.615572)
			(xy 85.88152 -273.645049) (xy 85.808937 -273.666935) (xy 85.734439 -273.680982) (xy 85.658869 -273.687031)
			(xy 85.583085 -273.685012) (xy 85.507945 -273.67495) (xy 85.4343 -273.656958) (xy 85.362984 -273.63124)
			(xy 85.294807 -273.598088) (xy 85.230539 -273.557876) (xy 85.17091 -273.511061) (xy 85.116594 -273.458173)
			(xy 85.068208 -273.399811) (xy 85.0263 -273.336636) (xy 84.991344 -273.269365) (xy 84.963737 -273.19876)
			(xy 84.943791 -273.125619) (xy 84.931732 -273.050774) (xy 84.927697 -272.97507) (xy 43.056327 -272.97507)
			(xy 43.061469 -272.986763) (xy 43.10075 -273.09599) (xy 43.132402 -273.207667) (xy 43.156275 -273.321262)
			(xy 43.172253 -273.436233) (xy 43.180261 -273.552032) (xy 43.180762 -273.61007) (xy 43.180261 -273.668108)
			(xy 43.172253 -273.783907) (xy 43.156275 -273.898878) (xy 43.132402 -274.012473) (xy 43.10075 -274.12415)
			(xy 43.061469 -274.233377) (xy 43.014745 -274.339634) (xy 42.960802 -274.442414) (xy 42.899896 -274.541228)
			(xy 42.832318 -274.635604) (xy 42.758391 -274.725093) (xy 42.678465 -274.809268) (xy 42.592922 -274.887729)
			(xy 42.502197 -274.96008) (xy 63.647577 -274.96008) (xy 63.651612 -274.884376) (xy 63.663671 -274.809531)
			(xy 63.683617 -274.73639) (xy 63.711224 -274.665785) (xy 63.74618 -274.598514) (xy 63.788088 -274.535339)
			(xy 63.836474 -274.476977) (xy 63.89079 -274.424089) (xy 63.950419 -274.377274) (xy 64.014687 -274.337062)
			(xy 64.082864 -274.30391) (xy 64.15418 -274.278192) (xy 64.227825 -274.2602) (xy 64.302965 -274.250138)
			(xy 64.378749 -274.248119) (xy 64.454319 -274.254168) (xy 64.528817 -274.268215) (xy 64.6014 -274.290101)
			(xy 64.671246 -274.319578) (xy 64.737563 -274.356313) (xy 64.799599 -274.399888) (xy 64.856652 -274.44981)
			(xy 64.908076 -274.505514) (xy 64.953287 -274.566369) (xy 64.991774 -274.631684) (xy 65.0231 -274.70072)
			(xy 65.04691 -274.772695) (xy 65.062935 -274.846793) (xy 65.070994 -274.922174) (xy 65.071498 -274.96008)
			(xy 66.187577 -274.96008) (xy 66.191612 -274.884376) (xy 66.203671 -274.809531) (xy 66.223617 -274.73639)
			(xy 66.251224 -274.665785) (xy 66.28618 -274.598514) (xy 66.328088 -274.535339) (xy 66.376474 -274.476977)
			(xy 66.43079 -274.424089) (xy 66.490419 -274.377274) (xy 66.554687 -274.337062) (xy 66.622864 -274.30391)
			(xy 66.69418 -274.278192) (xy 66.767825 -274.2602) (xy 66.842965 -274.250138) (xy 66.918749 -274.248119)
			(xy 66.994319 -274.254168) (xy 67.068817 -274.268215) (xy 67.1414 -274.290101) (xy 67.211246 -274.319578)
			(xy 67.277563 -274.356313) (xy 67.339599 -274.399888) (xy 67.396652 -274.44981) (xy 67.448076 -274.505514)
			(xy 67.493287 -274.566369) (xy 67.531774 -274.631684) (xy 67.5631 -274.70072) (xy 67.58691 -274.772695)
			(xy 67.602935 -274.846793) (xy 67.610994 -274.922174) (xy 67.611498 -274.96008) (xy 68.727577 -274.96008)
			(xy 68.731612 -274.884376) (xy 68.743671 -274.809531) (xy 68.763617 -274.73639) (xy 68.791224 -274.665785)
			(xy 68.82618 -274.598514) (xy 68.868088 -274.535339) (xy 68.916474 -274.476977) (xy 68.97079 -274.424089)
			(xy 69.030419 -274.377274) (xy 69.094687 -274.337062) (xy 69.162864 -274.30391) (xy 69.23418 -274.278192)
			(xy 69.307825 -274.2602) (xy 69.382965 -274.250138) (xy 69.458749 -274.248119) (xy 69.534319 -274.254168)
			(xy 69.608817 -274.268215) (xy 69.6814 -274.290101) (xy 69.751246 -274.319578) (xy 69.817563 -274.356313)
			(xy 69.879599 -274.399888) (xy 69.936652 -274.44981) (xy 69.988076 -274.505514) (xy 70.033287 -274.566369)
			(xy 70.071774 -274.631684) (xy 70.1031 -274.70072) (xy 70.12691 -274.772695) (xy 70.142935 -274.846793)
			(xy 70.150994 -274.922174) (xy 70.151498 -274.96008) (xy 71.267577 -274.96008) (xy 71.271612 -274.884376)
			(xy 71.283671 -274.809531) (xy 71.303617 -274.73639) (xy 71.331224 -274.665785) (xy 71.36618 -274.598514)
			(xy 71.408088 -274.535339) (xy 71.456474 -274.476977) (xy 71.51079 -274.424089) (xy 71.570419 -274.377274)
			(xy 71.634687 -274.337062) (xy 71.702864 -274.30391) (xy 71.77418 -274.278192) (xy 71.847825 -274.2602)
			(xy 71.922965 -274.250138) (xy 71.998749 -274.248119) (xy 72.074319 -274.254168) (xy 72.148817 -274.268215)
			(xy 72.2214 -274.290101) (xy 72.291246 -274.319578) (xy 72.357563 -274.356313) (xy 72.419599 -274.399888)
			(xy 72.476652 -274.44981) (xy 72.528076 -274.505514) (xy 72.573287 -274.566369) (xy 72.611774 -274.631684)
			(xy 72.6431 -274.70072) (xy 72.66691 -274.772695) (xy 72.682935 -274.846793) (xy 72.690994 -274.922174)
			(xy 72.691498 -274.96008) (xy 73.807577 -274.96008) (xy 73.811612 -274.884376) (xy 73.823671 -274.809531)
			(xy 73.843617 -274.73639) (xy 73.871224 -274.665785) (xy 73.90618 -274.598514) (xy 73.948088 -274.535339)
			(xy 73.996474 -274.476977) (xy 74.05079 -274.424089) (xy 74.110419 -274.377274) (xy 74.174687 -274.337062)
			(xy 74.242864 -274.30391) (xy 74.31418 -274.278192) (xy 74.387825 -274.2602) (xy 74.462965 -274.250138)
			(xy 74.538749 -274.248119) (xy 74.614319 -274.254168) (xy 74.688817 -274.268215) (xy 74.7614 -274.290101)
			(xy 74.831246 -274.319578) (xy 74.897563 -274.356313) (xy 74.959599 -274.399888) (xy 75.016652 -274.44981)
			(xy 75.068076 -274.505514) (xy 75.113287 -274.566369) (xy 75.151774 -274.631684) (xy 75.1831 -274.70072)
			(xy 75.20691 -274.772695) (xy 75.222935 -274.846793) (xy 75.230994 -274.922174) (xy 75.231498 -274.96008)
			(xy 76.347577 -274.96008) (xy 76.351612 -274.884376) (xy 76.363671 -274.809531) (xy 76.383617 -274.73639)
			(xy 76.411224 -274.665785) (xy 76.44618 -274.598514) (xy 76.488088 -274.535339) (xy 76.536474 -274.476977)
			(xy 76.59079 -274.424089) (xy 76.650419 -274.377274) (xy 76.714687 -274.337062) (xy 76.782864 -274.30391)
			(xy 76.85418 -274.278192) (xy 76.927825 -274.2602) (xy 77.002965 -274.250138) (xy 77.078749 -274.248119)
			(xy 77.154319 -274.254168) (xy 77.228817 -274.268215) (xy 77.3014 -274.290101) (xy 77.371246 -274.319578)
			(xy 77.437563 -274.356313) (xy 77.499599 -274.399888) (xy 77.556652 -274.44981) (xy 77.608076 -274.505514)
			(xy 77.653287 -274.566369) (xy 77.691774 -274.631684) (xy 77.7231 -274.70072) (xy 77.74691 -274.772695)
			(xy 77.762935 -274.846793) (xy 77.770994 -274.922174) (xy 77.771498 -274.96008) (xy 78.887577 -274.96008)
			(xy 78.891612 -274.884376) (xy 78.903671 -274.809531) (xy 78.923617 -274.73639) (xy 78.951224 -274.665785)
			(xy 78.98618 -274.598514) (xy 79.028088 -274.535339) (xy 79.076474 -274.476977) (xy 79.13079 -274.424089)
			(xy 79.190419 -274.377274) (xy 79.254687 -274.337062) (xy 79.322864 -274.30391) (xy 79.39418 -274.278192)
			(xy 79.467825 -274.2602) (xy 79.542965 -274.250138) (xy 79.618749 -274.248119) (xy 79.694319 -274.254168)
			(xy 79.768817 -274.268215) (xy 79.8414 -274.290101) (xy 79.911246 -274.319578) (xy 79.977563 -274.356313)
			(xy 80.039599 -274.399888) (xy 80.096652 -274.44981) (xy 80.148076 -274.505514) (xy 80.193287 -274.566369)
			(xy 80.231774 -274.631684) (xy 80.2631 -274.70072) (xy 80.28691 -274.772695) (xy 80.302935 -274.846793)
			(xy 80.310994 -274.922174) (xy 80.311498 -274.96008) (xy 81.427577 -274.96008) (xy 81.431612 -274.884376)
			(xy 81.443671 -274.809531) (xy 81.463617 -274.73639) (xy 81.491224 -274.665785) (xy 81.52618 -274.598514)
			(xy 81.568088 -274.535339) (xy 81.616474 -274.476977) (xy 81.67079 -274.424089) (xy 81.730419 -274.377274)
			(xy 81.794687 -274.337062) (xy 81.862864 -274.30391) (xy 81.93418 -274.278192) (xy 82.007825 -274.2602)
			(xy 82.082965 -274.250138) (xy 82.158749 -274.248119) (xy 82.234319 -274.254168) (xy 82.308817 -274.268215)
			(xy 82.3814 -274.290101) (xy 82.451246 -274.319578) (xy 82.517563 -274.356313) (xy 82.579599 -274.399888)
			(xy 82.636652 -274.44981) (xy 82.688076 -274.505514) (xy 82.733287 -274.566369) (xy 82.771774 -274.631684)
			(xy 82.8031 -274.70072) (xy 82.82691 -274.772695) (xy 82.842935 -274.846793) (xy 82.850994 -274.922174)
			(xy 82.851498 -274.96008) (xy 82.850994 -274.997986) (xy 82.842935 -275.073367) (xy 82.82691 -275.147465)
			(xy 82.8031 -275.21944) (xy 82.771774 -275.288476) (xy 82.733287 -275.353791) (xy 82.688076 -275.414646)
			(xy 82.636652 -275.47035) (xy 82.579599 -275.520272) (xy 82.517563 -275.563847) (xy 82.451246 -275.600582)
			(xy 82.3814 -275.630059) (xy 82.308817 -275.651945) (xy 82.234319 -275.665992) (xy 82.158749 -275.672041)
			(xy 82.082965 -275.670022) (xy 82.007825 -275.65996) (xy 81.93418 -275.641968) (xy 81.862864 -275.61625)
			(xy 81.794687 -275.583098) (xy 81.730419 -275.542886) (xy 81.67079 -275.496071) (xy 81.616474 -275.443183)
			(xy 81.568088 -275.384821) (xy 81.52618 -275.321646) (xy 81.491224 -275.254375) (xy 81.463617 -275.18377)
			(xy 81.443671 -275.110629) (xy 81.431612 -275.035784) (xy 81.427577 -274.96008) (xy 80.311498 -274.96008)
			(xy 80.310994 -274.997986) (xy 80.302935 -275.073367) (xy 80.28691 -275.147465) (xy 80.2631 -275.21944)
			(xy 80.231774 -275.288476) (xy 80.193287 -275.353791) (xy 80.148076 -275.414646) (xy 80.096652 -275.47035)
			(xy 80.039599 -275.520272) (xy 79.977563 -275.563847) (xy 79.911246 -275.600582) (xy 79.8414 -275.630059)
			(xy 79.768817 -275.651945) (xy 79.694319 -275.665992) (xy 79.618749 -275.672041) (xy 79.542965 -275.670022)
			(xy 79.467825 -275.65996) (xy 79.39418 -275.641968) (xy 79.322864 -275.61625) (xy 79.254687 -275.583098)
			(xy 79.190419 -275.542886) (xy 79.13079 -275.496071) (xy 79.076474 -275.443183) (xy 79.028088 -275.384821)
			(xy 78.98618 -275.321646) (xy 78.951224 -275.254375) (xy 78.923617 -275.18377) (xy 78.903671 -275.110629)
			(xy 78.891612 -275.035784) (xy 78.887577 -274.96008) (xy 77.771498 -274.96008) (xy 77.770994 -274.997986)
			(xy 77.762935 -275.073367) (xy 77.74691 -275.147465) (xy 77.7231 -275.21944) (xy 77.691774 -275.288476)
			(xy 77.653287 -275.353791) (xy 77.608076 -275.414646) (xy 77.556652 -275.47035) (xy 77.499599 -275.520272)
			(xy 77.437563 -275.563847) (xy 77.371246 -275.600582) (xy 77.3014 -275.630059) (xy 77.228817 -275.651945)
			(xy 77.154319 -275.665992) (xy 77.078749 -275.672041) (xy 77.002965 -275.670022) (xy 76.927825 -275.65996)
			(xy 76.85418 -275.641968) (xy 76.782864 -275.61625) (xy 76.714687 -275.583098) (xy 76.650419 -275.542886)
			(xy 76.59079 -275.496071) (xy 76.536474 -275.443183) (xy 76.488088 -275.384821) (xy 76.44618 -275.321646)
			(xy 76.411224 -275.254375) (xy 76.383617 -275.18377) (xy 76.363671 -275.110629) (xy 76.351612 -275.035784)
			(xy 76.347577 -274.96008) (xy 75.231498 -274.96008) (xy 75.230994 -274.997986) (xy 75.222935 -275.073367)
			(xy 75.20691 -275.147465) (xy 75.1831 -275.21944) (xy 75.151774 -275.288476) (xy 75.113287 -275.353791)
			(xy 75.068076 -275.414646) (xy 75.016652 -275.47035) (xy 74.959599 -275.520272) (xy 74.897563 -275.563847)
			(xy 74.831246 -275.600582) (xy 74.7614 -275.630059) (xy 74.688817 -275.651945) (xy 74.614319 -275.665992)
			(xy 74.538749 -275.672041) (xy 74.462965 -275.670022) (xy 74.387825 -275.65996) (xy 74.31418 -275.641968)
			(xy 74.242864 -275.61625) (xy 74.174687 -275.583098) (xy 74.110419 -275.542886) (xy 74.05079 -275.496071)
			(xy 73.996474 -275.443183) (xy 73.948088 -275.384821) (xy 73.90618 -275.321646) (xy 73.871224 -275.254375)
			(xy 73.843617 -275.18377) (xy 73.823671 -275.110629) (xy 73.811612 -275.035784) (xy 73.807577 -274.96008)
			(xy 72.691498 -274.96008) (xy 72.690994 -274.997986) (xy 72.682935 -275.073367) (xy 72.66691 -275.147465)
			(xy 72.6431 -275.21944) (xy 72.611774 -275.288476) (xy 72.573287 -275.353791) (xy 72.528076 -275.414646)
			(xy 72.476652 -275.47035) (xy 72.419599 -275.520272) (xy 72.357563 -275.563847) (xy 72.291246 -275.600582)
			(xy 72.2214 -275.630059) (xy 72.148817 -275.651945) (xy 72.074319 -275.665992) (xy 71.998749 -275.672041)
			(xy 71.922965 -275.670022) (xy 71.847825 -275.65996) (xy 71.77418 -275.641968) (xy 71.702864 -275.61625)
			(xy 71.634687 -275.583098) (xy 71.570419 -275.542886) (xy 71.51079 -275.496071) (xy 71.456474 -275.443183)
			(xy 71.408088 -275.384821) (xy 71.36618 -275.321646) (xy 71.331224 -275.254375) (xy 71.303617 -275.18377)
			(xy 71.283671 -275.110629) (xy 71.271612 -275.035784) (xy 71.267577 -274.96008) (xy 70.151498 -274.96008)
			(xy 70.150994 -274.997986) (xy 70.142935 -275.073367) (xy 70.12691 -275.147465) (xy 70.1031 -275.21944)
			(xy 70.071774 -275.288476) (xy 70.033287 -275.353791) (xy 69.988076 -275.414646) (xy 69.936652 -275.47035)
			(xy 69.879599 -275.520272) (xy 69.817563 -275.563847) (xy 69.751246 -275.600582) (xy 69.6814 -275.630059)
			(xy 69.608817 -275.651945) (xy 69.534319 -275.665992) (xy 69.458749 -275.672041) (xy 69.382965 -275.670022)
			(xy 69.307825 -275.65996) (xy 69.23418 -275.641968) (xy 69.162864 -275.61625) (xy 69.094687 -275.583098)
			(xy 69.030419 -275.542886) (xy 68.97079 -275.496071) (xy 68.916474 -275.443183) (xy 68.868088 -275.384821)
			(xy 68.82618 -275.321646) (xy 68.791224 -275.254375) (xy 68.763617 -275.18377) (xy 68.743671 -275.110629)
			(xy 68.731612 -275.035784) (xy 68.727577 -274.96008) (xy 67.611498 -274.96008) (xy 67.610994 -274.997986)
			(xy 67.602935 -275.073367) (xy 67.58691 -275.147465) (xy 67.5631 -275.21944) (xy 67.531774 -275.288476)
			(xy 67.493287 -275.353791) (xy 67.448076 -275.414646) (xy 67.396652 -275.47035) (xy 67.339599 -275.520272)
			(xy 67.277563 -275.563847) (xy 67.211246 -275.600582) (xy 67.1414 -275.630059) (xy 67.068817 -275.651945)
			(xy 66.994319 -275.665992) (xy 66.918749 -275.672041) (xy 66.842965 -275.670022) (xy 66.767825 -275.65996)
			(xy 66.69418 -275.641968) (xy 66.622864 -275.61625) (xy 66.554687 -275.583098) (xy 66.490419 -275.542886)
			(xy 66.43079 -275.496071) (xy 66.376474 -275.443183) (xy 66.328088 -275.384821) (xy 66.28618 -275.321646)
			(xy 66.251224 -275.254375) (xy 66.223617 -275.18377) (xy 66.203671 -275.110629) (xy 66.191612 -275.035784)
			(xy 66.187577 -274.96008) (xy 65.071498 -274.96008) (xy 65.070994 -274.997986) (xy 65.062935 -275.073367)
			(xy 65.04691 -275.147465) (xy 65.0231 -275.21944) (xy 64.991774 -275.288476) (xy 64.953287 -275.353791)
			(xy 64.908076 -275.414646) (xy 64.856652 -275.47035) (xy 64.799599 -275.520272) (xy 64.737563 -275.563847)
			(xy 64.671246 -275.600582) (xy 64.6014 -275.630059) (xy 64.528817 -275.651945) (xy 64.454319 -275.665992)
			(xy 64.378749 -275.672041) (xy 64.302965 -275.670022) (xy 64.227825 -275.65996) (xy 64.15418 -275.641968)
			(xy 64.082864 -275.61625) (xy 64.014687 -275.583098) (xy 63.950419 -275.542886) (xy 63.89079 -275.496071)
			(xy 63.836474 -275.443183) (xy 63.788088 -275.384821) (xy 63.74618 -275.321646) (xy 63.711224 -275.254375)
			(xy 63.683617 -275.18377) (xy 63.663671 -275.110629) (xy 63.651612 -275.035784) (xy 63.647577 -274.96008)
			(xy 42.502197 -274.96008) (xy 42.502171 -274.960101) (xy 42.406642 -275.02604) (xy 42.306792 -275.085231)
			(xy 42.203096 -275.137392) (xy 42.096049 -275.182275) (xy 41.98616 -275.219665) (xy 41.873953 -275.249385)
			(xy 41.759963 -275.271293) (xy 41.644734 -275.285284) (xy 41.528813 -275.291293) (xy 41.412755 -275.289289)
			(xy 41.297111 -275.279283) (xy 41.182433 -275.261323) (xy 41.069267 -275.235493) (xy 40.958153 -275.201918)
			(xy 40.84962 -275.160757) (xy 40.744186 -275.112206) (xy 40.642352 -275.056497) (xy 40.544604 -274.993895)
			(xy 40.451409 -274.924699) (xy 40.363209 -274.849237) (xy 40.280426 -274.76787) (xy 40.203453 -274.680986)
			(xy 40.132658 -274.588999) (xy 40.068378 -274.492346) (xy 40.01092 -274.391489) (xy 39.960556 -274.286909)
			(xy 39.917528 -274.179102) (xy 39.88204 -274.068585) (xy 39.854261 -273.955882) (xy 39.834324 -273.841531)
			(xy 39.822323 -273.726077) (xy 39.818317 -273.61007) (xy 31.619463 -273.61007) (xy 32.922856 -274.91336)
			(xy 34.599874 -274.91336) (xy 34.599874 -274.82646) (xy 34.607892 -274.739931) (xy 34.62386 -274.654511)
			(xy 34.647641 -274.570929) (xy 34.679033 -274.489897) (xy 34.717767 -274.412108) (xy 34.763514 -274.338224)
			(xy 34.815883 -274.268877) (xy 34.874427 -274.204657) (xy 34.938647 -274.146113) (xy 35.007994 -274.093744)
			(xy 35.081878 -274.047997) (xy 35.159667 -274.009263) (xy 35.240699 -273.977871) (xy 35.324281 -273.95409)
			(xy 35.409701 -273.938122) (xy 35.49623 -273.930104) (xy 35.58313 -273.930104) (xy 35.669659 -273.938122)
			(xy 35.755079 -273.95409) (xy 35.838661 -273.977871) (xy 35.919693 -274.009263) (xy 35.997482 -274.047997)
			(xy 36.071366 -274.093744) (xy 36.140713 -274.146113) (xy 36.204933 -274.204657) (xy 36.263477 -274.268877)
			(xy 36.315846 -274.338224) (xy 36.361593 -274.412108) (xy 36.400327 -274.489897) (xy 36.431719 -274.570929)
			(xy 36.4555 -274.654511) (xy 36.471468 -274.739931) (xy 36.479486 -274.82646) (xy 36.479988 -274.86991)
			(xy 36.479486 -274.91336) (xy 36.471468 -274.999889) (xy 36.4555 -275.085309) (xy 36.431719 -275.168891)
			(xy 36.400327 -275.249923) (xy 36.361593 -275.327712) (xy 36.315846 -275.401596) (xy 36.263477 -275.470943)
			(xy 36.204933 -275.535163) (xy 36.140713 -275.593707) (xy 36.071366 -275.646076) (xy 35.997482 -275.691823)
			(xy 35.919693 -275.730557) (xy 35.838661 -275.761949) (xy 35.755079 -275.78573) (xy 35.669659 -275.801698)
			(xy 35.58313 -275.809716) (xy 35.49623 -275.809716) (xy 35.409701 -275.801698) (xy 35.324281 -275.78573)
			(xy 35.240699 -275.761949) (xy 35.159667 -275.730557) (xy 35.081878 -275.691823) (xy 35.007994 -275.646076)
			(xy 34.938647 -275.593707) (xy 34.874427 -275.535163) (xy 34.815883 -275.470943) (xy 34.763514 -275.401596)
			(xy 34.717767 -275.327712) (xy 34.679033 -275.249923) (xy 34.647641 -275.168891) (xy 34.62386 -275.085309)
			(xy 34.607892 -274.999889) (xy 34.599874 -274.91336) (xy 32.922856 -274.91336) (xy 34.603944 -276.594316)
			(xy 34.603944 -276.766528) (xy 34.678112 -276.840696) (xy 34.73069 -276.840696) (xy 34.748941 -276.840105)
			(xy 34.783948 -276.829764) (xy 34.814604 -276.80995) (xy 34.826956 -276.7965) (xy 34.85561 -276.763965)
			(xy 34.917978 -276.703735) (xy 34.985625 -276.649502) (xy 35.057978 -276.601727) (xy 35.134421 -276.560815)
			(xy 35.214307 -276.527114) (xy 35.296955 -276.500911) (xy 35.381665 -276.482428) (xy 35.467717 -276.471821)
			(xy 35.554379 -276.469182) (xy 35.640917 -276.474532) (xy 35.726595 -276.487825) (xy 35.810685 -276.50895)
			(xy 35.892473 -276.537726) (xy 35.971265 -276.573909) (xy 36.046391 -276.617192) (xy 36.117213 -276.667208)
			(xy 36.183131 -276.723531) (xy 36.243583 -276.785683) (xy 36.298057 -276.853136) (xy 36.34609 -276.925318)
			(xy 36.387274 -277.001615) (xy 36.421259 -277.08138) (xy 36.447757 -277.163935) (xy 36.466543 -277.248578)
			(xy 36.477456 -277.334591) (xy 36.480405 -277.421244) (xy 36.475364 -277.5078) (xy 36.462376 -277.593525)
			(xy 36.441551 -277.677689) (xy 36.413067 -277.75958) (xy 36.377165 -277.8385) (xy 36.33415 -277.91378)
			(xy 36.284387 -277.984781) (xy 36.2283 -278.050899) (xy 36.166364 -278.111572) (xy 36.099105 -278.166287)
			(xy 36.027095 -278.214577) (xy 35.950945 -278.256033) (xy 35.871302 -278.290302) (xy 35.788843 -278.317094)
			(xy 35.704267 -278.336181) (xy 35.618293 -278.347402) (xy 35.531652 -278.350659) (xy 35.445078 -278.345927)
			(xy 35.359308 -278.333245) (xy 35.275069 -278.312721) (xy 35.193078 -278.284529) (xy 35.11403 -278.248908)
			(xy 35.038597 -278.206162) (xy 35.002724 -278.181816) (xy 34.983473 -278.169109) (xy 34.941474 -278.150054)
			(xy 34.896725 -278.138895) (xy 34.850696 -278.135999) (xy 34.804901 -278.141461) (xy 34.760844 -278.1551)
			(xy 34.719974 -278.17647) (xy 34.683634 -278.204867) (xy 34.653017 -278.239358) (xy 34.629131 -278.27881)
			(xy 34.61276 -278.321927) (xy 34.604443 -278.36729) (xy 34.603944 -278.39035) (xy 34.603944 -278.96947)
			(xy 34.604388 -278.992528) (xy 34.612737 -279.037881) (xy 34.629132 -279.080984) (xy 34.653034 -279.120422)
			(xy 34.683658 -279.154901) (xy 34.72 -279.18329) (xy 34.760867 -279.204656) (xy 34.804918 -279.2183)
			(xy 34.850708 -279.223773) (xy 34.896734 -279.220895) (xy 34.941485 -279.209761) (xy 34.983494 -279.190737)
			(xy 35.002724 -279.178004) (xy 35.038783 -279.1535) (xy 35.11466 -279.110548) (xy 35.194187 -279.074805)
			(xy 35.276681 -279.046577) (xy 35.361435 -279.026108) (xy 35.447719 -279.013572) (xy 35.534793 -279.009078)
			(xy 35.621909 -279.012663) (xy 35.708319 -279.024298) (xy 35.793282 -279.043883) (xy 35.876066 -279.071248)
			(xy 35.955961 -279.10616) (xy 36.032282 -279.148318) (xy 36.104372 -279.19736) (xy 36.171612 -279.252865)
			(xy 36.233426 -279.314356) (xy 36.289281 -279.381306) (xy 36.338699 -279.453139) (xy 36.381255 -279.529239)
			(xy 36.416583 -279.608951) (xy 36.434385 -279.661874) (xy 39.458898 -279.661874) (xy 39.462969 -279.606252)
			(xy 39.475095 -279.551815) (xy 39.495018 -279.499724) (xy 39.522314 -279.451089) (xy 39.5564 -279.406946)
			(xy 39.596549 -279.368237) (xy 39.641907 -279.335786) (xy 39.691507 -279.310285) (xy 39.744291 -279.292278)
			(xy 39.799134 -279.282148) (xy 39.854868 -279.280111) (xy 39.910305 -279.286211) (xy 39.964262 -279.300317)
			(xy 40.015591 -279.322129) (xy 40.063197 -279.351183) (xy 40.106065 -279.386858) (xy 40.143282 -279.428395)
			(xy 40.174055 -279.474908) (xy 40.197727 -279.525405) (xy 40.213795 -279.578812) (xy 40.221915 -279.633988)
			(xy 40.222424 -279.661874) (xy 40.221915 -279.68976) (xy 40.213795 -279.744936) (xy 40.197727 -279.798343)
			(xy 40.174055 -279.84884) (xy 40.143282 -279.895353) (xy 40.106065 -279.93689) (xy 40.063197 -279.972565)
			(xy 40.015591 -280.001619) (xy 39.964262 -280.023431) (xy 39.910305 -280.037537) (xy 39.854868 -280.043637)
			(xy 39.799134 -280.0416) (xy 39.744291 -280.03147) (xy 39.691507 -280.013463) (xy 39.641907 -279.987962)
			(xy 39.596549 -279.955511) (xy 39.5564 -279.916802) (xy 39.522314 -279.872659) (xy 39.495018 -279.824024)
			(xy 39.475095 -279.771933) (xy 39.462969 -279.717496) (xy 39.458898 -279.661874) (xy 36.434385 -279.661874)
			(xy 36.444381 -279.691591) (xy 36.464409 -279.77645) (xy 36.476495 -279.862798) (xy 36.480535 -279.949894)
			(xy 36.476496 -280.036991) (xy 36.464411 -280.123339) (xy 36.444384 -280.208198) (xy 36.416588 -280.290839)
			(xy 36.38126 -280.370551) (xy 36.338705 -280.446651) (xy 36.289288 -280.518485) (xy 36.233434 -280.585435)
			(xy 36.171621 -280.646927) (xy 36.104381 -280.702433) (xy 36.032292 -280.751476) (xy 35.955972 -280.793635)
			(xy 35.876077 -280.828548) (xy 35.793293 -280.855914) (xy 35.708331 -280.8755) (xy 35.621921 -280.887136)
			(xy 35.534804 -280.890723) (xy 35.44773 -280.886229) (xy 35.361446 -280.873695) (xy 35.276692 -280.853226)
			(xy 35.194198 -280.825) (xy 35.11467 -280.789257) (xy 35.038793 -280.746307) (xy 35.002724 -280.721816)
			(xy 34.983473 -280.709109) (xy 34.941474 -280.690054) (xy 34.896725 -280.678895) (xy 34.850696 -280.675999)
			(xy 34.804901 -280.681461) (xy 34.760844 -280.6951) (xy 34.719974 -280.71647) (xy 34.683634 -280.744867)
			(xy 34.653017 -280.779358) (xy 34.629131 -280.81881) (xy 34.61276 -280.861927) (xy 34.604443 -280.90729)
			(xy 34.603944 -280.93035) (xy 34.603944 -281.50947) (xy 34.604388 -281.532528) (xy 34.612737 -281.577881)
			(xy 34.629132 -281.620984) (xy 34.653034 -281.660422) (xy 34.683658 -281.694901) (xy 34.72 -281.72329)
			(xy 34.760867 -281.744656) (xy 34.804918 -281.7583) (xy 34.850708 -281.763773) (xy 34.896734 -281.760895)
			(xy 34.941485 -281.749761) (xy 34.983494 -281.730737) (xy 35.002724 -281.718004) (xy 35.038783 -281.693464)
			(xy 35.114695 -281.650496) (xy 35.194261 -281.614743) (xy 35.276795 -281.586513) (xy 35.36159 -281.566047)
			(xy 35.447915 -281.553522) (xy 35.535029 -281.549046) (xy 35.622184 -281.552657) (xy 35.708629 -281.564324)
			(xy 35.793622 -281.583947) (xy 35.876433 -281.611357) (xy 35.95635 -281.646318) (xy 36.032685 -281.68853)
			(xy 36.104783 -281.737631) (xy 36.172023 -281.793197) (xy 36.233829 -281.854752) (xy 36.289668 -281.921766)
			(xy 36.339061 -281.993664) (xy 36.381583 -282.069827) (xy 36.416868 -282.149601) (xy 36.444614 -282.2323)
			(xy 36.464582 -282.317213) (xy 36.4766 -282.40361) (xy 36.480565 -282.490749) (xy 36.476443 -282.577881)
			(xy 36.464269 -282.664256) (xy 36.444148 -282.749133) (xy 36.416253 -282.831782) (xy 36.380823 -282.911492)
			(xy 36.338164 -282.987578) (xy 36.288641 -283.059386) (xy 36.26104 -283.09316) (xy 36.251378 -283.10553)
			(xy 36.237779 -283.133806) (xy 36.231485 -283.164545) (xy 36.232876 -283.195891) (xy 36.241868 -283.225952)
			(xy 36.257918 -283.252913) (xy 36.26866 -283.264356) (xy 36.932108 -283.927804) (xy 36.932108 -285.245979)
			(xy 51.25211 -285.245979) (xy 51.25211 -285.164869) (xy 51.26006 -285.08415) (xy 51.275883 -285.004599)
			(xy 51.299428 -284.926983) (xy 51.330467 -284.852047) (xy 51.368702 -284.780515) (xy 51.413764 -284.713075)
			(xy 51.465219 -284.650376) (xy 51.522572 -284.593023) (xy 51.585271 -284.541568) (xy 51.652711 -284.496506)
			(xy 51.724243 -284.458271) (xy 51.799179 -284.427232) (xy 51.876795 -284.403687) (xy 51.956346 -284.387864)
			(xy 52.037065 -284.379914) (xy 52.118175 -284.379914) (xy 52.198894 -284.387864) (xy 52.278445 -284.403687)
			(xy 52.356061 -284.427232) (xy 52.430997 -284.458271) (xy 52.502529 -284.496506) (xy 52.569969 -284.541568)
			(xy 52.632668 -284.593023) (xy 52.690021 -284.650376) (xy 52.741476 -284.713075) (xy 52.786538 -284.780515)
			(xy 52.824773 -284.852047) (xy 52.855812 -284.926983) (xy 52.879357 -285.004599) (xy 52.89518 -285.08415)
			(xy 52.90313 -285.164869) (xy 52.903628 -285.205424) (xy 52.90313 -285.245979) (xy 52.89518 -285.326698)
			(xy 52.879357 -285.406249) (xy 52.855812 -285.483865) (xy 52.824773 -285.558801) (xy 52.789861 -285.624117)
			(xy 63.182746 -285.624117) (xy 63.182746 -285.552795) (xy 63.190732 -285.481921) (xy 63.206602 -285.412386)
			(xy 63.230159 -285.345066) (xy 63.261104 -285.280807) (xy 63.29905 -285.220416) (xy 63.343519 -285.164654)
			(xy 63.393952 -285.114221) (xy 63.449714 -285.069752) (xy 63.510105 -285.031806) (xy 63.574364 -285.000861)
			(xy 63.641684 -284.977304) (xy 63.711219 -284.961434) (xy 63.782093 -284.953448) (xy 63.853415 -284.953448)
			(xy 63.924289 -284.961434) (xy 63.993824 -284.977304) (xy 64.061144 -285.000861) (xy 64.125403 -285.031806)
			(xy 64.185794 -285.069752) (xy 64.241556 -285.114221) (xy 64.291989 -285.164654) (xy 64.336458 -285.220416)
			(xy 64.374404 -285.280807) (xy 64.405349 -285.345066) (xy 64.428906 -285.412386) (xy 64.444776 -285.481921)
			(xy 64.452762 -285.552795) (xy 64.453262 -285.588456) (xy 64.452762 -285.624117) (xy 65.714618 -285.624117)
			(xy 65.714618 -285.552795) (xy 65.722604 -285.481921) (xy 65.738474 -285.412386) (xy 65.762031 -285.345066)
			(xy 65.792976 -285.280807) (xy 65.830922 -285.220416) (xy 65.875391 -285.164654) (xy 65.925824 -285.114221)
			(xy 65.981586 -285.069752) (xy 66.041977 -285.031806) (xy 66.106236 -285.000861) (xy 66.173556 -284.977304)
			(xy 66.243091 -284.961434) (xy 66.313965 -284.953448) (xy 66.385287 -284.953448) (xy 66.456161 -284.961434)
			(xy 66.525696 -284.977304) (xy 66.593016 -285.000861) (xy 66.657275 -285.031806) (xy 66.717666 -285.069752)
			(xy 66.773428 -285.114221) (xy 66.823861 -285.164654) (xy 66.86833 -285.220416) (xy 66.906276 -285.280807)
			(xy 66.937221 -285.345066) (xy 66.960778 -285.412386) (xy 66.976648 -285.481921) (xy 66.984634 -285.552795)
			(xy 66.985121 -285.587541) (xy 67.938642 -285.587541) (xy 67.938642 -285.516219) (xy 67.946628 -285.445345)
			(xy 67.962498 -285.37581) (xy 67.986055 -285.30849) (xy 68.017 -285.244231) (xy 68.054946 -285.18384)
			(xy 68.099415 -285.128078) (xy 68.149848 -285.077645) (xy 68.20561 -285.033176) (xy 68.266001 -284.99523)
			(xy 68.33026 -284.964285) (xy 68.39758 -284.940728) (xy 68.467115 -284.924858) (xy 68.537989 -284.916872)
			(xy 68.609311 -284.916872) (xy 68.680185 -284.924858) (xy 68.74972 -284.940728) (xy 68.81704 -284.964285)
			(xy 68.881299 -284.99523) (xy 68.94169 -285.033176) (xy 68.997452 -285.077645) (xy 69.047885 -285.128078)
			(xy 69.092354 -285.18384) (xy 69.1303 -285.244231) (xy 69.161245 -285.30849) (xy 69.184802 -285.37581)
			(xy 69.200672 -285.445345) (xy 69.208658 -285.516219) (xy 69.209149 -285.551219) (xy 70.234802 -285.551219)
			(xy 70.234802 -285.479897) (xy 70.242788 -285.409023) (xy 70.258658 -285.339488) (xy 70.282215 -285.272168)
			(xy 70.31316 -285.207909) (xy 70.351106 -285.147518) (xy 70.395575 -285.091756) (xy 70.446008 -285.041323)
			(xy 70.50177 -284.996854) (xy 70.562161 -284.958908) (xy 70.62642 -284.927963) (xy 70.69374 -284.904406)
			(xy 70.763275 -284.888536) (xy 70.834149 -284.88055) (xy 70.905471 -284.88055) (xy 70.976345 -284.888536)
			(xy 71.04588 -284.904406) (xy 71.1132 -284.927963) (xy 71.177459 -284.958908) (xy 71.23785 -284.996854)
			(xy 71.293612 -285.041323) (xy 71.344045 -285.091756) (xy 71.388514 -285.147518) (xy 71.42646 -285.207909)
			(xy 71.457405 -285.272168) (xy 71.480962 -285.339488) (xy 71.496832 -285.409023) (xy 71.504818 -285.479897)
			(xy 71.505312 -285.515151) (xy 72.609194 -285.515151) (xy 72.609194 -285.443829) (xy 72.61718 -285.372955)
			(xy 72.63305 -285.30342) (xy 72.656607 -285.2361) (xy 72.687552 -285.171841) (xy 72.725498 -285.11145)
			(xy 72.769967 -285.055688) (xy 72.8204 -285.005255) (xy 72.876162 -284.960786) (xy 72.936553 -284.92284)
			(xy 73.000812 -284.891895) (xy 73.068132 -284.868338) (xy 73.137667 -284.852468) (xy 73.208541 -284.844482)
			(xy 73.279863 -284.844482) (xy 73.350737 -284.852468) (xy 73.420272 -284.868338) (xy 73.487592 -284.891895)
			(xy 73.551851 -284.92284) (xy 73.612242 -284.960786) (xy 73.668004 -285.005255) (xy 73.718437 -285.055688)
			(xy 73.762906 -285.11145) (xy 73.800852 -285.171841) (xy 73.831797 -285.2361) (xy 73.855354 -285.30342)
			(xy 73.871224 -285.372955) (xy 73.87921 -285.443829) (xy 73.87971 -285.47949) (xy 73.87921 -285.515151)
			(xy 73.871224 -285.586025) (xy 73.855354 -285.65556) (xy 73.831797 -285.72288) (xy 73.800852 -285.787139)
			(xy 73.762906 -285.84753) (xy 73.718437 -285.903292) (xy 73.668004 -285.953725) (xy 73.612242 -285.998194)
			(xy 73.551851 -286.03614) (xy 73.487592 -286.067085) (xy 73.420272 -286.090642) (xy 73.350737 -286.106512)
			(xy 73.279863 -286.114498) (xy 73.208541 -286.114498) (xy 73.137667 -286.106512) (xy 73.068132 -286.090642)
			(xy 73.000812 -286.067085) (xy 72.936553 -286.03614) (xy 72.876162 -285.998194) (xy 72.8204 -285.953725)
			(xy 72.769967 -285.903292) (xy 72.725498 -285.84753) (xy 72.687552 -285.787139) (xy 72.656607 -285.72288)
			(xy 72.63305 -285.65556) (xy 72.61718 -285.586025) (xy 72.609194 -285.515151) (xy 71.505312 -285.515151)
			(xy 71.505318 -285.515558) (xy 71.504818 -285.551219) (xy 71.496832 -285.622093) (xy 71.480962 -285.691628)
			(xy 71.457405 -285.758948) (xy 71.42646 -285.823207) (xy 71.388514 -285.883598) (xy 71.344045 -285.93936)
			(xy 71.293612 -285.989793) (xy 71.23785 -286.034262) (xy 71.177459 -286.072208) (xy 71.1132 -286.103153)
			(xy 71.04588 -286.12671) (xy 70.976345 -286.14258) (xy 70.905471 -286.150566) (xy 70.834149 -286.150566)
			(xy 70.763275 -286.14258) (xy 70.69374 -286.12671) (xy 70.62642 -286.103153) (xy 70.562161 -286.072208)
			(xy 70.50177 -286.034262) (xy 70.446008 -285.989793) (xy 70.395575 -285.93936) (xy 70.351106 -285.883598)
			(xy 70.31316 -285.823207) (xy 70.282215 -285.758948) (xy 70.258658 -285.691628) (xy 70.242788 -285.622093)
			(xy 70.234802 -285.551219) (xy 69.209149 -285.551219) (xy 69.209158 -285.55188) (xy 69.208658 -285.587541)
			(xy 69.200672 -285.658415) (xy 69.184802 -285.72795) (xy 69.161245 -285.79527) (xy 69.1303 -285.859529)
			(xy 69.092354 -285.91992) (xy 69.047885 -285.975682) (xy 68.997452 -286.026115) (xy 68.94169 -286.070584)
			(xy 68.881299 -286.10853) (xy 68.81704 -286.139475) (xy 68.74972 -286.163032) (xy 68.680185 -286.178902)
			(xy 68.609311 -286.186888) (xy 68.537989 -286.186888) (xy 68.467115 -286.178902) (xy 68.39758 -286.163032)
			(xy 68.33026 -286.139475) (xy 68.266001 -286.10853) (xy 68.20561 -286.070584) (xy 68.149848 -286.026115)
			(xy 68.099415 -285.975682) (xy 68.054946 -285.91992) (xy 68.017 -285.859529) (xy 67.986055 -285.79527)
			(xy 67.962498 -285.72795) (xy 67.946628 -285.658415) (xy 67.938642 -285.587541) (xy 66.985121 -285.587541)
			(xy 66.985134 -285.588456) (xy 66.984634 -285.624117) (xy 66.976648 -285.694991) (xy 66.960778 -285.764526)
			(xy 66.937221 -285.831846) (xy 66.906276 -285.896105) (xy 66.86833 -285.956496) (xy 66.823861 -286.012258)
			(xy 66.773428 -286.062691) (xy 66.717666 -286.10716) (xy 66.657275 -286.145106) (xy 66.593016 -286.176051)
			(xy 66.525696 -286.199608) (xy 66.456161 -286.215478) (xy 66.385287 -286.223464) (xy 66.313965 -286.223464)
			(xy 66.243091 -286.215478) (xy 66.173556 -286.199608) (xy 66.106236 -286.176051) (xy 66.041977 -286.145106)
			(xy 65.981586 -286.10716) (xy 65.925824 -286.062691) (xy 65.875391 -286.012258) (xy 65.830922 -285.956496)
			(xy 65.792976 -285.896105) (xy 65.762031 -285.831846) (xy 65.738474 -285.764526) (xy 65.722604 -285.694991)
			(xy 65.714618 -285.624117) (xy 64.452762 -285.624117) (xy 64.444776 -285.694991) (xy 64.428906 -285.764526)
			(xy 64.405349 -285.831846) (xy 64.374404 -285.896105) (xy 64.336458 -285.956496) (xy 64.291989 -286.012258)
			(xy 64.241556 -286.062691) (xy 64.185794 -286.10716) (xy 64.125403 -286.145106) (xy 64.061144 -286.176051)
			(xy 63.993824 -286.199608) (xy 63.924289 -286.215478) (xy 63.853415 -286.223464) (xy 63.782093 -286.223464)
			(xy 63.711219 -286.215478) (xy 63.641684 -286.199608) (xy 63.574364 -286.176051) (xy 63.510105 -286.145106)
			(xy 63.449714 -286.10716) (xy 63.393952 -286.062691) (xy 63.343519 -286.012258) (xy 63.29905 -285.956496)
			(xy 63.261104 -285.896105) (xy 63.230159 -285.831846) (xy 63.206602 -285.764526) (xy 63.190732 -285.694991)
			(xy 63.182746 -285.624117) (xy 52.789861 -285.624117) (xy 52.786538 -285.630333) (xy 52.741476 -285.697773)
			(xy 52.690021 -285.760472) (xy 52.632668 -285.817825) (xy 52.569969 -285.86928) (xy 52.502529 -285.914342)
			(xy 52.430997 -285.952577) (xy 52.356061 -285.983616) (xy 52.278445 -286.007161) (xy 52.198894 -286.022984)
			(xy 52.118175 -286.030934) (xy 52.037065 -286.030934) (xy 51.956346 -286.022984) (xy 51.876795 -286.007161)
			(xy 51.799179 -285.983616) (xy 51.724243 -285.952577) (xy 51.652711 -285.914342) (xy 51.585271 -285.86928)
			(xy 51.522572 -285.817825) (xy 51.465219 -285.760472) (xy 51.413764 -285.697773) (xy 51.368702 -285.630333)
			(xy 51.330467 -285.558801) (xy 51.299428 -285.483865) (xy 51.275883 -285.406249) (xy 51.26006 -285.326698)
			(xy 51.25211 -285.245979) (xy 36.932108 -285.245979) (xy 36.932108 -285.691326) (xy 36.140898 -286.482536)
			(xy 36.005516 -286.482536) (xy 35.988859 -286.483009) (xy 35.95668 -286.491629) (xy 35.927829 -286.508287)
			(xy 35.904274 -286.531845) (xy 35.887622 -286.560698) (xy 35.879006 -286.592879) (xy 35.878516 -286.609536)
			(xy 35.878516 -286.646366) (xy 35.917124 -286.707834) (xy 35.950144 -286.723836) (xy 35.98863 -286.743092)
			(xy 36.045504 -286.77743) (xy 39.865806 -286.77743) (xy 39.869877 -286.721808) (xy 39.882003 -286.667371)
			(xy 39.901926 -286.61528) (xy 39.929222 -286.566645) (xy 39.963308 -286.522502) (xy 40.003457 -286.483793)
			(xy 40.048815 -286.451342) (xy 40.098415 -286.425841) (xy 40.151199 -286.407834) (xy 40.206042 -286.397704)
			(xy 40.261776 -286.395667) (xy 40.317213 -286.401767) (xy 40.37117 -286.415873) (xy 40.422499 -286.437685)
			(xy 40.470105 -286.466739) (xy 40.512973 -286.502414) (xy 40.55019 -286.543951) (xy 40.580963 -286.590464)
			(xy 40.604635 -286.640961) (xy 40.620703 -286.694368) (xy 40.628823 -286.749544) (xy 40.629332 -286.77743)
			(xy 40.628823 -286.805316) (xy 40.620703 -286.860492) (xy 40.604635 -286.913899) (xy 40.580963 -286.964396)
			(xy 40.55019 -287.010909) (xy 40.512973 -287.052446) (xy 40.470105 -287.088121) (xy 40.422499 -287.117175)
			(xy 40.37117 -287.138987) (xy 40.317213 -287.153093) (xy 40.261776 -287.159193) (xy 40.206042 -287.157156)
			(xy 40.151199 -287.147026) (xy 40.098415 -287.129019) (xy 40.048815 -287.103518) (xy 40.003457 -287.071067)
			(xy 39.963308 -287.032358) (xy 39.929222 -286.988215) (xy 39.901926 -286.93958) (xy 39.882003 -286.887489)
			(xy 39.869877 -286.833052) (xy 39.865806 -286.77743) (xy 36.045504 -286.77743) (xy 36.062305 -286.787574)
			(xy 36.131607 -286.838603) (xy 36.195957 -286.895751) (xy 36.254815 -286.95854) (xy 36.307689 -287.026445)
			(xy 36.354136 -287.098898) (xy 36.393769 -287.175291) (xy 36.426255 -287.254987) (xy 36.451322 -287.337318)
			(xy 36.468761 -287.421595) (xy 36.478426 -287.507113) (xy 36.480236 -287.593156) (xy 36.474176 -287.679005)
			(xy 36.460296 -287.763941) (xy 36.438713 -287.847253) (xy 36.409608 -287.928244) (xy 36.373223 -288.006237)
			(xy 36.329863 -288.080578) (xy 36.279891 -288.150646) (xy 36.223726 -288.215855) (xy 36.161837 -288.275659)
			(xy 36.094742 -288.329557) (xy 36.023002 -288.377098) (xy 35.947218 -288.417885) (xy 35.868025 -288.451576)
			(xy 35.786084 -288.477889) (xy 35.702081 -288.496605) (xy 35.616719 -288.507566) (xy 35.530713 -288.510681)
			(xy 35.444783 -288.505924) (xy 35.359646 -288.493334) (xy 35.276016 -288.473017) (xy 35.194593 -288.445143)
			(xy 35.116057 -288.409945) (xy 35.041066 -288.367718) (xy 34.970248 -288.318815) (xy 34.904195 -288.263646)
			(xy 34.84346 -288.202671) (xy 34.78855 -288.136401) (xy 34.739926 -288.065391) (xy 34.697994 -287.990234)
			(xy 34.663106 -287.911561) (xy 34.635553 -287.830028) (xy 34.615565 -287.746319) (xy 34.60331 -287.661134)
			(xy 34.598891 -287.575185) (xy 34.602344 -287.489192) (xy 34.613641 -287.403874) (xy 34.632687 -287.319946)
			(xy 34.659323 -287.238109) (xy 34.693325 -287.159048) (xy 34.73441 -287.083426) (xy 34.782233 -287.011874)
			(xy 34.836394 -286.944991) (xy 34.866072 -286.913828) (xy 34.881686 -286.897042) (xy 34.90728 -286.859015)
			(xy 34.925637 -286.817014) (xy 34.936163 -286.772401) (xy 34.938516 -286.726624) (xy 34.93262 -286.681167)
			(xy 34.918666 -286.637505) (xy 34.897107 -286.597054) (xy 34.868641 -286.561127) (xy 34.834193 -286.530887)
			(xy 34.794879 -286.507318) (xy 34.751975 -286.491182) (xy 34.706873 -286.483004) (xy 34.683954 -286.482536)
			(xy 31.315406 -286.482536) (xy 31.292482 -286.48293) (xy 31.247373 -286.491116) (xy 31.204463 -286.50726)
			(xy 31.165144 -286.530838) (xy 31.130691 -286.561085) (xy 31.102222 -286.597021) (xy 31.08066 -286.637481)
			(xy 31.066704 -286.681151) (xy 31.060806 -286.726617) (xy 31.063159 -286.772403) (xy 31.073685 -286.817024)
			(xy 31.092043 -286.859035) (xy 31.117638 -286.897071) (xy 31.133288 -286.913828) (xy 31.163367 -286.945419)
			(xy 31.218186 -287.013279) (xy 31.266483 -287.085924) (xy 31.307844 -287.162731) (xy 31.341912 -287.243039)
			(xy 31.368395 -287.326158) (xy 31.387065 -287.411372) (xy 31.397761 -287.497949) (xy 31.400392 -287.585145)
			(xy 31.394935 -287.672209) (xy 31.381437 -287.758394) (xy 31.360014 -287.842958) (xy 31.330849 -287.925174)
			(xy 31.294195 -288.004335) (xy 31.250366 -288.07976) (xy 31.199738 -288.150802) (xy 31.142748 -288.216848)
			(xy 31.079885 -288.277332) (xy 31.01169 -288.331732) (xy 30.938748 -288.379582) (xy 30.861689 -288.42047)
			(xy 30.781173 -288.454044) (xy 30.697893 -288.480016) (xy 30.612566 -288.498161) (xy 30.525925 -288.508326)
			(xy 30.438715 -288.510421) (xy 30.351685 -288.504429) (xy 30.265585 -288.490401) (xy 30.181154 -288.468458)
			(xy 30.099119 -288.438789) (xy 30.020185 -288.401649) (xy 29.94503 -288.357357) (xy 29.874302 -288.306294)
			(xy 29.808607 -288.248899) (xy 29.748511 -288.185665) (xy 29.69453 -288.117137) (xy 29.647129 -288.043903)
			(xy 29.606716 -287.966594) (xy 29.573637 -287.885873) (xy 29.548178 -287.802435) (xy 29.530557 -287.716998)
			(xy 29.520925 -287.630296) (xy 29.519366 -287.543075) (xy 29.525893 -287.456084) (xy 29.54045 -287.370072)
			(xy 29.562911 -287.285777) (xy 29.593083 -287.203926) (xy 29.630708 -287.125222) (xy 29.675461 -287.050341)
			(xy 29.726958 -286.979927) (xy 29.784756 -286.914586) (xy 29.848357 -286.85488) (xy 29.917216 -286.801321)
			(xy 29.953712 -286.77743) (xy 29.972563 -286.764736) (xy 30.005905 -286.733862) (xy 30.033225 -286.69755)
			(xy 30.053652 -286.65696) (xy 30.066535 -286.613384) (xy 30.071465 -286.568211) (xy 30.068282 -286.522882)
			(xy 30.05709 -286.478841) (xy 30.038244 -286.437492) (xy 30.012345 -286.400154) (xy 29.996638 -286.38373)
			(xy 29.953204 -286.340296) (xy 29.934787 -286.321253) (xy 29.902871 -286.278969) (xy 29.877114 -286.232675)
			(xy 29.858012 -286.183262) (xy 29.845931 -286.131681) (xy 29.841106 -286.078924) (xy 29.843627 -286.026007)
			(xy 29.853448 -285.973948) (xy 29.870379 -285.92375) (xy 29.88183 -285.89986) (xy 29.888941 -285.884485)
			(xy 29.895636 -285.85129) (xy 29.893358 -285.817503) (xy 29.882267 -285.785508) (xy 29.863145 -285.75756)
			(xy 29.850588 -285.74619) (xy 29.816547 -285.716517) (xy 29.75367 -285.65169) (xy 29.6973 -285.581133)
			(xy 29.647954 -285.505496) (xy 29.60609 -285.425475) (xy 29.572091 -285.341809) (xy 29.546272 -285.255268)
			(xy 29.52887 -285.16665) (xy 29.520046 -285.076772) (xy 29.519881 -284.986461) (xy 29.528376 -284.896552)
			(xy 29.53639 -284.85211) (xy 29.538924 -284.836558) (xy 29.537116 -284.805108) (xy 29.527659 -284.775059)
			(xy 29.511128 -284.748243) (xy 29.488532 -284.726294) (xy 29.461247 -284.710549) (xy 29.44622 -284.705806)
			(xy 29.414709 -284.696286) (xy 29.354222 -284.670322) (xy 29.297591 -284.636767) (xy 29.245765 -284.596185)
			(xy 29.19961 -284.549253) (xy 29.159898 -284.496757) (xy 29.127293 -284.439574) (xy 29.102342 -284.378661)
			(xy 29.085461 -284.315038) (xy 29.076932 -284.249768) (xy 29.076396 -284.216856) (xy 29.076396 -284.014164)
			(xy 29.075922 -283.991408) (xy 29.067828 -283.946621) (xy 29.051888 -283.903991) (xy 29.02861 -283.864882)
			(xy 28.998739 -283.830544) (xy 28.963231 -283.802074) (xy 28.92322 -283.780383) (xy 28.879986 -283.766164)
			(xy 28.834911 -283.759872) (xy 28.789435 -283.761708) (xy 28.745014 -283.771613) (xy 28.723844 -283.779976)
			(xy 28.698545 -283.790122) (xy 28.645815 -283.803924) (xy 28.591657 -283.81008) (xy 28.537174 -283.808465)
			(xy 28.483475 -283.799114) (xy 28.431654 -283.782215) (xy 28.382766 -283.758113) (xy 28.337805 -283.727298)
			(xy 28.297688 -283.690399) (xy 28.26323 -283.648165) (xy 28.235134 -283.601458) (xy 28.213971 -283.551227)
			(xy 28.200173 -283.498496) (xy 28.194019 -283.444338) (xy 28.195636 -283.389855) (xy 28.204991 -283.336157)
			(xy 28.221892 -283.284337) (xy 28.245997 -283.235449) (xy 28.276814 -283.19049) (xy 28.313715 -283.150375)
			(xy 28.35595 -283.115919) (xy 28.402659 -283.087826) (xy 28.452891 -283.066665) (xy 28.505623 -283.052869)
			(xy 28.559782 -283.046719) (xy 28.614264 -283.048338) (xy 28.667962 -283.057696) (xy 28.719781 -283.0746)
			(xy 28.768667 -283.098707) (xy 28.791408 -283.113734) (xy 28.810599 -283.126231) (xy 28.852407 -283.144908)
			(xy 28.896882 -283.1558) (xy 28.942589 -283.158555) (xy 28.988051 -283.153083) (xy 29.031799 -283.139562)
			(xy 29.072421 -283.118428) (xy 29.108603 -283.090364) (xy 29.139177 -283.056276) (xy 29.15158 -283.037026)
			(xy 29.168486 -283.01041) (xy 29.207871 -282.961168) (xy 29.253049 -282.917181) (xy 29.303326 -282.879126)
			(xy 29.357926 -282.847587) (xy 29.416012 -282.823051) (xy 29.44622 -282.814014) (xy 29.46127 -282.809326)
			(xy 29.488578 -282.793592) (xy 29.511189 -282.771637) (xy 29.527719 -282.744805) (xy 29.537158 -282.714735)
			(xy 29.538928 -282.683269) (xy 29.53639 -282.66771) (xy 29.528457 -282.623688) (xy 29.51996 -282.534637)
			(xy 29.519959 -282.445182) (xy 29.528454 -282.356131) (xy 29.53639 -282.31211) (xy 29.538924 -282.296558)
			(xy 29.537116 -282.265108) (xy 29.527659 -282.235059) (xy 29.511128 -282.208243) (xy 29.488532 -282.186294)
			(xy 29.461247 -282.170549) (xy 29.44622 -282.165806) (xy 29.414709 -282.156286) (xy 29.354222 -282.130322)
			(xy 29.297591 -282.096767) (xy 29.245765 -282.056185) (xy 29.19961 -282.009253) (xy 29.159898 -281.956757)
			(xy 29.127293 -281.899574) (xy 29.102342 -281.838661) (xy 29.085461 -281.775038) (xy 29.076932 -281.709768)
			(xy 29.076396 -281.676856) (xy 29.076396 -280.762964) (xy 29.076882 -280.73005) (xy 29.085419 -280.664776)
			(xy 29.102308 -280.60115) (xy 29.127265 -280.540235) (xy 29.159874 -280.483049) (xy 29.199589 -280.430549)
			(xy 29.245746 -280.383613) (xy 29.297574 -280.343024) (xy 29.354205 -280.309463) (xy 29.414694 -280.28349)
			(xy 29.44622 -280.274014) (xy 29.46127 -280.269326) (xy 29.488578 -280.253592) (xy 29.511189 -280.231637)
			(xy 29.527719 -280.204805) (xy 29.537158 -280.174735) (xy 29.538928 -280.143269) (xy 29.53639 -280.12771)
			(xy 29.528457 -280.083688) (xy 29.51996 -279.994637) (xy 29.519959 -279.905182) (xy 29.528454 -279.816131)
			(xy 29.53639 -279.77211) (xy 29.538924 -279.756558) (xy 29.537116 -279.725108) (xy 29.527659 -279.695059)
			(xy 29.511128 -279.668243) (xy 29.488532 -279.646294) (xy 29.461247 -279.630549) (xy 29.44622 -279.625806)
			(xy 29.414709 -279.616286) (xy 29.354222 -279.590322) (xy 29.297591 -279.556767) (xy 29.245765 -279.516185)
			(xy 29.19961 -279.469253) (xy 29.159898 -279.416757) (xy 29.127293 -279.359574) (xy 29.102342 -279.298661)
			(xy 29.085461 -279.235038) (xy 29.076932 -279.169768) (xy 29.076396 -279.136856) (xy 29.076396 -278.222964)
			(xy 29.076866 -278.191832) (xy 29.084508 -278.130038) (xy 29.099636 -278.069639) (xy 29.122024 -278.011539)
			(xy 29.151336 -277.956606) (xy 29.168852 -277.930864) (xy 29.181087 -277.912797) (xy 29.199744 -277.873356)
			(xy 29.211386 -277.831306) (xy 29.215672 -277.787885) (xy 29.212475 -277.74437) (xy 29.201889 -277.702042)
			(xy 29.184225 -277.662145) (xy 29.160004 -277.625854) (xy 29.129937 -277.594235) (xy 29.094909 -277.568219)
			(xy 29.075634 -277.557992) (xy 29.051799 -277.545548) (xy 29.006648 -277.516343) (xy 28.964837 -277.482531)
			(xy 28.945586 -277.463758) (xy 27.40533 -275.923756) (xy 24.327612 -275.923756) (xy 23.709884 -275.306028)
			(xy 12.767818 -275.306028) (xy 11.116564 -276.957282) (xy 11.116564 -277.716488) (xy 11.088116 -277.744936)
			(xy 26.885136 -277.744936) (xy 26.889207 -277.689314) (xy 26.901333 -277.634877) (xy 26.921256 -277.582786)
			(xy 26.948552 -277.534151) (xy 26.982638 -277.490008) (xy 27.022787 -277.451299) (xy 27.068145 -277.418848)
			(xy 27.117745 -277.393347) (xy 27.170529 -277.37534) (xy 27.225372 -277.36521) (xy 27.281106 -277.363173)
			(xy 27.336543 -277.369273) (xy 27.3905 -277.383379) (xy 27.441829 -277.405191) (xy 27.489435 -277.434245)
			(xy 27.532303 -277.46992) (xy 27.56952 -277.511457) (xy 27.600293 -277.55797) (xy 27.623965 -277.608467)
			(xy 27.640033 -277.661874) (xy 27.648153 -277.71705) (xy 27.648662 -277.744936) (xy 27.648153 -277.772822)
			(xy 27.640033 -277.827998) (xy 27.623965 -277.881405) (xy 27.600293 -277.931902) (xy 27.56952 -277.978415)
			(xy 27.532303 -278.019952) (xy 27.489435 -278.055627) (xy 27.441829 -278.084681) (xy 27.3905 -278.106493)
			(xy 27.336543 -278.120599) (xy 27.281106 -278.126699) (xy 27.225372 -278.124662) (xy 27.170529 -278.114532)
			(xy 27.117745 -278.096525) (xy 27.068145 -278.071024) (xy 27.022787 -278.038573) (xy 26.982638 -277.999864)
			(xy 26.948552 -277.955721) (xy 26.921256 -277.907086) (xy 26.901333 -277.854995) (xy 26.889207 -277.800558)
			(xy 26.885136 -277.744936) (xy 11.088116 -277.744936) (xy 10.956036 -277.877016) (xy 9.679178 -279.15362)
			(xy 9.291828 -279.15362) (xy 9.268488 -279.154901) (xy 9.222834 -279.164917) (xy 9.179781 -279.183107)
			(xy 9.140776 -279.20886) (xy 9.107136 -279.241308) (xy 9.079992 -279.279357) (xy 9.06026 -279.321727)
			(xy 9.048603 -279.366989) (xy 9.045415 -279.413619) (xy 9.050803 -279.460046) (xy 9.057132 -279.48255)
			(xy 9.066968 -279.516084) (xy 9.0801 -279.584727) (xy 9.085622 -279.654395) (xy 9.083469 -279.724249)
			(xy 9.073665 -279.793445) (xy 9.056329 -279.861148) (xy 9.031671 -279.926541) (xy 8.999988 -279.988834)
			(xy 8.961662 -280.047275) (xy 8.917157 -280.101159) (xy 8.867009 -280.149835) (xy 8.839708 -280.171652)
			(xy 8.821496 -280.186458) (xy 8.790323 -280.221538) (xy 8.766122 -280.261745) (xy 8.749716 -280.305714)
			(xy 8.741665 -280.351948) (xy 8.742241 -280.398873) (xy 8.751425 -280.444895) (xy 8.768905 -280.488448)
			(xy 8.794086 -280.52805) (xy 8.809736 -280.54554) (xy 9.127236 -280.86304) (xy 27.247848 -280.86304)
			(xy 27.251919 -280.807418) (xy 27.264045 -280.752981) (xy 27.283968 -280.70089) (xy 27.311264 -280.652255)
			(xy 27.34535 -280.608112) (xy 27.385499 -280.569403) (xy 27.430857 -280.536952) (xy 27.480457 -280.511451)
			(xy 27.533241 -280.493444) (xy 27.588084 -280.483314) (xy 27.643818 -280.481277) (xy 27.699255 -280.487377)
			(xy 27.753212 -280.501483) (xy 27.804541 -280.523295) (xy 27.852147 -280.552349) (xy 27.895015 -280.588024)
			(xy 27.932232 -280.629561) (xy 27.963005 -280.676074) (xy 27.986677 -280.726571) (xy 28.002745 -280.779978)
			(xy 28.010865 -280.835154) (xy 28.011374 -280.86304) (xy 28.010865 -280.890926) (xy 28.002745 -280.946102)
			(xy 27.986677 -280.999509) (xy 27.963005 -281.050006) (xy 27.932232 -281.096519) (xy 27.895015 -281.138056)
			(xy 27.852147 -281.173731) (xy 27.804541 -281.202785) (xy 27.753212 -281.224597) (xy 27.699255 -281.238703)
			(xy 27.643818 -281.244803) (xy 27.588084 -281.242766) (xy 27.533241 -281.232636) (xy 27.480457 -281.214629)
			(xy 27.430857 -281.189128) (xy 27.385499 -281.156677) (xy 27.34535 -281.117968) (xy 27.311264 -281.073825)
			(xy 27.283968 -281.02519) (xy 27.264045 -280.973099) (xy 27.251919 -280.918662) (xy 27.247848 -280.86304)
			(xy 9.127236 -280.86304) (xy 10.968228 -282.704032) (xy 11.238992 -282.974796) (xy 22.838918 -282.974796)
			(xy 23.932896 -284.068774) (xy 26.32659 -284.068774) (xy 26.330661 -284.013152) (xy 26.342787 -283.958715)
			(xy 26.36271 -283.906624) (xy 26.390006 -283.857989) (xy 26.424092 -283.813846) (xy 26.464241 -283.775137)
			(xy 26.509599 -283.742686) (xy 26.559199 -283.717185) (xy 26.611983 -283.699178) (xy 26.666826 -283.689048)
			(xy 26.72256 -283.687011) (xy 26.777997 -283.693111) (xy 26.831954 -283.707217) (xy 26.883283 -283.729029)
			(xy 26.930889 -283.758083) (xy 26.973757 -283.793758) (xy 27.010974 -283.835295) (xy 27.041747 -283.881808)
			(xy 27.065419 -283.932305) (xy 27.081487 -283.985712) (xy 27.089607 -284.040888) (xy 27.090116 -284.068774)
			(xy 27.089607 -284.09666) (xy 27.081487 -284.151836) (xy 27.065419 -284.205243) (xy 27.041747 -284.25574)
			(xy 27.010974 -284.302253) (xy 26.973757 -284.34379) (xy 26.930889 -284.379465) (xy 26.883283 -284.408519)
			(xy 26.831954 -284.430331) (xy 26.777997 -284.444437) (xy 26.72256 -284.450537) (xy 26.666826 -284.4485)
			(xy 26.611983 -284.43837) (xy 26.559199 -284.420363) (xy 26.509599 -284.394862) (xy 26.464241 -284.362411)
			(xy 26.424092 -284.323702) (xy 26.390006 -284.279559) (xy 26.36271 -284.230924) (xy 26.342787 -284.178833)
			(xy 26.330661 -284.124396) (xy 26.32659 -284.068774) (xy 23.932896 -284.068774) (xy 26.749756 -286.885634)
			(xy 26.766181 -286.901348) (xy 26.803522 -286.92726) (xy 26.844876 -286.946119) (xy 26.888924 -286.957323)
			(xy 26.934263 -286.960515) (xy 26.979447 -286.955593) (xy 27.023036 -286.942715) (xy 27.063639 -286.92229)
			(xy 27.099963 -286.89497) (xy 27.13085 -286.861626) (xy 27.155314 -286.823321) (xy 27.172577 -286.781276)
			(xy 27.177746 -286.759142) (xy 27.18389 -286.732529) (xy 27.202767 -286.681276) (xy 27.22876 -286.633239)
			(xy 27.261338 -286.589399) (xy 27.299834 -286.550653) (xy 27.343463 -286.517793) (xy 27.391331 -286.49149)
			(xy 27.442461 -286.472283) (xy 27.495808 -286.460563) (xy 27.55028 -286.45657) (xy 27.604766 -286.460386)
			(xy 27.65815 -286.471933) (xy 27.709342 -286.490975) (xy 27.757295 -286.517122) (xy 27.80103 -286.54984)
			(xy 27.839652 -286.588461) (xy 27.872372 -286.632194) (xy 27.89852 -286.680147) (xy 27.917564 -286.731338)
			(xy 27.929112 -286.784722) (xy 27.93293 -286.839207) (xy 27.928939 -286.89368) (xy 27.917221 -286.947027)
			(xy 27.898015 -286.998158) (xy 27.871714 -287.046027) (xy 27.838855 -287.089656) (xy 27.80011 -287.128154)
			(xy 27.756272 -287.160733) (xy 27.708236 -287.186728) (xy 27.656983 -287.205606) (xy 27.630374 -287.21177)
			(xy 27.608257 -287.217008) (xy 27.566209 -287.234253) (xy 27.527901 -287.258704) (xy 27.494553 -287.28958)
			(xy 27.46723 -287.325896) (xy 27.446803 -287.366493) (xy 27.433925 -287.410077) (xy 27.429005 -287.455256)
			(xy 27.432201 -287.50059) (xy 27.443411 -287.544632) (xy 27.462278 -287.585978) (xy 27.488199 -287.623308)
			(xy 27.503882 -287.63976) (xy 28.446476 -288.582354) (xy 40.10101 -288.582354) (xy 40.105081 -288.526732)
			(xy 40.117207 -288.472295) (xy 40.13713 -288.420204) (xy 40.164426 -288.371569) (xy 40.198512 -288.327426)
			(xy 40.238661 -288.288717) (xy 40.284019 -288.256266) (xy 40.333619 -288.230765) (xy 40.386403 -288.212758)
			(xy 40.441246 -288.202628) (xy 40.49698 -288.200591) (xy 40.552417 -288.206691) (xy 40.606374 -288.220797)
			(xy 40.657703 -288.242609) (xy 40.705309 -288.271663) (xy 40.733264 -288.294927) (xy 63.182746 -288.294927)
			(xy 63.182746 -288.223605) (xy 63.190732 -288.152731) (xy 63.206602 -288.083196) (xy 63.230159 -288.015876)
			(xy 63.261104 -287.951617) (xy 63.29905 -287.891226) (xy 63.343519 -287.835464) (xy 63.393952 -287.785031)
			(xy 63.449714 -287.740562) (xy 63.510105 -287.702616) (xy 63.574364 -287.671671) (xy 63.641684 -287.648114)
			(xy 63.711219 -287.632244) (xy 63.782093 -287.624258) (xy 63.853415 -287.624258) (xy 63.924289 -287.632244)
			(xy 63.993824 -287.648114) (xy 64.061144 -287.671671) (xy 64.125403 -287.702616) (xy 64.185794 -287.740562)
			(xy 64.241556 -287.785031) (xy 64.291989 -287.835464) (xy 64.336458 -287.891226) (xy 64.374404 -287.951617)
			(xy 64.405349 -288.015876) (xy 64.428906 -288.083196) (xy 64.444776 -288.152731) (xy 64.452762 -288.223605)
			(xy 64.453262 -288.259266) (xy 64.452762 -288.294927) (xy 65.714618 -288.294927) (xy 65.714618 -288.223605)
			(xy 65.722604 -288.152731) (xy 65.738474 -288.083196) (xy 65.762031 -288.015876) (xy 65.792976 -287.951617)
			(xy 65.830922 -287.891226) (xy 65.875391 -287.835464) (xy 65.925824 -287.785031) (xy 65.981586 -287.740562)
			(xy 66.041977 -287.702616) (xy 66.106236 -287.671671) (xy 66.173556 -287.648114) (xy 66.243091 -287.632244)
			(xy 66.313965 -287.624258) (xy 66.385287 -287.624258) (xy 66.456161 -287.632244) (xy 66.525696 -287.648114)
			(xy 66.593016 -287.671671) (xy 66.657275 -287.702616) (xy 66.717666 -287.740562) (xy 66.773428 -287.785031)
			(xy 66.823861 -287.835464) (xy 66.86833 -287.891226) (xy 66.906276 -287.951617) (xy 66.937221 -288.015876)
			(xy 66.960778 -288.083196) (xy 66.976648 -288.152731) (xy 66.984634 -288.223605) (xy 66.985121 -288.258351)
			(xy 67.938642 -288.258351) (xy 67.938642 -288.187029) (xy 67.946628 -288.116155) (xy 67.962498 -288.04662)
			(xy 67.986055 -287.9793) (xy 68.017 -287.915041) (xy 68.054946 -287.85465) (xy 68.099415 -287.798888)
			(xy 68.149848 -287.748455) (xy 68.20561 -287.703986) (xy 68.266001 -287.66604) (xy 68.33026 -287.635095)
			(xy 68.39758 -287.611538) (xy 68.467115 -287.595668) (xy 68.537989 -287.587682) (xy 68.609311 -287.587682)
			(xy 68.680185 -287.595668) (xy 68.74972 -287.611538) (xy 68.81704 -287.635095) (xy 68.881299 -287.66604)
			(xy 68.94169 -287.703986) (xy 68.997452 -287.748455) (xy 69.047885 -287.798888) (xy 69.092354 -287.85465)
			(xy 69.1303 -287.915041) (xy 69.161245 -287.9793) (xy 69.184802 -288.04662) (xy 69.200672 -288.116155)
			(xy 69.208658 -288.187029) (xy 69.209149 -288.222029) (xy 70.234802 -288.222029) (xy 70.234802 -288.150707)
			(xy 70.242788 -288.079833) (xy 70.258658 -288.010298) (xy 70.282215 -287.942978) (xy 70.31316 -287.878719)
			(xy 70.351106 -287.818328) (xy 70.395575 -287.762566) (xy 70.446008 -287.712133) (xy 70.50177 -287.667664)
			(xy 70.562161 -287.629718) (xy 70.62642 -287.598773) (xy 70.69374 -287.575216) (xy 70.763275 -287.559346)
			(xy 70.834149 -287.55136) (xy 70.905471 -287.55136) (xy 70.976345 -287.559346) (xy 71.04588 -287.575216)
			(xy 71.1132 -287.598773) (xy 71.177459 -287.629718) (xy 71.23785 -287.667664) (xy 71.293612 -287.712133)
			(xy 71.344045 -287.762566) (xy 71.388514 -287.818328) (xy 71.42646 -287.878719) (xy 71.457405 -287.942978)
			(xy 71.480962 -288.010298) (xy 71.496832 -288.079833) (xy 71.504818 -288.150707) (xy 71.505312 -288.185961)
			(xy 72.609194 -288.185961) (xy 72.609194 -288.114639) (xy 72.61718 -288.043765) (xy 72.63305 -287.97423)
			(xy 72.656607 -287.90691) (xy 72.687552 -287.842651) (xy 72.725498 -287.78226) (xy 72.769967 -287.726498)
			(xy 72.8204 -287.676065) (xy 72.876162 -287.631596) (xy 72.936553 -287.59365) (xy 73.000812 -287.562705)
			(xy 73.068132 -287.539148) (xy 73.137667 -287.523278) (xy 73.208541 -287.515292) (xy 73.279863 -287.515292)
			(xy 73.350737 -287.523278) (xy 73.420272 -287.539148) (xy 73.487592 -287.562705) (xy 73.551851 -287.59365)
			(xy 73.612242 -287.631596) (xy 73.668004 -287.676065) (xy 73.718437 -287.726498) (xy 73.762906 -287.78226)
			(xy 73.800852 -287.842651) (xy 73.831797 -287.90691) (xy 73.855354 -287.97423) (xy 73.871224 -288.043765)
			(xy 73.87921 -288.114639) (xy 73.87971 -288.1503) (xy 73.87921 -288.185961) (xy 73.871224 -288.256835)
			(xy 73.855354 -288.32637) (xy 73.831797 -288.39369) (xy 73.800852 -288.457949) (xy 73.762906 -288.51834)
			(xy 73.718437 -288.574102) (xy 73.668004 -288.624535) (xy 73.612242 -288.669004) (xy 73.551851 -288.70695)
			(xy 73.487592 -288.737895) (xy 73.420272 -288.761452) (xy 73.350737 -288.777322) (xy 73.279863 -288.785308)
			(xy 73.208541 -288.785308) (xy 73.137667 -288.777322) (xy 73.068132 -288.761452) (xy 73.000812 -288.737895)
			(xy 72.936553 -288.70695) (xy 72.876162 -288.669004) (xy 72.8204 -288.624535) (xy 72.769967 -288.574102)
			(xy 72.725498 -288.51834) (xy 72.687552 -288.457949) (xy 72.656607 -288.39369) (xy 72.63305 -288.32637)
			(xy 72.61718 -288.256835) (xy 72.609194 -288.185961) (xy 71.505312 -288.185961) (xy 71.505318 -288.186368)
			(xy 71.504818 -288.222029) (xy 71.496832 -288.292903) (xy 71.480962 -288.362438) (xy 71.457405 -288.429758)
			(xy 71.42646 -288.494017) (xy 71.388514 -288.554408) (xy 71.344045 -288.61017) (xy 71.293612 -288.660603)
			(xy 71.23785 -288.705072) (xy 71.177459 -288.743018) (xy 71.1132 -288.773963) (xy 71.04588 -288.79752)
			(xy 70.976345 -288.81339) (xy 70.905471 -288.821376) (xy 70.834149 -288.821376) (xy 70.763275 -288.81339)
			(xy 70.69374 -288.79752) (xy 70.62642 -288.773963) (xy 70.562161 -288.743018) (xy 70.50177 -288.705072)
			(xy 70.446008 -288.660603) (xy 70.395575 -288.61017) (xy 70.351106 -288.554408) (xy 70.31316 -288.494017)
			(xy 70.282215 -288.429758) (xy 70.258658 -288.362438) (xy 70.242788 -288.292903) (xy 70.234802 -288.222029)
			(xy 69.209149 -288.222029) (xy 69.209158 -288.22269) (xy 69.208658 -288.258351) (xy 69.200672 -288.329225)
			(xy 69.184802 -288.39876) (xy 69.161245 -288.46608) (xy 69.1303 -288.530339) (xy 69.092354 -288.59073)
			(xy 69.047885 -288.646492) (xy 68.997452 -288.696925) (xy 68.94169 -288.741394) (xy 68.881299 -288.77934)
			(xy 68.81704 -288.810285) (xy 68.74972 -288.833842) (xy 68.680185 -288.849712) (xy 68.609311 -288.857698)
			(xy 68.537989 -288.857698) (xy 68.467115 -288.849712) (xy 68.39758 -288.833842) (xy 68.33026 -288.810285)
			(xy 68.266001 -288.77934) (xy 68.20561 -288.741394) (xy 68.149848 -288.696925) (xy 68.099415 -288.646492)
			(xy 68.054946 -288.59073) (xy 68.017 -288.530339) (xy 67.986055 -288.46608) (xy 67.962498 -288.39876)
			(xy 67.946628 -288.329225) (xy 67.938642 -288.258351) (xy 66.985121 -288.258351) (xy 66.985134 -288.259266)
			(xy 66.984634 -288.294927) (xy 66.976648 -288.365801) (xy 66.960778 -288.435336) (xy 66.937221 -288.502656)
			(xy 66.906276 -288.566915) (xy 66.86833 -288.627306) (xy 66.823861 -288.683068) (xy 66.773428 -288.733501)
			(xy 66.717666 -288.77797) (xy 66.657275 -288.815916) (xy 66.593016 -288.846861) (xy 66.525696 -288.870418)
			(xy 66.456161 -288.886288) (xy 66.385287 -288.894274) (xy 66.313965 -288.894274) (xy 66.243091 -288.886288)
			(xy 66.173556 -288.870418) (xy 66.106236 -288.846861) (xy 66.041977 -288.815916) (xy 65.981586 -288.77797)
			(xy 65.925824 -288.733501) (xy 65.875391 -288.683068) (xy 65.830922 -288.627306) (xy 65.792976 -288.566915)
			(xy 65.762031 -288.502656) (xy 65.738474 -288.435336) (xy 65.722604 -288.365801) (xy 65.714618 -288.294927)
			(xy 64.452762 -288.294927) (xy 64.444776 -288.365801) (xy 64.428906 -288.435336) (xy 64.405349 -288.502656)
			(xy 64.374404 -288.566915) (xy 64.336458 -288.627306) (xy 64.291989 -288.683068) (xy 64.241556 -288.733501)
			(xy 64.185794 -288.77797) (xy 64.125403 -288.815916) (xy 64.061144 -288.846861) (xy 63.993824 -288.870418)
			(xy 63.924289 -288.886288) (xy 63.853415 -288.894274) (xy 63.782093 -288.894274) (xy 63.711219 -288.886288)
			(xy 63.641684 -288.870418) (xy 63.574364 -288.846861) (xy 63.510105 -288.815916) (xy 63.449714 -288.77797)
			(xy 63.393952 -288.733501) (xy 63.343519 -288.683068) (xy 63.29905 -288.627306) (xy 63.261104 -288.566915)
			(xy 63.230159 -288.502656) (xy 63.206602 -288.435336) (xy 63.190732 -288.365801) (xy 63.182746 -288.294927)
			(xy 40.733264 -288.294927) (xy 40.748177 -288.307338) (xy 40.785394 -288.348875) (xy 40.816167 -288.395388)
			(xy 40.839839 -288.445885) (xy 40.855907 -288.499292) (xy 40.864027 -288.554468) (xy 40.864536 -288.582354)
			(xy 40.864027 -288.61024) (xy 40.855907 -288.665416) (xy 40.839839 -288.718823) (xy 40.816167 -288.76932)
			(xy 40.785394 -288.815833) (xy 40.748177 -288.85737) (xy 40.705309 -288.893045) (xy 40.657703 -288.922099)
			(xy 40.606374 -288.943911) (xy 40.552417 -288.958017) (xy 40.49698 -288.964117) (xy 40.441246 -288.96208)
			(xy 40.386403 -288.95195) (xy 40.333619 -288.933943) (xy 40.284019 -288.908442) (xy 40.238661 -288.875991)
			(xy 40.198512 -288.837282) (xy 40.164426 -288.793139) (xy 40.13713 -288.744504) (xy 40.117207 -288.692413)
			(xy 40.105081 -288.637976) (xy 40.10101 -288.582354) (xy 28.446476 -288.582354) (xy 29.73324 -289.869118)
			(xy 29.73324 -290.963197) (xy 63.182746 -290.963197) (xy 63.182746 -290.891875) (xy 63.190732 -290.821001)
			(xy 63.206602 -290.751466) (xy 63.230159 -290.684146) (xy 63.261104 -290.619887) (xy 63.29905 -290.559496)
			(xy 63.343519 -290.503734) (xy 63.393952 -290.453301) (xy 63.449714 -290.408832) (xy 63.510105 -290.370886)
			(xy 63.574364 -290.339941) (xy 63.641684 -290.316384) (xy 63.711219 -290.300514) (xy 63.782093 -290.292528)
			(xy 63.853415 -290.292528) (xy 63.924289 -290.300514) (xy 63.993824 -290.316384) (xy 64.061144 -290.339941)
			(xy 64.125403 -290.370886) (xy 64.185794 -290.408832) (xy 64.241556 -290.453301) (xy 64.291989 -290.503734)
			(xy 64.336458 -290.559496) (xy 64.374404 -290.619887) (xy 64.405349 -290.684146) (xy 64.428906 -290.751466)
			(xy 64.444776 -290.821001) (xy 64.452762 -290.891875) (xy 64.453262 -290.927536) (xy 64.452762 -290.963197)
			(xy 65.714618 -290.963197) (xy 65.714618 -290.891875) (xy 65.722604 -290.821001) (xy 65.738474 -290.751466)
			(xy 65.762031 -290.684146) (xy 65.792976 -290.619887) (xy 65.830922 -290.559496) (xy 65.875391 -290.503734)
			(xy 65.925824 -290.453301) (xy 65.981586 -290.408832) (xy 66.041977 -290.370886) (xy 66.106236 -290.339941)
			(xy 66.173556 -290.316384) (xy 66.243091 -290.300514) (xy 66.313965 -290.292528) (xy 66.385287 -290.292528)
			(xy 66.456161 -290.300514) (xy 66.525696 -290.316384) (xy 66.593016 -290.339941) (xy 66.657275 -290.370886)
			(xy 66.717666 -290.408832) (xy 66.773428 -290.453301) (xy 66.823861 -290.503734) (xy 66.86833 -290.559496)
			(xy 66.906276 -290.619887) (xy 66.937221 -290.684146) (xy 66.960778 -290.751466) (xy 66.976648 -290.821001)
			(xy 66.984634 -290.891875) (xy 66.985121 -290.926621) (xy 67.938642 -290.926621) (xy 67.938642 -290.855299)
			(xy 67.946628 -290.784425) (xy 67.962498 -290.71489) (xy 67.986055 -290.64757) (xy 68.017 -290.583311)
			(xy 68.054946 -290.52292) (xy 68.099415 -290.467158) (xy 68.149848 -290.416725) (xy 68.20561 -290.372256)
			(xy 68.266001 -290.33431) (xy 68.33026 -290.303365) (xy 68.39758 -290.279808) (xy 68.467115 -290.263938)
			(xy 68.537989 -290.255952) (xy 68.609311 -290.255952) (xy 68.680185 -290.263938) (xy 68.74972 -290.279808)
			(xy 68.81704 -290.303365) (xy 68.881299 -290.33431) (xy 68.94169 -290.372256) (xy 68.997452 -290.416725)
			(xy 69.047885 -290.467158) (xy 69.092354 -290.52292) (xy 69.1303 -290.583311) (xy 69.161245 -290.64757)
			(xy 69.184802 -290.71489) (xy 69.200672 -290.784425) (xy 69.208658 -290.855299) (xy 69.209149 -290.890299)
			(xy 70.234802 -290.890299) (xy 70.234802 -290.818977) (xy 70.242788 -290.748103) (xy 70.258658 -290.678568)
			(xy 70.282215 -290.611248) (xy 70.31316 -290.546989) (xy 70.351106 -290.486598) (xy 70.395575 -290.430836)
			(xy 70.446008 -290.380403) (xy 70.50177 -290.335934) (xy 70.562161 -290.297988) (xy 70.62642 -290.267043)
			(xy 70.69374 -290.243486) (xy 70.763275 -290.227616) (xy 70.834149 -290.21963) (xy 70.905471 -290.21963)
			(xy 70.976345 -290.227616) (xy 71.04588 -290.243486) (xy 71.1132 -290.267043) (xy 71.177459 -290.297988)
			(xy 71.23785 -290.335934) (xy 71.293612 -290.380403) (xy 71.344045 -290.430836) (xy 71.388514 -290.486598)
			(xy 71.42646 -290.546989) (xy 71.457405 -290.611248) (xy 71.480962 -290.678568) (xy 71.496832 -290.748103)
			(xy 71.504818 -290.818977) (xy 71.505312 -290.854231) (xy 72.609194 -290.854231) (xy 72.609194 -290.782909)
			(xy 72.61718 -290.712035) (xy 72.63305 -290.6425) (xy 72.656607 -290.57518) (xy 72.687552 -290.510921)
			(xy 72.725498 -290.45053) (xy 72.769967 -290.394768) (xy 72.8204 -290.344335) (xy 72.876162 -290.299866)
			(xy 72.936553 -290.26192) (xy 73.000812 -290.230975) (xy 73.068132 -290.207418) (xy 73.137667 -290.191548)
			(xy 73.208541 -290.183562) (xy 73.279863 -290.183562) (xy 73.350737 -290.191548) (xy 73.420272 -290.207418)
			(xy 73.487592 -290.230975) (xy 73.551851 -290.26192) (xy 73.612242 -290.299866) (xy 73.668004 -290.344335)
			(xy 73.718437 -290.394768) (xy 73.762906 -290.45053) (xy 73.800852 -290.510921) (xy 73.831797 -290.57518)
			(xy 73.855354 -290.6425) (xy 73.871224 -290.712035) (xy 73.87921 -290.782909) (xy 73.87971 -290.81857)
			(xy 73.87921 -290.854231) (xy 73.871224 -290.925105) (xy 73.855354 -290.99464) (xy 73.831797 -291.06196)
			(xy 73.800852 -291.126219) (xy 73.762906 -291.18661) (xy 73.718437 -291.242372) (xy 73.668004 -291.292805)
			(xy 73.612242 -291.337274) (xy 73.551851 -291.37522) (xy 73.487592 -291.406165) (xy 73.420272 -291.429722)
			(xy 73.350737 -291.445592) (xy 73.279863 -291.453578) (xy 73.208541 -291.453578) (xy 73.137667 -291.445592)
			(xy 73.068132 -291.429722) (xy 73.000812 -291.406165) (xy 72.936553 -291.37522) (xy 72.876162 -291.337274)
			(xy 72.8204 -291.292805) (xy 72.769967 -291.242372) (xy 72.725498 -291.18661) (xy 72.687552 -291.126219)
			(xy 72.656607 -291.06196) (xy 72.63305 -290.99464) (xy 72.61718 -290.925105) (xy 72.609194 -290.854231)
			(xy 71.505312 -290.854231) (xy 71.505318 -290.854638) (xy 71.504818 -290.890299) (xy 71.496832 -290.961173)
			(xy 71.480962 -291.030708) (xy 71.457405 -291.098028) (xy 71.42646 -291.162287) (xy 71.388514 -291.222678)
			(xy 71.344045 -291.27844) (xy 71.293612 -291.328873) (xy 71.23785 -291.373342) (xy 71.177459 -291.411288)
			(xy 71.1132 -291.442233) (xy 71.04588 -291.46579) (xy 70.976345 -291.48166) (xy 70.905471 -291.489646)
			(xy 70.834149 -291.489646) (xy 70.763275 -291.48166) (xy 70.69374 -291.46579) (xy 70.62642 -291.442233)
			(xy 70.562161 -291.411288) (xy 70.50177 -291.373342) (xy 70.446008 -291.328873) (xy 70.395575 -291.27844)
			(xy 70.351106 -291.222678) (xy 70.31316 -291.162287) (xy 70.282215 -291.098028) (xy 70.258658 -291.030708)
			(xy 70.242788 -290.961173) (xy 70.234802 -290.890299) (xy 69.209149 -290.890299) (xy 69.209158 -290.89096)
			(xy 69.208658 -290.926621) (xy 69.200672 -290.997495) (xy 69.184802 -291.06703) (xy 69.161245 -291.13435)
			(xy 69.1303 -291.198609) (xy 69.092354 -291.259) (xy 69.047885 -291.314762) (xy 68.997452 -291.365195)
			(xy 68.94169 -291.409664) (xy 68.881299 -291.44761) (xy 68.81704 -291.478555) (xy 68.74972 -291.502112)
			(xy 68.680185 -291.517982) (xy 68.609311 -291.525968) (xy 68.537989 -291.525968) (xy 68.467115 -291.517982)
			(xy 68.39758 -291.502112) (xy 68.33026 -291.478555) (xy 68.266001 -291.44761) (xy 68.20561 -291.409664)
			(xy 68.149848 -291.365195) (xy 68.099415 -291.314762) (xy 68.054946 -291.259) (xy 68.017 -291.198609)
			(xy 67.986055 -291.13435) (xy 67.962498 -291.06703) (xy 67.946628 -290.997495) (xy 67.938642 -290.926621)
			(xy 66.985121 -290.926621) (xy 66.985134 -290.927536) (xy 66.984634 -290.963197) (xy 66.976648 -291.034071)
			(xy 66.960778 -291.103606) (xy 66.937221 -291.170926) (xy 66.906276 -291.235185) (xy 66.86833 -291.295576)
			(xy 66.823861 -291.351338) (xy 66.773428 -291.401771) (xy 66.717666 -291.44624) (xy 66.657275 -291.484186)
			(xy 66.593016 -291.515131) (xy 66.525696 -291.538688) (xy 66.456161 -291.554558) (xy 66.385287 -291.562544)
			(xy 66.313965 -291.562544) (xy 66.243091 -291.554558) (xy 66.173556 -291.538688) (xy 66.106236 -291.515131)
			(xy 66.041977 -291.484186) (xy 65.981586 -291.44624) (xy 65.925824 -291.401771) (xy 65.875391 -291.351338)
			(xy 65.830922 -291.295576) (xy 65.792976 -291.235185) (xy 65.762031 -291.170926) (xy 65.738474 -291.103606)
			(xy 65.722604 -291.034071) (xy 65.714618 -290.963197) (xy 64.452762 -290.963197) (xy 64.444776 -291.034071)
			(xy 64.428906 -291.103606) (xy 64.405349 -291.170926) (xy 64.374404 -291.235185) (xy 64.336458 -291.295576)
			(xy 64.291989 -291.351338) (xy 64.241556 -291.401771) (xy 64.185794 -291.44624) (xy 64.125403 -291.484186)
			(xy 64.061144 -291.515131) (xy 63.993824 -291.538688) (xy 63.924289 -291.554558) (xy 63.853415 -291.562544)
			(xy 63.782093 -291.562544) (xy 63.711219 -291.554558) (xy 63.641684 -291.538688) (xy 63.574364 -291.515131)
			(xy 63.510105 -291.484186) (xy 63.449714 -291.44624) (xy 63.393952 -291.401771) (xy 63.343519 -291.351338)
			(xy 63.29905 -291.295576) (xy 63.261104 -291.235185) (xy 63.230159 -291.170926) (xy 63.206602 -291.103606)
			(xy 63.190732 -291.034071) (xy 63.182746 -290.963197) (xy 29.73324 -290.963197) (xy 29.73324 -295.215564)
			(xy 78.99984 -295.215564) (xy 79.003911 -295.159942) (xy 79.016037 -295.105505) (xy 79.03596 -295.053414)
			(xy 79.063256 -295.004779) (xy 79.097342 -294.960636) (xy 79.137491 -294.921927) (xy 79.182849 -294.889476)
			(xy 79.232449 -294.863975) (xy 79.285233 -294.845968) (xy 79.340076 -294.835838) (xy 79.39581 -294.833801)
			(xy 79.451247 -294.839901) (xy 79.505204 -294.854007) (xy 79.556533 -294.875819) (xy 79.604139 -294.904873)
			(xy 79.647007 -294.940548) (xy 79.684224 -294.982085) (xy 79.714997 -295.028598) (xy 79.738669 -295.079095)
			(xy 79.754737 -295.132502) (xy 79.762857 -295.187678) (xy 79.763366 -295.215564) (xy 79.762857 -295.24345)
			(xy 79.754737 -295.298626) (xy 79.738669 -295.352033) (xy 79.714997 -295.40253) (xy 79.684224 -295.449043)
			(xy 79.647007 -295.49058) (xy 79.604139 -295.526255) (xy 79.556533 -295.555309) (xy 79.505204 -295.577121)
			(xy 79.451247 -295.591227) (xy 79.39581 -295.597327) (xy 79.340076 -295.59529) (xy 79.285233 -295.58516)
			(xy 79.232449 -295.567153) (xy 79.182849 -295.541652) (xy 79.137491 -295.509201) (xy 79.097342 -295.470492)
			(xy 79.063256 -295.426349) (xy 79.03596 -295.377714) (xy 79.016037 -295.325623) (xy 79.003911 -295.271186)
			(xy 78.99984 -295.215564) (xy 29.73324 -295.215564) (xy 29.73324 -297.892216) (xy 79.043274 -297.892216)
			(xy 79.047345 -297.836594) (xy 79.059471 -297.782157) (xy 79.079394 -297.730066) (xy 79.10669 -297.681431)
			(xy 79.140776 -297.637288) (xy 79.180925 -297.598579) (xy 79.226283 -297.566128) (xy 79.275883 -297.540627)
			(xy 79.328667 -297.52262) (xy 79.38351 -297.51249) (xy 79.439244 -297.510453) (xy 79.494681 -297.516553)
			(xy 79.548638 -297.530659) (xy 79.599967 -297.552471) (xy 79.647573 -297.581525) (xy 79.690441 -297.6172)
			(xy 79.727658 -297.658737) (xy 79.758431 -297.70525) (xy 79.782103 -297.755747) (xy 79.798171 -297.809154)
			(xy 79.806291 -297.86433) (xy 79.8068 -297.892216) (xy 81.762344 -297.892216) (xy 81.766415 -297.836594)
			(xy 81.778541 -297.782157) (xy 81.798464 -297.730066) (xy 81.82576 -297.681431) (xy 81.859846 -297.637288)
			(xy 81.899995 -297.598579) (xy 81.945353 -297.566128) (xy 81.994953 -297.540627) (xy 82.047737 -297.52262)
			(xy 82.10258 -297.51249) (xy 82.158314 -297.510453) (xy 82.213751 -297.516553) (xy 82.267708 -297.530659)
			(xy 82.319037 -297.552471) (xy 82.366643 -297.581525) (xy 82.409511 -297.6172) (xy 82.446728 -297.658737)
			(xy 82.477501 -297.70525) (xy 82.501173 -297.755747) (xy 82.517241 -297.809154) (xy 82.525361 -297.86433)
			(xy 82.52587 -297.892216) (xy 82.525361 -297.920102) (xy 82.517241 -297.975278) (xy 82.501173 -298.028685)
			(xy 82.477501 -298.079182) (xy 82.446728 -298.125695) (xy 82.409511 -298.167232) (xy 82.366643 -298.202907)
			(xy 82.319037 -298.231961) (xy 82.267708 -298.253773) (xy 82.213751 -298.267879) (xy 82.158314 -298.273979)
			(xy 82.10258 -298.271942) (xy 82.047737 -298.261812) (xy 81.994953 -298.243805) (xy 81.945353 -298.218304)
			(xy 81.899995 -298.185853) (xy 81.859846 -298.147144) (xy 81.82576 -298.103001) (xy 81.798464 -298.054366)
			(xy 81.778541 -298.002275) (xy 81.766415 -297.947838) (xy 81.762344 -297.892216) (xy 79.8068 -297.892216)
			(xy 79.806291 -297.920102) (xy 79.798171 -297.975278) (xy 79.782103 -298.028685) (xy 79.758431 -298.079182)
			(xy 79.727658 -298.125695) (xy 79.690441 -298.167232) (xy 79.647573 -298.202907) (xy 79.599967 -298.231961)
			(xy 79.548638 -298.253773) (xy 79.494681 -298.267879) (xy 79.439244 -298.273979) (xy 79.38351 -298.271942)
			(xy 79.328667 -298.261812) (xy 79.275883 -298.243805) (xy 79.226283 -298.218304) (xy 79.180925 -298.185853)
			(xy 79.140776 -298.147144) (xy 79.10669 -298.103001) (xy 79.079394 -298.054366) (xy 79.059471 -298.002275)
			(xy 79.047345 -297.947838) (xy 79.043274 -297.892216) (xy 29.73324 -297.892216) (xy 29.73324 -300.887231)
			(xy 70.02322 -300.887231) (xy 70.02322 -300.815909) (xy 70.031206 -300.745035) (xy 70.047076 -300.6755)
			(xy 70.070633 -300.60818) (xy 70.101578 -300.543921) (xy 70.139524 -300.48353) (xy 70.183993 -300.427768)
			(xy 70.234426 -300.377335) (xy 70.290188 -300.332866) (xy 70.350579 -300.29492) (xy 70.414838 -300.263975)
			(xy 70.482158 -300.240418) (xy 70.551693 -300.224548) (xy 70.622567 -300.216562) (xy 70.693889 -300.216562)
			(xy 70.764763 -300.224548) (xy 70.834298 -300.240418) (xy 70.901618 -300.263975) (xy 70.965877 -300.29492)
			(xy 71.026268 -300.332866) (xy 71.08203 -300.377335) (xy 71.132463 -300.427768) (xy 71.176932 -300.48353)
			(xy 71.214878 -300.543921) (xy 71.245823 -300.60818) (xy 71.26938 -300.6755) (xy 71.28525 -300.745035)
			(xy 71.293236 -300.815909) (xy 71.293727 -300.850909) (xy 72.192126 -300.850909) (xy 72.192126 -300.779587)
			(xy 72.200112 -300.708713) (xy 72.215982 -300.639178) (xy 72.239539 -300.571858) (xy 72.270484 -300.507599)
			(xy 72.30843 -300.447208) (xy 72.352899 -300.391446) (xy 72.403332 -300.341013) (xy 72.459094 -300.296544)
			(xy 72.519485 -300.258598) (xy 72.583744 -300.227653) (xy 72.651064 -300.204096) (xy 72.720599 -300.188226)
			(xy 72.791473 -300.18024) (xy 72.862795 -300.18024) (xy 72.933669 -300.188226) (xy 73.003204 -300.204096)
			(xy 73.070524 -300.227653) (xy 73.134783 -300.258598) (xy 73.195174 -300.296544) (xy 73.250936 -300.341013)
			(xy 73.301369 -300.391446) (xy 73.345838 -300.447208) (xy 73.383784 -300.507599) (xy 73.414729 -300.571858)
			(xy 73.438286 -300.639178) (xy 73.454156 -300.708713) (xy 73.462142 -300.779587) (xy 73.462642 -300.815248)
			(xy 73.462142 -300.850909) (xy 73.456017 -300.905265) (xy 74.216506 -300.905265) (xy 74.216506 -300.833943)
			(xy 74.224492 -300.763069) (xy 74.240362 -300.693534) (xy 74.263919 -300.626214) (xy 74.294864 -300.561955)
			(xy 74.33281 -300.501564) (xy 74.377279 -300.445802) (xy 74.427712 -300.395369) (xy 74.483474 -300.3509)
			(xy 74.543865 -300.312954) (xy 74.608124 -300.282009) (xy 74.675444 -300.258452) (xy 74.744979 -300.242582)
			(xy 74.815853 -300.234596) (xy 74.887175 -300.234596) (xy 74.958049 -300.242582) (xy 75.027584 -300.258452)
			(xy 75.094904 -300.282009) (xy 75.159163 -300.312954) (xy 75.219554 -300.3509) (xy 75.275316 -300.395369)
			(xy 75.325749 -300.445802) (xy 75.370218 -300.501564) (xy 75.408164 -300.561955) (xy 75.439109 -300.626214)
			(xy 75.462666 -300.693534) (xy 75.478536 -300.763069) (xy 75.486522 -300.833943) (xy 75.487022 -300.869604)
			(xy 75.486522 -300.905265) (xy 76.367378 -300.905265) (xy 76.367378 -300.833943) (xy 76.375364 -300.763069)
			(xy 76.391234 -300.693534) (xy 76.414791 -300.626214) (xy 76.445736 -300.561955) (xy 76.483682 -300.501564)
			(xy 76.528151 -300.445802) (xy 76.578584 -300.395369) (xy 76.634346 -300.3509) (xy 76.694737 -300.312954)
			(xy 76.758996 -300.282009) (xy 76.826316 -300.258452) (xy 76.895851 -300.242582) (xy 76.966725 -300.234596)
			(xy 77.038047 -300.234596) (xy 77.108921 -300.242582) (xy 77.178456 -300.258452) (xy 77.245776 -300.282009)
			(xy 77.310035 -300.312954) (xy 77.370426 -300.3509) (xy 77.426188 -300.395369) (xy 77.476621 -300.445802)
			(xy 77.52109 -300.501564) (xy 77.559036 -300.561955) (xy 77.589981 -300.626214) (xy 77.613538 -300.693534)
			(xy 77.629408 -300.763069) (xy 77.637394 -300.833943) (xy 77.637894 -300.869604) (xy 77.637398 -300.905011)
			(xy 78.596736 -300.905011) (xy 78.596736 -300.833689) (xy 78.604722 -300.762815) (xy 78.620592 -300.69328)
			(xy 78.644149 -300.62596) (xy 78.675094 -300.561701) (xy 78.71304 -300.50131) (xy 78.757509 -300.445548)
			(xy 78.807942 -300.395115) (xy 78.863704 -300.350646) (xy 78.924095 -300.3127) (xy 78.988354 -300.281755)
			(xy 79.055674 -300.258198) (xy 79.125209 -300.242328) (xy 79.196083 -300.234342) (xy 79.267405 -300.234342)
			(xy 79.338279 -300.242328) (xy 79.407814 -300.258198) (xy 79.475134 -300.281755) (xy 79.539393 -300.3127)
			(xy 79.599784 -300.350646) (xy 79.655546 -300.395115) (xy 79.705979 -300.445548) (xy 79.750448 -300.50131)
			(xy 79.788394 -300.561701) (xy 79.819339 -300.62596) (xy 79.842896 -300.69328) (xy 79.858766 -300.762815)
			(xy 79.866752 -300.833689) (xy 79.867252 -300.86935) (xy 79.866752 -300.905011) (xy 79.858766 -300.975885)
			(xy 79.842896 -301.04542) (xy 79.819339 -301.11274) (xy 79.788394 -301.176999) (xy 79.750448 -301.23739)
			(xy 79.705979 -301.293152) (xy 79.655546 -301.343585) (xy 79.599784 -301.388054) (xy 79.539393 -301.426)
			(xy 79.475134 -301.456945) (xy 79.407814 -301.480502) (xy 79.338279 -301.496372) (xy 79.267405 -301.504358)
			(xy 79.196083 -301.504358) (xy 79.125209 -301.496372) (xy 79.055674 -301.480502) (xy 78.988354 -301.456945)
			(xy 78.924095 -301.426) (xy 78.863704 -301.388054) (xy 78.807942 -301.343585) (xy 78.757509 -301.293152)
			(xy 78.71304 -301.23739) (xy 78.675094 -301.176999) (xy 78.644149 -301.11274) (xy 78.620592 -301.04542)
			(xy 78.604722 -300.975885) (xy 78.596736 -300.905011) (xy 77.637398 -300.905011) (xy 77.637394 -300.905265)
			(xy 77.629408 -300.976139) (xy 77.613538 -301.045674) (xy 77.589981 -301.112994) (xy 77.559036 -301.177253)
			(xy 77.52109 -301.237644) (xy 77.476621 -301.293406) (xy 77.426188 -301.343839) (xy 77.370426 -301.388308)
			(xy 77.310035 -301.426254) (xy 77.245776 -301.457199) (xy 77.178456 -301.480756) (xy 77.108921 -301.496626)
			(xy 77.038047 -301.504612) (xy 76.966725 -301.504612) (xy 76.895851 -301.496626) (xy 76.826316 -301.480756)
			(xy 76.758996 -301.457199) (xy 76.694737 -301.426254) (xy 76.634346 -301.388308) (xy 76.578584 -301.343839)
			(xy 76.528151 -301.293406) (xy 76.483682 -301.237644) (xy 76.445736 -301.177253) (xy 76.414791 -301.112994)
			(xy 76.391234 -301.045674) (xy 76.375364 -300.976139) (xy 76.367378 -300.905265) (xy 75.486522 -300.905265)
			(xy 75.478536 -300.976139) (xy 75.462666 -301.045674) (xy 75.439109 -301.112994) (xy 75.408164 -301.177253)
			(xy 75.370218 -301.237644) (xy 75.325749 -301.293406) (xy 75.275316 -301.343839) (xy 75.219554 -301.388308)
			(xy 75.159163 -301.426254) (xy 75.094904 -301.457199) (xy 75.027584 -301.480756) (xy 74.958049 -301.496626)
			(xy 74.887175 -301.504612) (xy 74.815853 -301.504612) (xy 74.744979 -301.496626) (xy 74.675444 -301.480756)
			(xy 74.608124 -301.457199) (xy 74.543865 -301.426254) (xy 74.483474 -301.388308) (xy 74.427712 -301.343839)
			(xy 74.377279 -301.293406) (xy 74.33281 -301.237644) (xy 74.294864 -301.177253) (xy 74.263919 -301.112994)
			(xy 74.240362 -301.045674) (xy 74.224492 -300.976139) (xy 74.216506 -300.905265) (xy 73.456017 -300.905265)
			(xy 73.454156 -300.921783) (xy 73.438286 -300.991318) (xy 73.414729 -301.058638) (xy 73.383784 -301.122897)
			(xy 73.345838 -301.183288) (xy 73.301369 -301.23905) (xy 73.250936 -301.289483) (xy 73.195174 -301.333952)
			(xy 73.134783 -301.371898) (xy 73.070524 -301.402843) (xy 73.003204 -301.4264) (xy 72.933669 -301.44227)
			(xy 72.862795 -301.450256) (xy 72.791473 -301.450256) (xy 72.720599 -301.44227) (xy 72.651064 -301.4264)
			(xy 72.583744 -301.402843) (xy 72.519485 -301.371898) (xy 72.459094 -301.333952) (xy 72.403332 -301.289483)
			(xy 72.352899 -301.23905) (xy 72.30843 -301.183288) (xy 72.270484 -301.122897) (xy 72.239539 -301.058638)
			(xy 72.215982 -300.991318) (xy 72.200112 -300.921783) (xy 72.192126 -300.850909) (xy 71.293727 -300.850909)
			(xy 71.293736 -300.85157) (xy 71.293236 -300.887231) (xy 71.28525 -300.958105) (xy 71.26938 -301.02764)
			(xy 71.245823 -301.09496) (xy 71.214878 -301.159219) (xy 71.176932 -301.21961) (xy 71.132463 -301.275372)
			(xy 71.08203 -301.325805) (xy 71.026268 -301.370274) (xy 70.965877 -301.40822) (xy 70.901618 -301.439165)
			(xy 70.834298 -301.462722) (xy 70.764763 -301.478592) (xy 70.693889 -301.486578) (xy 70.622567 -301.486578)
			(xy 70.551693 -301.478592) (xy 70.482158 -301.462722) (xy 70.414838 -301.439165) (xy 70.350579 -301.40822)
			(xy 70.290188 -301.370274) (xy 70.234426 -301.325805) (xy 70.183993 -301.275372) (xy 70.139524 -301.21961)
			(xy 70.101578 -301.159219) (xy 70.070633 -301.09496) (xy 70.047076 -301.02764) (xy 70.031206 -300.958105)
			(xy 70.02322 -300.887231) (xy 29.73324 -300.887231) (xy 29.73324 -302.850143) (xy 70.02322 -302.850143)
			(xy 70.02322 -302.778821) (xy 70.031206 -302.707947) (xy 70.047076 -302.638412) (xy 70.070633 -302.571092)
			(xy 70.101578 -302.506833) (xy 70.139524 -302.446442) (xy 70.183993 -302.39068) (xy 70.234426 -302.340247)
			(xy 70.290188 -302.295778) (xy 70.350579 -302.257832) (xy 70.414838 -302.226887) (xy 70.482158 -302.20333)
			(xy 70.551693 -302.18746) (xy 70.622567 -302.179474) (xy 70.693889 -302.179474) (xy 70.764763 -302.18746)
			(xy 70.834298 -302.20333) (xy 70.901618 -302.226887) (xy 70.965877 -302.257832) (xy 71.026268 -302.295778)
			(xy 71.08203 -302.340247) (xy 71.132463 -302.39068) (xy 71.176932 -302.446442) (xy 71.214878 -302.506833)
			(xy 71.245823 -302.571092) (xy 71.26938 -302.638412) (xy 71.28525 -302.707947) (xy 71.293236 -302.778821)
			(xy 71.293727 -302.813821) (xy 72.192126 -302.813821) (xy 72.192126 -302.742499) (xy 72.200112 -302.671625)
			(xy 72.215982 -302.60209) (xy 72.239539 -302.53477) (xy 72.270484 -302.470511) (xy 72.30843 -302.41012)
			(xy 72.352899 -302.354358) (xy 72.403332 -302.303925) (xy 72.459094 -302.259456) (xy 72.519485 -302.22151)
			(xy 72.583744 -302.190565) (xy 72.651064 -302.167008) (xy 72.720599 -302.151138) (xy 72.791473 -302.143152)
			(xy 72.862795 -302.143152) (xy 72.933669 -302.151138) (xy 73.003204 -302.167008) (xy 73.070524 -302.190565)
			(xy 73.134783 -302.22151) (xy 73.195174 -302.259456) (xy 73.250936 -302.303925) (xy 73.301369 -302.354358)
			(xy 73.345838 -302.41012) (xy 73.383784 -302.470511) (xy 73.414729 -302.53477) (xy 73.438286 -302.60209)
			(xy 73.454156 -302.671625) (xy 73.462142 -302.742499) (xy 73.462642 -302.77816) (xy 73.462142 -302.813821)
			(xy 73.456017 -302.868177) (xy 74.216506 -302.868177) (xy 74.216506 -302.796855) (xy 74.224492 -302.725981)
			(xy 74.240362 -302.656446) (xy 74.263919 -302.589126) (xy 74.294864 -302.524867) (xy 74.33281 -302.464476)
			(xy 74.377279 -302.408714) (xy 74.427712 -302.358281) (xy 74.483474 -302.313812) (xy 74.543865 -302.275866)
			(xy 74.608124 -302.244921) (xy 74.675444 -302.221364) (xy 74.744979 -302.205494) (xy 74.815853 -302.197508)
			(xy 74.887175 -302.197508) (xy 74.958049 -302.205494) (xy 75.027584 -302.221364) (xy 75.094904 -302.244921)
			(xy 75.159163 -302.275866) (xy 75.219554 -302.313812) (xy 75.275316 -302.358281) (xy 75.325749 -302.408714)
			(xy 75.370218 -302.464476) (xy 75.408164 -302.524867) (xy 75.439109 -302.589126) (xy 75.462666 -302.656446)
			(xy 75.478536 -302.725981) (xy 75.486522 -302.796855) (xy 75.487022 -302.832516) (xy 75.486522 -302.868177)
			(xy 76.367378 -302.868177) (xy 76.367378 -302.796855) (xy 76.375364 -302.725981) (xy 76.391234 -302.656446)
			(xy 76.414791 -302.589126) (xy 76.445736 -302.524867) (xy 76.483682 -302.464476) (xy 76.528151 -302.408714)
			(xy 76.578584 -302.358281) (xy 76.634346 -302.313812) (xy 76.694737 -302.275866) (xy 76.758996 -302.244921)
			(xy 76.826316 -302.221364) (xy 76.895851 -302.205494) (xy 76.966725 -302.197508) (xy 77.038047 -302.197508)
			(xy 77.108921 -302.205494) (xy 77.178456 -302.221364) (xy 77.245776 -302.244921) (xy 77.310035 -302.275866)
			(xy 77.370426 -302.313812) (xy 77.426188 -302.358281) (xy 77.476621 -302.408714) (xy 77.52109 -302.464476)
			(xy 77.559036 -302.524867) (xy 77.589981 -302.589126) (xy 77.613538 -302.656446) (xy 77.629408 -302.725981)
			(xy 77.637394 -302.796855) (xy 77.637894 -302.832516) (xy 77.637398 -302.867923) (xy 78.596736 -302.867923)
			(xy 78.596736 -302.796601) (xy 78.604722 -302.725727) (xy 78.620592 -302.656192) (xy 78.644149 -302.588872)
			(xy 78.675094 -302.524613) (xy 78.71304 -302.464222) (xy 78.757509 -302.40846) (xy 78.807942 -302.358027)
			(xy 78.863704 -302.313558) (xy 78.924095 -302.275612) (xy 78.988354 -302.244667) (xy 79.055674 -302.22111)
			(xy 79.125209 -302.20524) (xy 79.196083 -302.197254) (xy 79.267405 -302.197254) (xy 79.338279 -302.20524)
			(xy 79.407814 -302.22111) (xy 79.475134 -302.244667) (xy 79.539393 -302.275612) (xy 79.599784 -302.313558)
			(xy 79.655546 -302.358027) (xy 79.705979 -302.40846) (xy 79.750448 -302.464222) (xy 79.788394 -302.524613)
			(xy 79.819339 -302.588872) (xy 79.842896 -302.656192) (xy 79.858766 -302.725727) (xy 79.866752 -302.796601)
			(xy 79.867252 -302.832262) (xy 79.866752 -302.867923) (xy 79.858766 -302.938797) (xy 79.842896 -303.008332)
			(xy 79.819339 -303.075652) (xy 79.788394 -303.139911) (xy 79.750448 -303.200302) (xy 79.705979 -303.256064)
			(xy 79.655546 -303.306497) (xy 79.599784 -303.350966) (xy 79.539393 -303.388912) (xy 79.475134 -303.419857)
			(xy 79.407814 -303.443414) (xy 79.338279 -303.459284) (xy 79.267405 -303.46727) (xy 79.196083 -303.46727)
			(xy 79.125209 -303.459284) (xy 79.055674 -303.443414) (xy 78.988354 -303.419857) (xy 78.924095 -303.388912)
			(xy 78.863704 -303.350966) (xy 78.807942 -303.306497) (xy 78.757509 -303.256064) (xy 78.71304 -303.200302)
			(xy 78.675094 -303.139911) (xy 78.644149 -303.075652) (xy 78.620592 -303.008332) (xy 78.604722 -302.938797)
			(xy 78.596736 -302.867923) (xy 77.637398 -302.867923) (xy 77.637394 -302.868177) (xy 77.629408 -302.939051)
			(xy 77.613538 -303.008586) (xy 77.589981 -303.075906) (xy 77.559036 -303.140165) (xy 77.52109 -303.200556)
			(xy 77.476621 -303.256318) (xy 77.426188 -303.306751) (xy 77.370426 -303.35122) (xy 77.310035 -303.389166)
			(xy 77.245776 -303.420111) (xy 77.178456 -303.443668) (xy 77.108921 -303.459538) (xy 77.038047 -303.467524)
			(xy 76.966725 -303.467524) (xy 76.895851 -303.459538) (xy 76.826316 -303.443668) (xy 76.758996 -303.420111)
			(xy 76.694737 -303.389166) (xy 76.634346 -303.35122) (xy 76.578584 -303.306751) (xy 76.528151 -303.256318)
			(xy 76.483682 -303.200556) (xy 76.445736 -303.140165) (xy 76.414791 -303.075906) (xy 76.391234 -303.008586)
			(xy 76.375364 -302.939051) (xy 76.367378 -302.868177) (xy 75.486522 -302.868177) (xy 75.478536 -302.939051)
			(xy 75.462666 -303.008586) (xy 75.439109 -303.075906) (xy 75.408164 -303.140165) (xy 75.370218 -303.200556)
			(xy 75.325749 -303.256318) (xy 75.275316 -303.306751) (xy 75.219554 -303.35122) (xy 75.159163 -303.389166)
			(xy 75.094904 -303.420111) (xy 75.027584 -303.443668) (xy 74.958049 -303.459538) (xy 74.887175 -303.467524)
			(xy 74.815853 -303.467524) (xy 74.744979 -303.459538) (xy 74.675444 -303.443668) (xy 74.608124 -303.420111)
			(xy 74.543865 -303.389166) (xy 74.483474 -303.35122) (xy 74.427712 -303.306751) (xy 74.377279 -303.256318)
			(xy 74.33281 -303.200556) (xy 74.294864 -303.140165) (xy 74.263919 -303.075906) (xy 74.240362 -303.008586)
			(xy 74.224492 -302.939051) (xy 74.216506 -302.868177) (xy 73.456017 -302.868177) (xy 73.454156 -302.884695)
			(xy 73.438286 -302.95423) (xy 73.414729 -303.02155) (xy 73.383784 -303.085809) (xy 73.345838 -303.1462)
			(xy 73.301369 -303.201962) (xy 73.250936 -303.252395) (xy 73.195174 -303.296864) (xy 73.134783 -303.33481)
			(xy 73.070524 -303.365755) (xy 73.003204 -303.389312) (xy 72.933669 -303.405182) (xy 72.862795 -303.413168)
			(xy 72.791473 -303.413168) (xy 72.720599 -303.405182) (xy 72.651064 -303.389312) (xy 72.583744 -303.365755)
			(xy 72.519485 -303.33481) (xy 72.459094 -303.296864) (xy 72.403332 -303.252395) (xy 72.352899 -303.201962)
			(xy 72.30843 -303.1462) (xy 72.270484 -303.085809) (xy 72.239539 -303.02155) (xy 72.215982 -302.95423)
			(xy 72.200112 -302.884695) (xy 72.192126 -302.813821) (xy 71.293727 -302.813821) (xy 71.293736 -302.814482)
			(xy 71.293236 -302.850143) (xy 71.28525 -302.921017) (xy 71.26938 -302.990552) (xy 71.245823 -303.057872)
			(xy 71.214878 -303.122131) (xy 71.176932 -303.182522) (xy 71.132463 -303.238284) (xy 71.08203 -303.288717)
			(xy 71.026268 -303.333186) (xy 70.965877 -303.371132) (xy 70.901618 -303.402077) (xy 70.834298 -303.425634)
			(xy 70.764763 -303.441504) (xy 70.693889 -303.44949) (xy 70.622567 -303.44949) (xy 70.551693 -303.441504)
			(xy 70.482158 -303.425634) (xy 70.414838 -303.402077) (xy 70.350579 -303.371132) (xy 70.290188 -303.333186)
			(xy 70.234426 -303.288717) (xy 70.183993 -303.238284) (xy 70.139524 -303.182522) (xy 70.101578 -303.122131)
			(xy 70.070633 -303.057872) (xy 70.047076 -302.990552) (xy 70.031206 -302.921017) (xy 70.02322 -302.850143)
			(xy 29.73324 -302.850143) (xy 29.73324 -304.993649) (xy 70.02322 -304.993649) (xy 70.02322 -304.922327)
			(xy 70.031206 -304.851453) (xy 70.047076 -304.781918) (xy 70.070633 -304.714598) (xy 70.101578 -304.650339)
			(xy 70.139524 -304.589948) (xy 70.183993 -304.534186) (xy 70.234426 -304.483753) (xy 70.290188 -304.439284)
			(xy 70.350579 -304.401338) (xy 70.414838 -304.370393) (xy 70.482158 -304.346836) (xy 70.551693 -304.330966)
			(xy 70.622567 -304.32298) (xy 70.693889 -304.32298) (xy 70.764763 -304.330966) (xy 70.834298 -304.346836)
			(xy 70.901618 -304.370393) (xy 70.965877 -304.401338) (xy 71.026268 -304.439284) (xy 71.08203 -304.483753)
			(xy 71.132463 -304.534186) (xy 71.176932 -304.589948) (xy 71.214878 -304.650339) (xy 71.245823 -304.714598)
			(xy 71.26938 -304.781918) (xy 71.28525 -304.851453) (xy 71.293236 -304.922327) (xy 71.293727 -304.957327)
			(xy 72.192126 -304.957327) (xy 72.192126 -304.886005) (xy 72.200112 -304.815131) (xy 72.215982 -304.745596)
			(xy 72.239539 -304.678276) (xy 72.270484 -304.614017) (xy 72.30843 -304.553626) (xy 72.352899 -304.497864)
			(xy 72.403332 -304.447431) (xy 72.459094 -304.402962) (xy 72.519485 -304.365016) (xy 72.583744 -304.334071)
			(xy 72.651064 -304.310514) (xy 72.720599 -304.294644) (xy 72.791473 -304.286658) (xy 72.862795 -304.286658)
			(xy 72.933669 -304.294644) (xy 73.003204 -304.310514) (xy 73.070524 -304.334071) (xy 73.134783 -304.365016)
			(xy 73.195174 -304.402962) (xy 73.250936 -304.447431) (xy 73.301369 -304.497864) (xy 73.345838 -304.553626)
			(xy 73.383784 -304.614017) (xy 73.414729 -304.678276) (xy 73.438286 -304.745596) (xy 73.454156 -304.815131)
			(xy 73.462142 -304.886005) (xy 73.462642 -304.921666) (xy 73.462142 -304.957327) (xy 73.456017 -305.011683)
			(xy 74.216506 -305.011683) (xy 74.216506 -304.940361) (xy 74.224492 -304.869487) (xy 74.240362 -304.799952)
			(xy 74.263919 -304.732632) (xy 74.294864 -304.668373) (xy 74.33281 -304.607982) (xy 74.377279 -304.55222)
			(xy 74.427712 -304.501787) (xy 74.483474 -304.457318) (xy 74.543865 -304.419372) (xy 74.608124 -304.388427)
			(xy 74.675444 -304.36487) (xy 74.744979 -304.349) (xy 74.815853 -304.341014) (xy 74.887175 -304.341014)
			(xy 74.958049 -304.349) (xy 75.027584 -304.36487) (xy 75.094904 -304.388427) (xy 75.159163 -304.419372)
			(xy 75.219554 -304.457318) (xy 75.275316 -304.501787) (xy 75.325749 -304.55222) (xy 75.370218 -304.607982)
			(xy 75.408164 -304.668373) (xy 75.439109 -304.732632) (xy 75.462666 -304.799952) (xy 75.478536 -304.869487)
			(xy 75.486522 -304.940361) (xy 75.487022 -304.976022) (xy 75.486522 -305.011683) (xy 76.367378 -305.011683)
			(xy 76.367378 -304.940361) (xy 76.375364 -304.869487) (xy 76.391234 -304.799952) (xy 76.414791 -304.732632)
			(xy 76.445736 -304.668373) (xy 76.483682 -304.607982) (xy 76.528151 -304.55222) (xy 76.578584 -304.501787)
			(xy 76.634346 -304.457318) (xy 76.694737 -304.419372) (xy 76.758996 -304.388427) (xy 76.826316 -304.36487)
			(xy 76.895851 -304.349) (xy 76.966725 -304.341014) (xy 77.038047 -304.341014) (xy 77.108921 -304.349)
			(xy 77.178456 -304.36487) (xy 77.245776 -304.388427) (xy 77.310035 -304.419372) (xy 77.370426 -304.457318)
			(xy 77.426188 -304.501787) (xy 77.476621 -304.55222) (xy 77.52109 -304.607982) (xy 77.559036 -304.668373)
			(xy 77.589981 -304.732632) (xy 77.613538 -304.799952) (xy 77.629408 -304.869487) (xy 77.637394 -304.940361)
			(xy 77.637894 -304.976022) (xy 77.637398 -305.011429) (xy 78.596736 -305.011429) (xy 78.596736 -304.940107)
			(xy 78.604722 -304.869233) (xy 78.620592 -304.799698) (xy 78.644149 -304.732378) (xy 78.675094 -304.668119)
			(xy 78.71304 -304.607728) (xy 78.757509 -304.551966) (xy 78.807942 -304.501533) (xy 78.863704 -304.457064)
			(xy 78.924095 -304.419118) (xy 78.988354 -304.388173) (xy 79.055674 -304.364616) (xy 79.125209 -304.348746)
			(xy 79.196083 -304.34076) (xy 79.267405 -304.34076) (xy 79.338279 -304.348746) (xy 79.407814 -304.364616)
			(xy 79.475134 -304.388173) (xy 79.539393 -304.419118) (xy 79.599784 -304.457064) (xy 79.655546 -304.501533)
			(xy 79.705979 -304.551966) (xy 79.750448 -304.607728) (xy 79.788394 -304.668119) (xy 79.819339 -304.732378)
			(xy 79.842896 -304.799698) (xy 79.858766 -304.869233) (xy 79.866752 -304.940107) (xy 79.867252 -304.975768)
			(xy 79.866752 -305.011429) (xy 79.858766 -305.082303) (xy 79.842896 -305.151838) (xy 79.819339 -305.219158)
			(xy 79.788394 -305.283417) (xy 79.750448 -305.343808) (xy 79.705979 -305.39957) (xy 79.655546 -305.450003)
			(xy 79.599784 -305.494472) (xy 79.539393 -305.532418) (xy 79.475134 -305.563363) (xy 79.407814 -305.58692)
			(xy 79.338279 -305.60279) (xy 79.267405 -305.610776) (xy 79.196083 -305.610776) (xy 79.125209 -305.60279)
			(xy 79.055674 -305.58692) (xy 78.988354 -305.563363) (xy 78.924095 -305.532418) (xy 78.863704 -305.494472)
			(xy 78.807942 -305.450003) (xy 78.757509 -305.39957) (xy 78.71304 -305.343808) (xy 78.675094 -305.283417)
			(xy 78.644149 -305.219158) (xy 78.620592 -305.151838) (xy 78.604722 -305.082303) (xy 78.596736 -305.011429)
			(xy 77.637398 -305.011429) (xy 77.637394 -305.011683) (xy 77.629408 -305.082557) (xy 77.613538 -305.152092)
			(xy 77.589981 -305.219412) (xy 77.559036 -305.283671) (xy 77.52109 -305.344062) (xy 77.476621 -305.399824)
			(xy 77.426188 -305.450257) (xy 77.370426 -305.494726) (xy 77.310035 -305.532672) (xy 77.245776 -305.563617)
			(xy 77.178456 -305.587174) (xy 77.108921 -305.603044) (xy 77.038047 -305.61103) (xy 76.966725 -305.61103)
			(xy 76.895851 -305.603044) (xy 76.826316 -305.587174) (xy 76.758996 -305.563617) (xy 76.694737 -305.532672)
			(xy 76.634346 -305.494726) (xy 76.578584 -305.450257) (xy 76.528151 -305.399824) (xy 76.483682 -305.344062)
			(xy 76.445736 -305.283671) (xy 76.414791 -305.219412) (xy 76.391234 -305.152092) (xy 76.375364 -305.082557)
			(xy 76.367378 -305.011683) (xy 75.486522 -305.011683) (xy 75.478536 -305.082557) (xy 75.462666 -305.152092)
			(xy 75.439109 -305.219412) (xy 75.408164 -305.283671) (xy 75.370218 -305.344062) (xy 75.325749 -305.399824)
			(xy 75.275316 -305.450257) (xy 75.219554 -305.494726) (xy 75.159163 -305.532672) (xy 75.094904 -305.563617)
			(xy 75.027584 -305.587174) (xy 74.958049 -305.603044) (xy 74.887175 -305.61103) (xy 74.815853 -305.61103)
			(xy 74.744979 -305.603044) (xy 74.675444 -305.587174) (xy 74.608124 -305.563617) (xy 74.543865 -305.532672)
			(xy 74.483474 -305.494726) (xy 74.427712 -305.450257) (xy 74.377279 -305.399824) (xy 74.33281 -305.344062)
			(xy 74.294864 -305.283671) (xy 74.263919 -305.219412) (xy 74.240362 -305.152092) (xy 74.224492 -305.082557)
			(xy 74.216506 -305.011683) (xy 73.456017 -305.011683) (xy 73.454156 -305.028201) (xy 73.438286 -305.097736)
			(xy 73.414729 -305.165056) (xy 73.383784 -305.229315) (xy 73.345838 -305.289706) (xy 73.301369 -305.345468)
			(xy 73.250936 -305.395901) (xy 73.195174 -305.44037) (xy 73.134783 -305.478316) (xy 73.070524 -305.509261)
			(xy 73.003204 -305.532818) (xy 72.933669 -305.548688) (xy 72.862795 -305.556674) (xy 72.791473 -305.556674)
			(xy 72.720599 -305.548688) (xy 72.651064 -305.532818) (xy 72.583744 -305.509261) (xy 72.519485 -305.478316)
			(xy 72.459094 -305.44037) (xy 72.403332 -305.395901) (xy 72.352899 -305.345468) (xy 72.30843 -305.289706)
			(xy 72.270484 -305.229315) (xy 72.239539 -305.165056) (xy 72.215982 -305.097736) (xy 72.200112 -305.028201)
			(xy 72.192126 -304.957327) (xy 71.293727 -304.957327) (xy 71.293736 -304.957988) (xy 71.293236 -304.993649)
			(xy 71.28525 -305.064523) (xy 71.26938 -305.134058) (xy 71.245823 -305.201378) (xy 71.214878 -305.265637)
			(xy 71.176932 -305.326028) (xy 71.132463 -305.38179) (xy 71.08203 -305.432223) (xy 71.026268 -305.476692)
			(xy 70.965877 -305.514638) (xy 70.901618 -305.545583) (xy 70.834298 -305.56914) (xy 70.764763 -305.58501)
			(xy 70.693889 -305.592996) (xy 70.622567 -305.592996) (xy 70.551693 -305.58501) (xy 70.482158 -305.56914)
			(xy 70.414838 -305.545583) (xy 70.350579 -305.514638) (xy 70.290188 -305.476692) (xy 70.234426 -305.432223)
			(xy 70.183993 -305.38179) (xy 70.139524 -305.326028) (xy 70.101578 -305.265637) (xy 70.070633 -305.201378)
			(xy 70.047076 -305.134058) (xy 70.031206 -305.064523) (xy 70.02322 -304.993649) (xy 29.73324 -304.993649)
			(xy 29.73324 -306.423737) (xy 51.275478 -306.423737) (xy 51.275478 -306.342627) (xy 51.283428 -306.261908)
			(xy 51.299251 -306.182357) (xy 51.322796 -306.104741) (xy 51.353835 -306.029805) (xy 51.39207 -305.958273)
			(xy 51.437132 -305.890833) (xy 51.488587 -305.828134) (xy 51.54594 -305.770781) (xy 51.608639 -305.719326)
			(xy 51.676079 -305.674264) (xy 51.747611 -305.636029) (xy 51.822547 -305.60499) (xy 51.900163 -305.581445)
			(xy 51.979714 -305.565622) (xy 52.060433 -305.557672) (xy 52.141543 -305.557672) (xy 52.222262 -305.565622)
			(xy 52.301813 -305.581445) (xy 52.379429 -305.60499) (xy 52.454365 -305.636029) (xy 52.525897 -305.674264)
			(xy 52.593337 -305.719326) (xy 52.656036 -305.770781) (xy 52.713389 -305.828134) (xy 52.764844 -305.890833)
			(xy 52.809906 -305.958273) (xy 52.848141 -306.029805) (xy 52.87918 -306.104741) (xy 52.902725 -306.182357)
			(xy 52.918548 -306.261908) (xy 52.926498 -306.342627) (xy 52.926996 -306.383182) (xy 52.926498 -306.423737)
			(xy 52.918548 -306.504456) (xy 52.902725 -306.584007) (xy 52.87918 -306.661623) (xy 52.848141 -306.736559)
			(xy 52.809906 -306.808091) (xy 52.764844 -306.875531) (xy 52.713389 -306.93823) (xy 52.656036 -306.995583)
			(xy 52.593337 -307.047038) (xy 52.525897 -307.0921) (xy 52.454365 -307.130335) (xy 52.379429 -307.161374)
			(xy 52.301813 -307.184919) (xy 52.222262 -307.200742) (xy 52.141543 -307.208692) (xy 52.060433 -307.208692)
			(xy 51.979714 -307.200742) (xy 51.900163 -307.184919) (xy 51.822547 -307.161374) (xy 51.747611 -307.130335)
			(xy 51.676079 -307.0921) (xy 51.608639 -307.047038) (xy 51.54594 -306.995583) (xy 51.488587 -306.93823)
			(xy 51.437132 -306.875531) (xy 51.39207 -306.808091) (xy 51.353835 -306.736559) (xy 51.322796 -306.661623)
			(xy 51.299251 -306.584007) (xy 51.283428 -306.504456) (xy 51.275478 -306.423737) (xy 29.73324 -306.423737)
			(xy 29.73324 -318.06007) (xy 39.818317 -318.06007) (xy 39.822323 -317.944063) (xy 39.834324 -317.828609)
			(xy 39.854261 -317.714258) (xy 39.88204 -317.601555) (xy 39.917528 -317.491038) (xy 39.960556 -317.383231)
			(xy 40.01092 -317.278651) (xy 40.068378 -317.177794) (xy 40.132658 -317.081141) (xy 40.203453 -316.989154)
			(xy 40.280426 -316.90227) (xy 40.363209 -316.820903) (xy 40.451409 -316.745441) (xy 40.544604 -316.676245)
			(xy 40.642352 -316.613643) (xy 40.744186 -316.557934) (xy 40.84962 -316.509383) (xy 40.958153 -316.468222)
			(xy 41.069267 -316.434647) (xy 41.182433 -316.408817) (xy 41.297111 -316.390857) (xy 41.412755 -316.380851)
			(xy 41.528813 -316.378847) (xy 41.644734 -316.384856) (xy 41.759963 -316.398847) (xy 41.873953 -316.420755)
			(xy 41.98616 -316.450475) (xy 42.096049 -316.487865) (xy 42.203096 -316.532748) (xy 42.306792 -316.584909)
			(xy 42.406642 -316.6441) (xy 42.502171 -316.710039) (xy 42.502197 -316.71006) (xy 63.647577 -316.71006)
			(xy 63.651612 -316.634356) (xy 63.663671 -316.559511) (xy 63.683617 -316.48637) (xy 63.711224 -316.415765)
			(xy 63.74618 -316.348494) (xy 63.788088 -316.285319) (xy 63.836474 -316.226957) (xy 63.89079 -316.174069)
			(xy 63.950419 -316.127254) (xy 64.014687 -316.087042) (xy 64.082864 -316.05389) (xy 64.15418 -316.028172)
			(xy 64.227825 -316.01018) (xy 64.302965 -316.000118) (xy 64.378749 -315.998099) (xy 64.454319 -316.004148)
			(xy 64.528817 -316.018195) (xy 64.6014 -316.040081) (xy 64.671246 -316.069558) (xy 64.737563 -316.106293)
			(xy 64.799599 -316.149868) (xy 64.856652 -316.19979) (xy 64.908076 -316.255494) (xy 64.953287 -316.316349)
			(xy 64.991774 -316.381664) (xy 65.0231 -316.4507) (xy 65.04691 -316.522675) (xy 65.062935 -316.596773)
			(xy 65.070994 -316.672154) (xy 65.071498 -316.71006) (xy 66.187577 -316.71006) (xy 66.191612 -316.634356)
			(xy 66.203671 -316.559511) (xy 66.223617 -316.48637) (xy 66.251224 -316.415765) (xy 66.28618 -316.348494)
			(xy 66.328088 -316.285319) (xy 66.376474 -316.226957) (xy 66.43079 -316.174069) (xy 66.490419 -316.127254)
			(xy 66.554687 -316.087042) (xy 66.622864 -316.05389) (xy 66.69418 -316.028172) (xy 66.767825 -316.01018)
			(xy 66.842965 -316.000118) (xy 66.918749 -315.998099) (xy 66.994319 -316.004148) (xy 67.068817 -316.018195)
			(xy 67.1414 -316.040081) (xy 67.211246 -316.069558) (xy 67.277563 -316.106293) (xy 67.339599 -316.149868)
			(xy 67.396652 -316.19979) (xy 67.448076 -316.255494) (xy 67.493287 -316.316349) (xy 67.531774 -316.381664)
			(xy 67.5631 -316.4507) (xy 67.58691 -316.522675) (xy 67.602935 -316.596773) (xy 67.610994 -316.672154)
			(xy 67.611498 -316.71006) (xy 68.727577 -316.71006) (xy 68.731612 -316.634356) (xy 68.743671 -316.559511)
			(xy 68.763617 -316.48637) (xy 68.791224 -316.415765) (xy 68.82618 -316.348494) (xy 68.868088 -316.285319)
			(xy 68.916474 -316.226957) (xy 68.97079 -316.174069) (xy 69.030419 -316.127254) (xy 69.094687 -316.087042)
			(xy 69.162864 -316.05389) (xy 69.23418 -316.028172) (xy 69.307825 -316.01018) (xy 69.382965 -316.000118)
			(xy 69.458749 -315.998099) (xy 69.534319 -316.004148) (xy 69.608817 -316.018195) (xy 69.6814 -316.040081)
			(xy 69.751246 -316.069558) (xy 69.817563 -316.106293) (xy 69.879599 -316.149868) (xy 69.936652 -316.19979)
			(xy 69.988076 -316.255494) (xy 70.033287 -316.316349) (xy 70.071774 -316.381664) (xy 70.1031 -316.4507)
			(xy 70.12691 -316.522675) (xy 70.142935 -316.596773) (xy 70.150994 -316.672154) (xy 70.151498 -316.71006)
			(xy 71.267577 -316.71006) (xy 71.271612 -316.634356) (xy 71.283671 -316.559511) (xy 71.303617 -316.48637)
			(xy 71.331224 -316.415765) (xy 71.36618 -316.348494) (xy 71.408088 -316.285319) (xy 71.456474 -316.226957)
			(xy 71.51079 -316.174069) (xy 71.570419 -316.127254) (xy 71.634687 -316.087042) (xy 71.702864 -316.05389)
			(xy 71.77418 -316.028172) (xy 71.847825 -316.01018) (xy 71.922965 -316.000118) (xy 71.998749 -315.998099)
			(xy 72.074319 -316.004148) (xy 72.148817 -316.018195) (xy 72.2214 -316.040081) (xy 72.291246 -316.069558)
			(xy 72.357563 -316.106293) (xy 72.419599 -316.149868) (xy 72.476652 -316.19979) (xy 72.528076 -316.255494)
			(xy 72.573287 -316.316349) (xy 72.611774 -316.381664) (xy 72.6431 -316.4507) (xy 72.66691 -316.522675)
			(xy 72.682935 -316.596773) (xy 72.690994 -316.672154) (xy 72.691498 -316.71006) (xy 73.807577 -316.71006)
			(xy 73.811612 -316.634356) (xy 73.823671 -316.559511) (xy 73.843617 -316.48637) (xy 73.871224 -316.415765)
			(xy 73.90618 -316.348494) (xy 73.948088 -316.285319) (xy 73.996474 -316.226957) (xy 74.05079 -316.174069)
			(xy 74.110419 -316.127254) (xy 74.174687 -316.087042) (xy 74.242864 -316.05389) (xy 74.31418 -316.028172)
			(xy 74.387825 -316.01018) (xy 74.462965 -316.000118) (xy 74.538749 -315.998099) (xy 74.614319 -316.004148)
			(xy 74.688817 -316.018195) (xy 74.7614 -316.040081) (xy 74.831246 -316.069558) (xy 74.897563 -316.106293)
			(xy 74.959599 -316.149868) (xy 75.016652 -316.19979) (xy 75.068076 -316.255494) (xy 75.113287 -316.316349)
			(xy 75.151774 -316.381664) (xy 75.1831 -316.4507) (xy 75.20691 -316.522675) (xy 75.222935 -316.596773)
			(xy 75.230994 -316.672154) (xy 75.231498 -316.71006) (xy 76.347577 -316.71006) (xy 76.351612 -316.634356)
			(xy 76.363671 -316.559511) (xy 76.383617 -316.48637) (xy 76.411224 -316.415765) (xy 76.44618 -316.348494)
			(xy 76.488088 -316.285319) (xy 76.536474 -316.226957) (xy 76.59079 -316.174069) (xy 76.650419 -316.127254)
			(xy 76.714687 -316.087042) (xy 76.782864 -316.05389) (xy 76.85418 -316.028172) (xy 76.927825 -316.01018)
			(xy 77.002965 -316.000118) (xy 77.078749 -315.998099) (xy 77.154319 -316.004148) (xy 77.228817 -316.018195)
			(xy 77.3014 -316.040081) (xy 77.371246 -316.069558) (xy 77.437563 -316.106293) (xy 77.499599 -316.149868)
			(xy 77.556652 -316.19979) (xy 77.608076 -316.255494) (xy 77.653287 -316.316349) (xy 77.691774 -316.381664)
			(xy 77.7231 -316.4507) (xy 77.74691 -316.522675) (xy 77.762935 -316.596773) (xy 77.770994 -316.672154)
			(xy 77.771498 -316.71006) (xy 78.887577 -316.71006) (xy 78.891612 -316.634356) (xy 78.903671 -316.559511)
			(xy 78.923617 -316.48637) (xy 78.951224 -316.415765) (xy 78.98618 -316.348494) (xy 79.028088 -316.285319)
			(xy 79.076474 -316.226957) (xy 79.13079 -316.174069) (xy 79.190419 -316.127254) (xy 79.254687 -316.087042)
			(xy 79.322864 -316.05389) (xy 79.39418 -316.028172) (xy 79.467825 -316.01018) (xy 79.542965 -316.000118)
			(xy 79.618749 -315.998099) (xy 79.694319 -316.004148) (xy 79.768817 -316.018195) (xy 79.8414 -316.040081)
			(xy 79.911246 -316.069558) (xy 79.977563 -316.106293) (xy 80.039599 -316.149868) (xy 80.096652 -316.19979)
			(xy 80.148076 -316.255494) (xy 80.193287 -316.316349) (xy 80.231774 -316.381664) (xy 80.2631 -316.4507)
			(xy 80.28691 -316.522675) (xy 80.302935 -316.596773) (xy 80.310994 -316.672154) (xy 80.311498 -316.71006)
			(xy 80.310994 -316.747966) (xy 80.302935 -316.823347) (xy 80.28691 -316.897445) (xy 80.2631 -316.96942)
			(xy 80.231774 -317.038456) (xy 80.193287 -317.103771) (xy 80.148076 -317.164626) (xy 80.096652 -317.22033)
			(xy 80.039599 -317.270252) (xy 79.977563 -317.313827) (xy 79.911246 -317.350562) (xy 79.8414 -317.380039)
			(xy 79.768817 -317.401925) (xy 79.694319 -317.415972) (xy 79.618749 -317.422021) (xy 79.542965 -317.420002)
			(xy 79.467825 -317.40994) (xy 79.39418 -317.391948) (xy 79.322864 -317.36623) (xy 79.254687 -317.333078)
			(xy 79.190419 -317.292866) (xy 79.13079 -317.246051) (xy 79.076474 -317.193163) (xy 79.028088 -317.134801)
			(xy 78.98618 -317.071626) (xy 78.951224 -317.004355) (xy 78.923617 -316.93375) (xy 78.903671 -316.860609)
			(xy 78.891612 -316.785764) (xy 78.887577 -316.71006) (xy 77.771498 -316.71006) (xy 77.770994 -316.747966)
			(xy 77.762935 -316.823347) (xy 77.74691 -316.897445) (xy 77.7231 -316.96942) (xy 77.691774 -317.038456)
			(xy 77.653287 -317.103771) (xy 77.608076 -317.164626) (xy 77.556652 -317.22033) (xy 77.499599 -317.270252)
			(xy 77.437563 -317.313827) (xy 77.371246 -317.350562) (xy 77.3014 -317.380039) (xy 77.228817 -317.401925)
			(xy 77.154319 -317.415972) (xy 77.078749 -317.422021) (xy 77.002965 -317.420002) (xy 76.927825 -317.40994)
			(xy 76.85418 -317.391948) (xy 76.782864 -317.36623) (xy 76.714687 -317.333078) (xy 76.650419 -317.292866)
			(xy 76.59079 -317.246051) (xy 76.536474 -317.193163) (xy 76.488088 -317.134801) (xy 76.44618 -317.071626)
			(xy 76.411224 -317.004355) (xy 76.383617 -316.93375) (xy 76.363671 -316.860609) (xy 76.351612 -316.785764)
			(xy 76.347577 -316.71006) (xy 75.231498 -316.71006) (xy 75.230994 -316.747966) (xy 75.222935 -316.823347)
			(xy 75.20691 -316.897445) (xy 75.1831 -316.96942) (xy 75.151774 -317.038456) (xy 75.113287 -317.103771)
			(xy 75.068076 -317.164626) (xy 75.016652 -317.22033) (xy 74.959599 -317.270252) (xy 74.897563 -317.313827)
			(xy 74.831246 -317.350562) (xy 74.7614 -317.380039) (xy 74.688817 -317.401925) (xy 74.614319 -317.415972)
			(xy 74.538749 -317.422021) (xy 74.462965 -317.420002) (xy 74.387825 -317.40994) (xy 74.31418 -317.391948)
			(xy 74.242864 -317.36623) (xy 74.174687 -317.333078) (xy 74.110419 -317.292866) (xy 74.05079 -317.246051)
			(xy 73.996474 -317.193163) (xy 73.948088 -317.134801) (xy 73.90618 -317.071626) (xy 73.871224 -317.004355)
			(xy 73.843617 -316.93375) (xy 73.823671 -316.860609) (xy 73.811612 -316.785764) (xy 73.807577 -316.71006)
			(xy 72.691498 -316.71006) (xy 72.690994 -316.747966) (xy 72.682935 -316.823347) (xy 72.66691 -316.897445)
			(xy 72.6431 -316.96942) (xy 72.611774 -317.038456) (xy 72.573287 -317.103771) (xy 72.528076 -317.164626)
			(xy 72.476652 -317.22033) (xy 72.419599 -317.270252) (xy 72.357563 -317.313827) (xy 72.291246 -317.350562)
			(xy 72.2214 -317.380039) (xy 72.148817 -317.401925) (xy 72.074319 -317.415972) (xy 71.998749 -317.422021)
			(xy 71.922965 -317.420002) (xy 71.847825 -317.40994) (xy 71.77418 -317.391948) (xy 71.702864 -317.36623)
			(xy 71.634687 -317.333078) (xy 71.570419 -317.292866) (xy 71.51079 -317.246051) (xy 71.456474 -317.193163)
			(xy 71.408088 -317.134801) (xy 71.36618 -317.071626) (xy 71.331224 -317.004355) (xy 71.303617 -316.93375)
			(xy 71.283671 -316.860609) (xy 71.271612 -316.785764) (xy 71.267577 -316.71006) (xy 70.151498 -316.71006)
			(xy 70.150994 -316.747966) (xy 70.142935 -316.823347) (xy 70.12691 -316.897445) (xy 70.1031 -316.96942)
			(xy 70.071774 -317.038456) (xy 70.033287 -317.103771) (xy 69.988076 -317.164626) (xy 69.936652 -317.22033)
			(xy 69.879599 -317.270252) (xy 69.817563 -317.313827) (xy 69.751246 -317.350562) (xy 69.6814 -317.380039)
			(xy 69.608817 -317.401925) (xy 69.534319 -317.415972) (xy 69.458749 -317.422021) (xy 69.382965 -317.420002)
			(xy 69.307825 -317.40994) (xy 69.23418 -317.391948) (xy 69.162864 -317.36623) (xy 69.094687 -317.333078)
			(xy 69.030419 -317.292866) (xy 68.97079 -317.246051) (xy 68.916474 -317.193163) (xy 68.868088 -317.134801)
			(xy 68.82618 -317.071626) (xy 68.791224 -317.004355) (xy 68.763617 -316.93375) (xy 68.743671 -316.860609)
			(xy 68.731612 -316.785764) (xy 68.727577 -316.71006) (xy 67.611498 -316.71006) (xy 67.610994 -316.747966)
			(xy 67.602935 -316.823347) (xy 67.58691 -316.897445) (xy 67.5631 -316.96942) (xy 67.531774 -317.038456)
			(xy 67.493287 -317.103771) (xy 67.448076 -317.164626) (xy 67.396652 -317.22033) (xy 67.339599 -317.270252)
			(xy 67.277563 -317.313827) (xy 67.211246 -317.350562) (xy 67.1414 -317.380039) (xy 67.068817 -317.401925)
			(xy 66.994319 -317.415972) (xy 66.918749 -317.422021) (xy 66.842965 -317.420002) (xy 66.767825 -317.40994)
			(xy 66.69418 -317.391948) (xy 66.622864 -317.36623) (xy 66.554687 -317.333078) (xy 66.490419 -317.292866)
			(xy 66.43079 -317.246051) (xy 66.376474 -317.193163) (xy 66.328088 -317.134801) (xy 66.28618 -317.071626)
			(xy 66.251224 -317.004355) (xy 66.223617 -316.93375) (xy 66.203671 -316.860609) (xy 66.191612 -316.785764)
			(xy 66.187577 -316.71006) (xy 65.071498 -316.71006) (xy 65.070994 -316.747966) (xy 65.062935 -316.823347)
			(xy 65.04691 -316.897445) (xy 65.0231 -316.96942) (xy 64.991774 -317.038456) (xy 64.953287 -317.103771)
			(xy 64.908076 -317.164626) (xy 64.856652 -317.22033) (xy 64.799599 -317.270252) (xy 64.737563 -317.313827)
			(xy 64.671246 -317.350562) (xy 64.6014 -317.380039) (xy 64.528817 -317.401925) (xy 64.454319 -317.415972)
			(xy 64.378749 -317.422021) (xy 64.302965 -317.420002) (xy 64.227825 -317.40994) (xy 64.15418 -317.391948)
			(xy 64.082864 -317.36623) (xy 64.014687 -317.333078) (xy 63.950419 -317.292866) (xy 63.89079 -317.246051)
			(xy 63.836474 -317.193163) (xy 63.788088 -317.134801) (xy 63.74618 -317.071626) (xy 63.711224 -317.004355)
			(xy 63.683617 -316.93375) (xy 63.663671 -316.860609) (xy 63.651612 -316.785764) (xy 63.647577 -316.71006)
			(xy 42.502197 -316.71006) (xy 42.592922 -316.782411) (xy 42.678465 -316.860872) (xy 42.758391 -316.945047)
			(xy 42.832318 -317.034536) (xy 42.899896 -317.128912) (xy 42.960802 -317.227726) (xy 43.014745 -317.330506)
			(xy 43.061469 -317.436763) (xy 43.10075 -317.54599) (xy 43.132402 -317.657667) (xy 43.156275 -317.771262)
			(xy 43.172253 -317.886233) (xy 43.180261 -318.002032) (xy 43.180762 -318.06007) (xy 43.180261 -318.118108)
			(xy 43.172253 -318.233907) (xy 43.156275 -318.348878) (xy 43.132402 -318.462473) (xy 43.10075 -318.57415)
			(xy 43.061469 -318.683377) (xy 43.014745 -318.789634) (xy 42.960802 -318.892414) (xy 42.899896 -318.991228)
			(xy 42.832318 -319.085604) (xy 42.758391 -319.175093) (xy 42.678465 -319.259268) (xy 42.592922 -319.337729)
			(xy 42.502197 -319.41008) (xy 63.647577 -319.41008) (xy 63.651612 -319.334376) (xy 63.663671 -319.259531)
			(xy 63.683617 -319.18639) (xy 63.711224 -319.115785) (xy 63.74618 -319.048514) (xy 63.788088 -318.985339)
			(xy 63.836474 -318.926977) (xy 63.89079 -318.874089) (xy 63.950419 -318.827274) (xy 64.014687 -318.787062)
			(xy 64.082864 -318.75391) (xy 64.15418 -318.728192) (xy 64.227825 -318.7102) (xy 64.302965 -318.700138)
			(xy 64.378749 -318.698119) (xy 64.454319 -318.704168) (xy 64.528817 -318.718215) (xy 64.6014 -318.740101)
			(xy 64.671246 -318.769578) (xy 64.737563 -318.806313) (xy 64.799599 -318.849888) (xy 64.856652 -318.89981)
			(xy 64.908076 -318.955514) (xy 64.953287 -319.016369) (xy 64.991774 -319.081684) (xy 65.0231 -319.15072)
			(xy 65.04691 -319.222695) (xy 65.062935 -319.296793) (xy 65.070994 -319.372174) (xy 65.071498 -319.41008)
			(xy 66.187577 -319.41008) (xy 66.191612 -319.334376) (xy 66.203671 -319.259531) (xy 66.223617 -319.18639)
			(xy 66.251224 -319.115785) (xy 66.28618 -319.048514) (xy 66.328088 -318.985339) (xy 66.376474 -318.926977)
			(xy 66.43079 -318.874089) (xy 66.490419 -318.827274) (xy 66.554687 -318.787062) (xy 66.622864 -318.75391)
			(xy 66.69418 -318.728192) (xy 66.767825 -318.7102) (xy 66.842965 -318.700138) (xy 66.918749 -318.698119)
			(xy 66.994319 -318.704168) (xy 67.068817 -318.718215) (xy 67.1414 -318.740101) (xy 67.211246 -318.769578)
			(xy 67.277563 -318.806313) (xy 67.339599 -318.849888) (xy 67.396652 -318.89981) (xy 67.448076 -318.955514)
			(xy 67.493287 -319.016369) (xy 67.531774 -319.081684) (xy 67.5631 -319.15072) (xy 67.58691 -319.222695)
			(xy 67.602935 -319.296793) (xy 67.610994 -319.372174) (xy 67.611498 -319.41008) (xy 68.727577 -319.41008)
			(xy 68.731612 -319.334376) (xy 68.743671 -319.259531) (xy 68.763617 -319.18639) (xy 68.791224 -319.115785)
			(xy 68.82618 -319.048514) (xy 68.868088 -318.985339) (xy 68.916474 -318.926977) (xy 68.97079 -318.874089)
			(xy 69.030419 -318.827274) (xy 69.094687 -318.787062) (xy 69.162864 -318.75391) (xy 69.23418 -318.728192)
			(xy 69.307825 -318.7102) (xy 69.382965 -318.700138) (xy 69.458749 -318.698119) (xy 69.534319 -318.704168)
			(xy 69.608817 -318.718215) (xy 69.6814 -318.740101) (xy 69.751246 -318.769578) (xy 69.817563 -318.806313)
			(xy 69.879599 -318.849888) (xy 69.936652 -318.89981) (xy 69.988076 -318.955514) (xy 70.033287 -319.016369)
			(xy 70.071774 -319.081684) (xy 70.1031 -319.15072) (xy 70.12691 -319.222695) (xy 70.142935 -319.296793)
			(xy 70.150994 -319.372174) (xy 70.151498 -319.41008) (xy 71.267577 -319.41008) (xy 71.271612 -319.334376)
			(xy 71.283671 -319.259531) (xy 71.303617 -319.18639) (xy 71.331224 -319.115785) (xy 71.36618 -319.048514)
			(xy 71.408088 -318.985339) (xy 71.456474 -318.926977) (xy 71.51079 -318.874089) (xy 71.570419 -318.827274)
			(xy 71.634687 -318.787062) (xy 71.702864 -318.75391) (xy 71.77418 -318.728192) (xy 71.847825 -318.7102)
			(xy 71.922965 -318.700138) (xy 71.998749 -318.698119) (xy 72.074319 -318.704168) (xy 72.148817 -318.718215)
			(xy 72.2214 -318.740101) (xy 72.291246 -318.769578) (xy 72.357563 -318.806313) (xy 72.419599 -318.849888)
			(xy 72.476652 -318.89981) (xy 72.528076 -318.955514) (xy 72.573287 -319.016369) (xy 72.611774 -319.081684)
			(xy 72.6431 -319.15072) (xy 72.66691 -319.222695) (xy 72.682935 -319.296793) (xy 72.690994 -319.372174)
			(xy 72.691498 -319.41008) (xy 73.807577 -319.41008) (xy 73.811612 -319.334376) (xy 73.823671 -319.259531)
			(xy 73.843617 -319.18639) (xy 73.871224 -319.115785) (xy 73.90618 -319.048514) (xy 73.948088 -318.985339)
			(xy 73.996474 -318.926977) (xy 74.05079 -318.874089) (xy 74.110419 -318.827274) (xy 74.174687 -318.787062)
			(xy 74.242864 -318.75391) (xy 74.31418 -318.728192) (xy 74.387825 -318.7102) (xy 74.462965 -318.700138)
			(xy 74.538749 -318.698119) (xy 74.614319 -318.704168) (xy 74.688817 -318.718215) (xy 74.7614 -318.740101)
			(xy 74.831246 -318.769578) (xy 74.897563 -318.806313) (xy 74.959599 -318.849888) (xy 75.016652 -318.89981)
			(xy 75.068076 -318.955514) (xy 75.113287 -319.016369) (xy 75.151774 -319.081684) (xy 75.1831 -319.15072)
			(xy 75.20691 -319.222695) (xy 75.222935 -319.296793) (xy 75.230994 -319.372174) (xy 75.231498 -319.41008)
			(xy 76.347577 -319.41008) (xy 76.351612 -319.334376) (xy 76.363671 -319.259531) (xy 76.383617 -319.18639)
			(xy 76.411224 -319.115785) (xy 76.44618 -319.048514) (xy 76.488088 -318.985339) (xy 76.536474 -318.926977)
			(xy 76.59079 -318.874089) (xy 76.650419 -318.827274) (xy 76.714687 -318.787062) (xy 76.782864 -318.75391)
			(xy 76.85418 -318.728192) (xy 76.927825 -318.7102) (xy 77.002965 -318.700138) (xy 77.078749 -318.698119)
			(xy 77.154319 -318.704168) (xy 77.228817 -318.718215) (xy 77.3014 -318.740101) (xy 77.371246 -318.769578)
			(xy 77.437563 -318.806313) (xy 77.499599 -318.849888) (xy 77.556652 -318.89981) (xy 77.608076 -318.955514)
			(xy 77.653287 -319.016369) (xy 77.691774 -319.081684) (xy 77.7231 -319.15072) (xy 77.74691 -319.222695)
			(xy 77.762935 -319.296793) (xy 77.770994 -319.372174) (xy 77.771498 -319.41008) (xy 78.887577 -319.41008)
			(xy 78.891612 -319.334376) (xy 78.903671 -319.259531) (xy 78.923617 -319.18639) (xy 78.951224 -319.115785)
			(xy 78.98618 -319.048514) (xy 79.028088 -318.985339) (xy 79.076474 -318.926977) (xy 79.13079 -318.874089)
			(xy 79.190419 -318.827274) (xy 79.254687 -318.787062) (xy 79.322864 -318.75391) (xy 79.39418 -318.728192)
			(xy 79.467825 -318.7102) (xy 79.542965 -318.700138) (xy 79.618749 -318.698119) (xy 79.694319 -318.704168)
			(xy 79.768817 -318.718215) (xy 79.8414 -318.740101) (xy 79.911246 -318.769578) (xy 79.977563 -318.806313)
			(xy 80.039599 -318.849888) (xy 80.096652 -318.89981) (xy 80.148076 -318.955514) (xy 80.193287 -319.016369)
			(xy 80.231774 -319.081684) (xy 80.2631 -319.15072) (xy 80.28691 -319.222695) (xy 80.302935 -319.296793)
			(xy 80.310994 -319.372174) (xy 80.311498 -319.41008) (xy 80.310994 -319.447986) (xy 80.302935 -319.523367)
			(xy 80.28691 -319.597465) (xy 80.2631 -319.66944) (xy 80.231774 -319.738476) (xy 80.193287 -319.803791)
			(xy 80.148076 -319.864646) (xy 80.096652 -319.92035) (xy 80.039599 -319.970272) (xy 79.977563 -320.013847)
			(xy 79.911246 -320.050582) (xy 79.8414 -320.080059) (xy 79.768817 -320.101945) (xy 79.694319 -320.115992)
			(xy 79.618749 -320.122041) (xy 79.542965 -320.120022) (xy 79.467825 -320.10996) (xy 79.39418 -320.091968)
			(xy 79.322864 -320.06625) (xy 79.254687 -320.033098) (xy 79.190419 -319.992886) (xy 79.13079 -319.946071)
			(xy 79.076474 -319.893183) (xy 79.028088 -319.834821) (xy 78.98618 -319.771646) (xy 78.951224 -319.704375)
			(xy 78.923617 -319.63377) (xy 78.903671 -319.560629) (xy 78.891612 -319.485784) (xy 78.887577 -319.41008)
			(xy 77.771498 -319.41008) (xy 77.770994 -319.447986) (xy 77.762935 -319.523367) (xy 77.74691 -319.597465)
			(xy 77.7231 -319.66944) (xy 77.691774 -319.738476) (xy 77.653287 -319.803791) (xy 77.608076 -319.864646)
			(xy 77.556652 -319.92035) (xy 77.499599 -319.970272) (xy 77.437563 -320.013847) (xy 77.371246 -320.050582)
			(xy 77.3014 -320.080059) (xy 77.228817 -320.101945) (xy 77.154319 -320.115992) (xy 77.078749 -320.122041)
			(xy 77.002965 -320.120022) (xy 76.927825 -320.10996) (xy 76.85418 -320.091968) (xy 76.782864 -320.06625)
			(xy 76.714687 -320.033098) (xy 76.650419 -319.992886) (xy 76.59079 -319.946071) (xy 76.536474 -319.893183)
			(xy 76.488088 -319.834821) (xy 76.44618 -319.771646) (xy 76.411224 -319.704375) (xy 76.383617 -319.63377)
			(xy 76.363671 -319.560629) (xy 76.351612 -319.485784) (xy 76.347577 -319.41008) (xy 75.231498 -319.41008)
			(xy 75.230994 -319.447986) (xy 75.222935 -319.523367) (xy 75.20691 -319.597465) (xy 75.1831 -319.66944)
			(xy 75.151774 -319.738476) (xy 75.113287 -319.803791) (xy 75.068076 -319.864646) (xy 75.016652 -319.92035)
			(xy 74.959599 -319.970272) (xy 74.897563 -320.013847) (xy 74.831246 -320.050582) (xy 74.7614 -320.080059)
			(xy 74.688817 -320.101945) (xy 74.614319 -320.115992) (xy 74.538749 -320.122041) (xy 74.462965 -320.120022)
			(xy 74.387825 -320.10996) (xy 74.31418 -320.091968) (xy 74.242864 -320.06625) (xy 74.174687 -320.033098)
			(xy 74.110419 -319.992886) (xy 74.05079 -319.946071) (xy 73.996474 -319.893183) (xy 73.948088 -319.834821)
			(xy 73.90618 -319.771646) (xy 73.871224 -319.704375) (xy 73.843617 -319.63377) (xy 73.823671 -319.560629)
			(xy 73.811612 -319.485784) (xy 73.807577 -319.41008) (xy 72.691498 -319.41008) (xy 72.690994 -319.447986)
			(xy 72.682935 -319.523367) (xy 72.66691 -319.597465) (xy 72.6431 -319.66944) (xy 72.611774 -319.738476)
			(xy 72.573287 -319.803791) (xy 72.528076 -319.864646) (xy 72.476652 -319.92035) (xy 72.419599 -319.970272)
			(xy 72.357563 -320.013847) (xy 72.291246 -320.050582) (xy 72.2214 -320.080059) (xy 72.148817 -320.101945)
			(xy 72.074319 -320.115992) (xy 71.998749 -320.122041) (xy 71.922965 -320.120022) (xy 71.847825 -320.10996)
			(xy 71.77418 -320.091968) (xy 71.702864 -320.06625) (xy 71.634687 -320.033098) (xy 71.570419 -319.992886)
			(xy 71.51079 -319.946071) (xy 71.456474 -319.893183) (xy 71.408088 -319.834821) (xy 71.36618 -319.771646)
			(xy 71.331224 -319.704375) (xy 71.303617 -319.63377) (xy 71.283671 -319.560629) (xy 71.271612 -319.485784)
			(xy 71.267577 -319.41008) (xy 70.151498 -319.41008) (xy 70.150994 -319.447986) (xy 70.142935 -319.523367)
			(xy 70.12691 -319.597465) (xy 70.1031 -319.66944) (xy 70.071774 -319.738476) (xy 70.033287 -319.803791)
			(xy 69.988076 -319.864646) (xy 69.936652 -319.92035) (xy 69.879599 -319.970272) (xy 69.817563 -320.013847)
			(xy 69.751246 -320.050582) (xy 69.6814 -320.080059) (xy 69.608817 -320.101945) (xy 69.534319 -320.115992)
			(xy 69.458749 -320.122041) (xy 69.382965 -320.120022) (xy 69.307825 -320.10996) (xy 69.23418 -320.091968)
			(xy 69.162864 -320.06625) (xy 69.094687 -320.033098) (xy 69.030419 -319.992886) (xy 68.97079 -319.946071)
			(xy 68.916474 -319.893183) (xy 68.868088 -319.834821) (xy 68.82618 -319.771646) (xy 68.791224 -319.704375)
			(xy 68.763617 -319.63377) (xy 68.743671 -319.560629) (xy 68.731612 -319.485784) (xy 68.727577 -319.41008)
			(xy 67.611498 -319.41008) (xy 67.610994 -319.447986) (xy 67.602935 -319.523367) (xy 67.58691 -319.597465)
			(xy 67.5631 -319.66944) (xy 67.531774 -319.738476) (xy 67.493287 -319.803791) (xy 67.448076 -319.864646)
			(xy 67.396652 -319.92035) (xy 67.339599 -319.970272) (xy 67.277563 -320.013847) (xy 67.211246 -320.050582)
			(xy 67.1414 -320.080059) (xy 67.068817 -320.101945) (xy 66.994319 -320.115992) (xy 66.918749 -320.122041)
			(xy 66.842965 -320.120022) (xy 66.767825 -320.10996) (xy 66.69418 -320.091968) (xy 66.622864 -320.06625)
			(xy 66.554687 -320.033098) (xy 66.490419 -319.992886) (xy 66.43079 -319.946071) (xy 66.376474 -319.893183)
			(xy 66.328088 -319.834821) (xy 66.28618 -319.771646) (xy 66.251224 -319.704375) (xy 66.223617 -319.63377)
			(xy 66.203671 -319.560629) (xy 66.191612 -319.485784) (xy 66.187577 -319.41008) (xy 65.071498 -319.41008)
			(xy 65.070994 -319.447986) (xy 65.062935 -319.523367) (xy 65.04691 -319.597465) (xy 65.0231 -319.66944)
			(xy 64.991774 -319.738476) (xy 64.953287 -319.803791) (xy 64.908076 -319.864646) (xy 64.856652 -319.92035)
			(xy 64.799599 -319.970272) (xy 64.737563 -320.013847) (xy 64.671246 -320.050582) (xy 64.6014 -320.080059)
			(xy 64.528817 -320.101945) (xy 64.454319 -320.115992) (xy 64.378749 -320.122041) (xy 64.302965 -320.120022)
			(xy 64.227825 -320.10996) (xy 64.15418 -320.091968) (xy 64.082864 -320.06625) (xy 64.014687 -320.033098)
			(xy 63.950419 -319.992886) (xy 63.89079 -319.946071) (xy 63.836474 -319.893183) (xy 63.788088 -319.834821)
			(xy 63.74618 -319.771646) (xy 63.711224 -319.704375) (xy 63.683617 -319.63377) (xy 63.663671 -319.560629)
			(xy 63.651612 -319.485784) (xy 63.647577 -319.41008) (xy 42.502197 -319.41008) (xy 42.502171 -319.410101)
			(xy 42.406642 -319.47604) (xy 42.306792 -319.535231) (xy 42.203096 -319.587392) (xy 42.096049 -319.632275)
			(xy 41.98616 -319.669665) (xy 41.873953 -319.699385) (xy 41.759963 -319.721293) (xy 41.644734 -319.735284)
			(xy 41.528813 -319.741293) (xy 41.412755 -319.739289) (xy 41.297111 -319.729283) (xy 41.182433 -319.711323)
			(xy 41.069267 -319.685493) (xy 40.958153 -319.651918) (xy 40.84962 -319.610757) (xy 40.744186 -319.562206)
			(xy 40.642352 -319.506497) (xy 40.544604 -319.443895) (xy 40.451409 -319.374699) (xy 40.363209 -319.299237)
			(xy 40.280426 -319.21787) (xy 40.203453 -319.130986) (xy 40.132658 -319.038999) (xy 40.068378 -318.942346)
			(xy 40.01092 -318.841489) (xy 39.960556 -318.736909) (xy 39.917528 -318.629102) (xy 39.88204 -318.518585)
			(xy 39.854261 -318.405882) (xy 39.834324 -318.291531) (xy 39.822323 -318.176077) (xy 39.818317 -318.06007)
			(xy 29.73324 -318.06007) (xy 29.73324 -319.493138) (xy 29.733718 -319.51598) (xy 29.741878 -319.56093)
			(xy 29.757945 -319.603696) (xy 29.781402 -319.642898) (xy 29.811492 -319.677274) (xy 29.847245 -319.705713)
			(xy 29.887507 -319.7273) (xy 29.930982 -319.741337) (xy 29.976265 -319.747373) (xy 30.021899 -319.745213)
			(xy 30.06641 -319.734926) (xy 30.08757 -319.72631) (xy 30.127491 -319.709645) (xy 30.20975 -319.682851)
			(xy 30.294124 -319.663727) (xy 30.379897 -319.652433) (xy 30.466345 -319.649066) (xy 30.552736 -319.653654)
			(xy 30.638341 -319.666158) (xy 30.722436 -319.686472) (xy 30.804309 -319.714424) (xy 30.883269 -319.74978)
			(xy 30.958647 -319.792238) (xy 31.029806 -319.84144) (xy 31.096145 -319.896971) (xy 31.157103 -319.958361)
			(xy 31.212165 -320.025091) (xy 31.260864 -320.096596) (xy 31.302789 -320.172272) (xy 31.337586 -320.251479)
			(xy 31.36496 -320.333547) (xy 31.38468 -320.417783) (xy 31.39658 -320.503474) (xy 31.400557 -320.589896)
			(xy 31.398557 -320.63336) (xy 34.599874 -320.63336) (xy 34.599874 -320.54646) (xy 34.607892 -320.459931)
			(xy 34.62386 -320.374511) (xy 34.647641 -320.290929) (xy 34.679033 -320.209897) (xy 34.717767 -320.132108)
			(xy 34.763514 -320.058224) (xy 34.815883 -319.988877) (xy 34.874427 -319.924657) (xy 34.938647 -319.866113)
			(xy 35.007994 -319.813744) (xy 35.081878 -319.767997) (xy 35.159667 -319.729263) (xy 35.240699 -319.697871)
			(xy 35.324281 -319.67409) (xy 35.409701 -319.658122) (xy 35.49623 -319.650104) (xy 35.58313 -319.650104)
			(xy 35.669659 -319.658122) (xy 35.755079 -319.67409) (xy 35.838661 -319.697871) (xy 35.919693 -319.729263)
			(xy 35.997482 -319.767997) (xy 36.071366 -319.813744) (xy 36.140713 -319.866113) (xy 36.204933 -319.924657)
			(xy 36.263477 -319.988877) (xy 36.315846 -320.058224) (xy 36.361593 -320.132108) (xy 36.400327 -320.209897)
			(xy 36.431719 -320.290929) (xy 36.4555 -320.374511) (xy 36.471468 -320.459931) (xy 36.479486 -320.54646)
			(xy 36.479988 -320.58991) (xy 36.479486 -320.63336) (xy 36.471468 -320.719889) (xy 36.4555 -320.805309)
			(xy 36.431719 -320.888891) (xy 36.400327 -320.969923) (xy 36.361593 -321.047712) (xy 36.315846 -321.121596)
			(xy 36.263477 -321.190943) (xy 36.204933 -321.255163) (xy 36.140713 -321.313707) (xy 36.071366 -321.366076)
			(xy 35.997482 -321.411823) (xy 35.919693 -321.450557) (xy 35.838661 -321.481949) (xy 35.755079 -321.50573)
			(xy 35.669659 -321.521698) (xy 35.58313 -321.529716) (xy 35.49623 -321.529716) (xy 35.409701 -321.521698)
			(xy 35.324281 -321.50573) (xy 35.240699 -321.481949) (xy 35.159667 -321.450557) (xy 35.081878 -321.411823)
			(xy 35.007994 -321.366076) (xy 34.938647 -321.313707) (xy 34.874427 -321.255163) (xy 34.815883 -321.190943)
			(xy 34.763514 -321.121596) (xy 34.717767 -321.047712) (xy 34.679033 -320.969923) (xy 34.647641 -320.888891)
			(xy 34.62386 -320.805309) (xy 34.607892 -320.719889) (xy 34.599874 -320.63336) (xy 31.398557 -320.63336)
			(xy 31.39658 -320.676318) (xy 31.384682 -320.762009) (xy 31.364962 -320.846245) (xy 31.337589 -320.928314)
			(xy 31.302793 -321.007521) (xy 31.260868 -321.083198) (xy 31.212169 -321.154703) (xy 31.157109 -321.221433)
			(xy 31.096151 -321.282823) (xy 31.029813 -321.338355) (xy 30.958653 -321.387558) (xy 30.883276 -321.430017)
			(xy 30.804316 -321.465373) (xy 30.722444 -321.493326) (xy 30.638349 -321.513641) (xy 30.552744 -321.526145)
			(xy 30.466352 -321.530734) (xy 30.379905 -321.527368) (xy 30.294131 -321.516075) (xy 30.209758 -321.496951)
			(xy 30.127498 -321.470158) (xy 30.08757 -321.45351) (xy 30.066403 -321.444941) (xy 30.021906 -321.434702)
			(xy 29.976295 -321.432576) (xy 29.931038 -321.438634) (xy 29.887591 -321.452679) (xy 29.847352 -321.474259)
			(xy 29.811616 -321.502681) (xy 29.781532 -321.53703) (xy 29.758068 -321.576201) (xy 29.74198 -321.618933)
			(xy 29.733784 -321.663852) (xy 29.73324 -321.686682) (xy 29.73324 -322.033138) (xy 29.733718 -322.05598)
			(xy 29.741878 -322.10093) (xy 29.757945 -322.143696) (xy 29.781402 -322.182898) (xy 29.811492 -322.217274)
			(xy 29.847245 -322.245713) (xy 29.887507 -322.2673) (xy 29.930982 -322.281337) (xy 29.976265 -322.287373)
			(xy 30.021899 -322.285213) (xy 30.06641 -322.274926) (xy 30.08757 -322.26631) (xy 30.127491 -322.249645)
			(xy 30.20975 -322.222851) (xy 30.294124 -322.203727) (xy 30.379897 -322.192433) (xy 30.466345 -322.189066)
			(xy 30.552736 -322.193654) (xy 30.638341 -322.206158) (xy 30.722436 -322.226472) (xy 30.804309 -322.254424)
			(xy 30.883269 -322.28978) (xy 30.958647 -322.332238) (xy 31.029806 -322.38144) (xy 31.096145 -322.436971)
			(xy 31.157103 -322.498361) (xy 31.212165 -322.565091) (xy 31.260864 -322.636596) (xy 31.302789 -322.712272)
			(xy 31.337586 -322.791479) (xy 31.36496 -322.873547) (xy 31.38468 -322.957783) (xy 31.39658 -323.043474)
			(xy 31.400557 -323.129896) (xy 31.398557 -323.17336) (xy 34.599874 -323.17336) (xy 34.599874 -323.08646)
			(xy 34.607892 -322.999931) (xy 34.62386 -322.914511) (xy 34.647641 -322.830929) (xy 34.679033 -322.749897)
			(xy 34.717767 -322.672108) (xy 34.763514 -322.598224) (xy 34.815883 -322.528877) (xy 34.874427 -322.464657)
			(xy 34.938647 -322.406113) (xy 35.007994 -322.353744) (xy 35.081878 -322.307997) (xy 35.159667 -322.269263)
			(xy 35.240699 -322.237871) (xy 35.324281 -322.21409) (xy 35.409701 -322.198122) (xy 35.49623 -322.190104)
			(xy 35.58313 -322.190104) (xy 35.669659 -322.198122) (xy 35.755079 -322.21409) (xy 35.838661 -322.237871)
			(xy 35.919693 -322.269263) (xy 35.997482 -322.307997) (xy 36.071366 -322.353744) (xy 36.140713 -322.406113)
			(xy 36.204933 -322.464657) (xy 36.263477 -322.528877) (xy 36.315846 -322.598224) (xy 36.361593 -322.672108)
			(xy 36.400327 -322.749897) (xy 36.431719 -322.830929) (xy 36.4555 -322.914511) (xy 36.471468 -322.999931)
			(xy 36.479486 -323.08646) (xy 36.479988 -323.12991) (xy 36.479486 -323.17336) (xy 36.473971 -323.232881)
			(xy 65.298566 -323.232881) (xy 65.298566 -323.161559) (xy 65.306552 -323.090685) (xy 65.322422 -323.02115)
			(xy 65.345979 -322.95383) (xy 65.376924 -322.889571) (xy 65.41487 -322.82918) (xy 65.459339 -322.773418)
			(xy 65.509772 -322.722985) (xy 65.565534 -322.678516) (xy 65.625925 -322.64057) (xy 65.690184 -322.609625)
			(xy 65.757504 -322.586068) (xy 65.827039 -322.570198) (xy 65.897913 -322.562212) (xy 65.969235 -322.562212)
			(xy 66.040109 -322.570198) (xy 66.109644 -322.586068) (xy 66.176964 -322.609625) (xy 66.241223 -322.64057)
			(xy 66.301614 -322.678516) (xy 66.357376 -322.722985) (xy 66.407809 -322.773418) (xy 66.452278 -322.82918)
			(xy 66.490224 -322.889571) (xy 66.521169 -322.95383) (xy 66.544726 -323.02115) (xy 66.560596 -323.090685)
			(xy 66.568582 -323.161559) (xy 66.569082 -323.19722) (xy 66.568582 -323.232881) (xy 68.10298 -323.232881)
			(xy 68.10298 -323.161559) (xy 68.110966 -323.090685) (xy 68.126836 -323.02115) (xy 68.150393 -322.95383)
			(xy 68.181338 -322.889571) (xy 68.219284 -322.82918) (xy 68.263753 -322.773418) (xy 68.314186 -322.722985)
			(xy 68.369948 -322.678516) (xy 68.430339 -322.64057) (xy 68.494598 -322.609625) (xy 68.561918 -322.586068)
			(xy 68.631453 -322.570198) (xy 68.702327 -322.562212) (xy 68.773649 -322.562212) (xy 68.844523 -322.570198)
			(xy 68.914058 -322.586068) (xy 68.981378 -322.609625) (xy 69.045637 -322.64057) (xy 69.106028 -322.678516)
			(xy 69.16179 -322.722985) (xy 69.212223 -322.773418) (xy 69.256692 -322.82918) (xy 69.294638 -322.889571)
			(xy 69.325583 -322.95383) (xy 69.34914 -323.02115) (xy 69.36501 -323.090685) (xy 69.372996 -323.161559)
			(xy 69.373496 -323.19722) (xy 69.372996 -323.232881) (xy 69.36501 -323.303755) (xy 69.34914 -323.37329)
			(xy 69.325583 -323.44061) (xy 69.294638 -323.504869) (xy 69.256692 -323.56526) (xy 69.212223 -323.621022)
			(xy 69.16179 -323.671455) (xy 69.106028 -323.715924) (xy 69.045637 -323.75387) (xy 68.981378 -323.784815)
			(xy 68.914058 -323.808372) (xy 68.844523 -323.824242) (xy 68.773649 -323.832228) (xy 68.702327 -323.832228)
			(xy 68.631453 -323.824242) (xy 68.561918 -323.808372) (xy 68.494598 -323.784815) (xy 68.430339 -323.75387)
			(xy 68.369948 -323.715924) (xy 68.314186 -323.671455) (xy 68.263753 -323.621022) (xy 68.219284 -323.56526)
			(xy 68.181338 -323.504869) (xy 68.150393 -323.44061) (xy 68.126836 -323.37329) (xy 68.110966 -323.303755)
			(xy 68.10298 -323.232881) (xy 66.568582 -323.232881) (xy 66.560596 -323.303755) (xy 66.544726 -323.37329)
			(xy 66.521169 -323.44061) (xy 66.490224 -323.504869) (xy 66.452278 -323.56526) (xy 66.407809 -323.621022)
			(xy 66.357376 -323.671455) (xy 66.301614 -323.715924) (xy 66.241223 -323.75387) (xy 66.176964 -323.784815)
			(xy 66.109644 -323.808372) (xy 66.040109 -323.824242) (xy 65.969235 -323.832228) (xy 65.897913 -323.832228)
			(xy 65.827039 -323.824242) (xy 65.757504 -323.808372) (xy 65.690184 -323.784815) (xy 65.625925 -323.75387)
			(xy 65.565534 -323.715924) (xy 65.509772 -323.671455) (xy 65.459339 -323.621022) (xy 65.41487 -323.56526)
			(xy 65.376924 -323.504869) (xy 65.345979 -323.44061) (xy 65.322422 -323.37329) (xy 65.306552 -323.303755)
			(xy 65.298566 -323.232881) (xy 36.473971 -323.232881) (xy 36.471468 -323.259889) (xy 36.4555 -323.345309)
			(xy 36.431719 -323.428891) (xy 36.400327 -323.509923) (xy 36.361593 -323.587712) (xy 36.315846 -323.661596)
			(xy 36.263477 -323.730943) (xy 36.204933 -323.795163) (xy 36.140713 -323.853707) (xy 36.071366 -323.906076)
			(xy 35.997482 -323.951823) (xy 35.919693 -323.990557) (xy 35.838661 -324.021949) (xy 35.755079 -324.04573)
			(xy 35.669659 -324.061698) (xy 35.58313 -324.069716) (xy 35.49623 -324.069716) (xy 35.409701 -324.061698)
			(xy 35.324281 -324.04573) (xy 35.240699 -324.021949) (xy 35.159667 -323.990557) (xy 35.081878 -323.951823)
			(xy 35.007994 -323.906076) (xy 34.938647 -323.853707) (xy 34.874427 -323.795163) (xy 34.815883 -323.730943)
			(xy 34.763514 -323.661596) (xy 34.717767 -323.587712) (xy 34.679033 -323.509923) (xy 34.647641 -323.428891)
			(xy 34.62386 -323.345309) (xy 34.607892 -323.259889) (xy 34.599874 -323.17336) (xy 31.398557 -323.17336)
			(xy 31.39658 -323.216318) (xy 31.384682 -323.302009) (xy 31.364962 -323.386245) (xy 31.337589 -323.468314)
			(xy 31.302793 -323.547521) (xy 31.260868 -323.623198) (xy 31.212169 -323.694703) (xy 31.157109 -323.761433)
			(xy 31.096151 -323.822823) (xy 31.029813 -323.878355) (xy 30.958653 -323.927558) (xy 30.883276 -323.970017)
			(xy 30.804316 -324.005373) (xy 30.722444 -324.033326) (xy 30.638349 -324.053641) (xy 30.552744 -324.066145)
			(xy 30.466352 -324.070734) (xy 30.379905 -324.067368) (xy 30.294131 -324.056075) (xy 30.209758 -324.036951)
			(xy 30.127498 -324.010158) (xy 30.08757 -323.99351) (xy 30.066403 -323.984941) (xy 30.021906 -323.974702)
			(xy 29.976295 -323.972576) (xy 29.931038 -323.978634) (xy 29.887591 -323.992679) (xy 29.847352 -324.014259)
			(xy 29.811616 -324.042681) (xy 29.781532 -324.07703) (xy 29.758068 -324.116201) (xy 29.74198 -324.158933)
			(xy 29.733784 -324.203852) (xy 29.73324 -324.226682) (xy 29.73324 -324.573138) (xy 29.733718 -324.59598)
			(xy 29.741878 -324.64093) (xy 29.757945 -324.683696) (xy 29.781402 -324.722898) (xy 29.811492 -324.757274)
			(xy 29.847245 -324.785713) (xy 29.887507 -324.8073) (xy 29.930982 -324.821337) (xy 29.976265 -324.827373)
			(xy 30.021899 -324.825213) (xy 30.06641 -324.814926) (xy 30.08757 -324.80631) (xy 30.127491 -324.789645)
			(xy 30.20975 -324.762851) (xy 30.294124 -324.743727) (xy 30.379897 -324.732433) (xy 30.466345 -324.729066)
			(xy 30.552736 -324.733654) (xy 30.638341 -324.746158) (xy 30.722436 -324.766472) (xy 30.804309 -324.794424)
			(xy 30.883269 -324.82978) (xy 30.958647 -324.872238) (xy 31.029806 -324.92144) (xy 31.096145 -324.976971)
			(xy 31.157103 -325.038361) (xy 31.212165 -325.105091) (xy 31.260864 -325.176596) (xy 31.302789 -325.252272)
			(xy 31.337586 -325.331479) (xy 31.36496 -325.413547) (xy 31.38468 -325.497783) (xy 31.39658 -325.583474)
			(xy 31.400557 -325.669896) (xy 31.398557 -325.71336) (xy 34.599874 -325.71336) (xy 34.599874 -325.62646)
			(xy 34.607892 -325.539931) (xy 34.62386 -325.454511) (xy 34.647641 -325.370929) (xy 34.679033 -325.289897)
			(xy 34.717767 -325.212108) (xy 34.763514 -325.138224) (xy 34.815883 -325.068877) (xy 34.874427 -325.004657)
			(xy 34.938647 -324.946113) (xy 35.007994 -324.893744) (xy 35.081878 -324.847997) (xy 35.159667 -324.809263)
			(xy 35.240699 -324.777871) (xy 35.324281 -324.75409) (xy 35.409701 -324.738122) (xy 35.49623 -324.730104)
			(xy 35.58313 -324.730104) (xy 35.669659 -324.738122) (xy 35.755079 -324.75409) (xy 35.838661 -324.777871)
			(xy 35.919693 -324.809263) (xy 35.997482 -324.847997) (xy 36.071366 -324.893744) (xy 36.140713 -324.946113)
			(xy 36.204933 -325.004657) (xy 36.263477 -325.068877) (xy 36.315846 -325.138224) (xy 36.361593 -325.212108)
			(xy 36.400327 -325.289897) (xy 36.431719 -325.370929) (xy 36.4555 -325.454511) (xy 36.471468 -325.539931)
			(xy 36.479486 -325.62646) (xy 36.479988 -325.66991) (xy 36.479486 -325.71336) (xy 36.471468 -325.799889)
			(xy 36.4555 -325.885309) (xy 36.45027 -325.903691) (xy 65.298566 -325.903691) (xy 65.298566 -325.832369)
			(xy 65.306552 -325.761495) (xy 65.322422 -325.69196) (xy 65.345979 -325.62464) (xy 65.376924 -325.560381)
			(xy 65.41487 -325.49999) (xy 65.459339 -325.444228) (xy 65.509772 -325.393795) (xy 65.565534 -325.349326)
			(xy 65.625925 -325.31138) (xy 65.690184 -325.280435) (xy 65.757504 -325.256878) (xy 65.827039 -325.241008)
			(xy 65.897913 -325.233022) (xy 65.969235 -325.233022) (xy 66.040109 -325.241008) (xy 66.109644 -325.256878)
			(xy 66.176964 -325.280435) (xy 66.241223 -325.31138) (xy 66.301614 -325.349326) (xy 66.357376 -325.393795)
			(xy 66.407809 -325.444228) (xy 66.452278 -325.49999) (xy 66.490224 -325.560381) (xy 66.521169 -325.62464)
			(xy 66.544726 -325.69196) (xy 66.560596 -325.761495) (xy 66.568582 -325.832369) (xy 66.569082 -325.86803)
			(xy 66.568582 -325.903691) (xy 68.10298 -325.903691) (xy 68.10298 -325.832369) (xy 68.110966 -325.761495)
			(xy 68.126836 -325.69196) (xy 68.150393 -325.62464) (xy 68.181338 -325.560381) (xy 68.219284 -325.49999)
			(xy 68.263753 -325.444228) (xy 68.314186 -325.393795) (xy 68.369948 -325.349326) (xy 68.430339 -325.31138)
			(xy 68.494598 -325.280435) (xy 68.561918 -325.256878) (xy 68.631453 -325.241008) (xy 68.702327 -325.233022)
			(xy 68.773649 -325.233022) (xy 68.844523 -325.241008) (xy 68.914058 -325.256878) (xy 68.981378 -325.280435)
			(xy 69.045637 -325.31138) (xy 69.106028 -325.349326) (xy 69.16179 -325.393795) (xy 69.212223 -325.444228)
			(xy 69.256692 -325.49999) (xy 69.294638 -325.560381) (xy 69.325583 -325.62464) (xy 69.34914 -325.69196)
			(xy 69.36501 -325.761495) (xy 69.372996 -325.832369) (xy 69.373496 -325.86803) (xy 69.372996 -325.903691)
			(xy 69.36501 -325.974565) (xy 69.34914 -326.0441) (xy 69.325583 -326.11142) (xy 69.294638 -326.175679)
			(xy 69.256692 -326.23607) (xy 69.212223 -326.291832) (xy 69.16179 -326.342265) (xy 69.106028 -326.386734)
			(xy 69.045637 -326.42468) (xy 68.981378 -326.455625) (xy 68.914058 -326.479182) (xy 68.844523 -326.495052)
			(xy 68.773649 -326.503038) (xy 68.702327 -326.503038) (xy 68.631453 -326.495052) (xy 68.561918 -326.479182)
			(xy 68.494598 -326.455625) (xy 68.430339 -326.42468) (xy 68.369948 -326.386734) (xy 68.314186 -326.342265)
			(xy 68.263753 -326.291832) (xy 68.219284 -326.23607) (xy 68.181338 -326.175679) (xy 68.150393 -326.11142)
			(xy 68.126836 -326.0441) (xy 68.110966 -325.974565) (xy 68.10298 -325.903691) (xy 66.568582 -325.903691)
			(xy 66.560596 -325.974565) (xy 66.544726 -326.0441) (xy 66.521169 -326.11142) (xy 66.490224 -326.175679)
			(xy 66.452278 -326.23607) (xy 66.407809 -326.291832) (xy 66.357376 -326.342265) (xy 66.301614 -326.386734)
			(xy 66.241223 -326.42468) (xy 66.176964 -326.455625) (xy 66.109644 -326.479182) (xy 66.040109 -326.495052)
			(xy 65.969235 -326.503038) (xy 65.897913 -326.503038) (xy 65.827039 -326.495052) (xy 65.757504 -326.479182)
			(xy 65.690184 -326.455625) (xy 65.625925 -326.42468) (xy 65.565534 -326.386734) (xy 65.509772 -326.342265)
			(xy 65.459339 -326.291832) (xy 65.41487 -326.23607) (xy 65.376924 -326.175679) (xy 65.345979 -326.11142)
			(xy 65.322422 -326.0441) (xy 65.306552 -325.974565) (xy 65.298566 -325.903691) (xy 36.45027 -325.903691)
			(xy 36.431719 -325.968891) (xy 36.400327 -326.049923) (xy 36.361593 -326.127712) (xy 36.315846 -326.201596)
			(xy 36.263477 -326.270943) (xy 36.204933 -326.335163) (xy 36.140713 -326.393707) (xy 36.071366 -326.446076)
			(xy 35.997482 -326.491823) (xy 35.919693 -326.530557) (xy 35.838661 -326.561949) (xy 35.755079 -326.58573)
			(xy 35.669659 -326.601698) (xy 35.58313 -326.609716) (xy 35.49623 -326.609716) (xy 35.409701 -326.601698)
			(xy 35.324281 -326.58573) (xy 35.240699 -326.561949) (xy 35.159667 -326.530557) (xy 35.081878 -326.491823)
			(xy 35.007994 -326.446076) (xy 34.938647 -326.393707) (xy 34.874427 -326.335163) (xy 34.815883 -326.270943)
			(xy 34.763514 -326.201596) (xy 34.717767 -326.127712) (xy 34.679033 -326.049923) (xy 34.647641 -325.968891)
			(xy 34.62386 -325.885309) (xy 34.607892 -325.799889) (xy 34.599874 -325.71336) (xy 31.398557 -325.71336)
			(xy 31.39658 -325.756318) (xy 31.384682 -325.842009) (xy 31.364962 -325.926245) (xy 31.337589 -326.008314)
			(xy 31.302793 -326.087521) (xy 31.260868 -326.163198) (xy 31.212169 -326.234703) (xy 31.157109 -326.301433)
			(xy 31.096151 -326.362823) (xy 31.029813 -326.418355) (xy 30.958653 -326.467558) (xy 30.883276 -326.510017)
			(xy 30.804316 -326.545373) (xy 30.722444 -326.573326) (xy 30.638349 -326.593641) (xy 30.552744 -326.606145)
			(xy 30.466352 -326.610734) (xy 30.379905 -326.607368) (xy 30.294131 -326.596075) (xy 30.209758 -326.576951)
			(xy 30.127498 -326.550158) (xy 30.08757 -326.53351) (xy 30.066403 -326.524941) (xy 30.021906 -326.514702)
			(xy 29.976295 -326.512576) (xy 29.931038 -326.518634) (xy 29.887591 -326.532679) (xy 29.847352 -326.554259)
			(xy 29.811616 -326.582681) (xy 29.781532 -326.61703) (xy 29.758068 -326.656201) (xy 29.74198 -326.698933)
			(xy 29.733784 -326.743852) (xy 29.73324 -326.766682) (xy 29.73324 -327.002749) (xy 55.045348 -327.002749)
			(xy 55.045348 -326.931427) (xy 55.053334 -326.860553) (xy 55.069204 -326.791018) (xy 55.092761 -326.723698)
			(xy 55.123706 -326.659439) (xy 55.161652 -326.599048) (xy 55.206121 -326.543286) (xy 55.256554 -326.492853)
			(xy 55.312316 -326.448384) (xy 55.372707 -326.410438) (xy 55.436966 -326.379493) (xy 55.504286 -326.355936)
			(xy 55.573821 -326.340066) (xy 55.644695 -326.33208) (xy 55.716017 -326.33208) (xy 55.786891 -326.340066)
			(xy 55.856426 -326.355936) (xy 55.923746 -326.379493) (xy 55.988005 -326.410438) (xy 56.048396 -326.448384)
			(xy 56.104158 -326.492853) (xy 56.154591 -326.543286) (xy 56.19906 -326.599048) (xy 56.237006 -326.659439)
			(xy 56.267951 -326.723698) (xy 56.291508 -326.791018) (xy 56.307378 -326.860553) (xy 56.315364 -326.931427)
			(xy 56.315864 -326.967088) (xy 56.315364 -327.002749) (xy 56.93206 -327.002749) (xy 56.93206 -326.931427)
			(xy 56.940046 -326.860553) (xy 56.955916 -326.791018) (xy 56.979473 -326.723698) (xy 57.010418 -326.659439)
			(xy 57.048364 -326.599048) (xy 57.092833 -326.543286) (xy 57.143266 -326.492853) (xy 57.199028 -326.448384)
			(xy 57.259419 -326.410438) (xy 57.323678 -326.379493) (xy 57.390998 -326.355936) (xy 57.460533 -326.340066)
			(xy 57.531407 -326.33208) (xy 57.602729 -326.33208) (xy 57.673603 -326.340066) (xy 57.743138 -326.355936)
			(xy 57.810458 -326.379493) (xy 57.874717 -326.410438) (xy 57.935108 -326.448384) (xy 57.99087 -326.492853)
			(xy 58.041303 -326.543286) (xy 58.085772 -326.599048) (xy 58.123718 -326.659439) (xy 58.154663 -326.723698)
			(xy 58.17822 -326.791018) (xy 58.19409 -326.860553) (xy 58.202076 -326.931427) (xy 58.202576 -326.967088)
			(xy 58.202076 -327.002749) (xy 58.19409 -327.073623) (xy 58.17822 -327.143158) (xy 58.154663 -327.210478)
			(xy 58.123718 -327.274737) (xy 58.085772 -327.335128) (xy 58.041303 -327.39089) (xy 57.99087 -327.441323)
			(xy 57.935108 -327.485792) (xy 57.874717 -327.523738) (xy 57.810458 -327.554683) (xy 57.743138 -327.57824)
			(xy 57.673603 -327.59411) (xy 57.602729 -327.602096) (xy 57.531407 -327.602096) (xy 57.460533 -327.59411)
			(xy 57.390998 -327.57824) (xy 57.323678 -327.554683) (xy 57.259419 -327.523738) (xy 57.199028 -327.485792)
			(xy 57.143266 -327.441323) (xy 57.092833 -327.39089) (xy 57.048364 -327.335128) (xy 57.010418 -327.274737)
			(xy 56.979473 -327.210478) (xy 56.955916 -327.143158) (xy 56.940046 -327.073623) (xy 56.93206 -327.002749)
			(xy 56.315364 -327.002749) (xy 56.307378 -327.073623) (xy 56.291508 -327.143158) (xy 56.267951 -327.210478)
			(xy 56.237006 -327.274737) (xy 56.19906 -327.335128) (xy 56.154591 -327.39089) (xy 56.104158 -327.441323)
			(xy 56.048396 -327.485792) (xy 55.988005 -327.523738) (xy 55.923746 -327.554683) (xy 55.856426 -327.57824)
			(xy 55.786891 -327.59411) (xy 55.716017 -327.602096) (xy 55.644695 -327.602096) (xy 55.573821 -327.59411)
			(xy 55.504286 -327.57824) (xy 55.436966 -327.554683) (xy 55.372707 -327.523738) (xy 55.312316 -327.485792)
			(xy 55.256554 -327.441323) (xy 55.206121 -327.39089) (xy 55.161652 -327.335128) (xy 55.123706 -327.274737)
			(xy 55.092761 -327.210478) (xy 55.069204 -327.143158) (xy 55.053334 -327.073623) (xy 55.045348 -327.002749)
			(xy 29.73324 -327.002749) (xy 29.73324 -327.113138) (xy 29.733718 -327.13598) (xy 29.741878 -327.18093)
			(xy 29.757945 -327.223696) (xy 29.781402 -327.262898) (xy 29.811492 -327.297274) (xy 29.847245 -327.325713)
			(xy 29.887507 -327.3473) (xy 29.930982 -327.361337) (xy 29.976265 -327.367373) (xy 30.021899 -327.365213)
			(xy 30.06641 -327.354926) (xy 30.08757 -327.34631) (xy 30.127491 -327.329645) (xy 30.20975 -327.302851)
			(xy 30.294124 -327.283727) (xy 30.379897 -327.272433) (xy 30.466345 -327.269066) (xy 30.552736 -327.273654)
			(xy 30.638341 -327.286158) (xy 30.722436 -327.306472) (xy 30.804309 -327.334424) (xy 30.883269 -327.36978)
			(xy 30.958647 -327.412238) (xy 31.029806 -327.46144) (xy 31.096145 -327.516971) (xy 31.157103 -327.578361)
			(xy 31.212165 -327.645091) (xy 31.260864 -327.716596) (xy 31.302789 -327.792272) (xy 31.337586 -327.871479)
			(xy 31.36496 -327.953547) (xy 31.38468 -328.037783) (xy 31.39658 -328.123474) (xy 31.400557 -328.209896)
			(xy 31.398557 -328.25336) (xy 34.599874 -328.25336) (xy 34.599874 -328.16646) (xy 34.607892 -328.079931)
			(xy 34.62386 -327.994511) (xy 34.647641 -327.910929) (xy 34.679033 -327.829897) (xy 34.717767 -327.752108)
			(xy 34.763514 -327.678224) (xy 34.815883 -327.608877) (xy 34.874427 -327.544657) (xy 34.938647 -327.486113)
			(xy 35.007994 -327.433744) (xy 35.081878 -327.387997) (xy 35.159667 -327.349263) (xy 35.240699 -327.317871)
			(xy 35.324281 -327.29409) (xy 35.409701 -327.278122) (xy 35.49623 -327.270104) (xy 35.58313 -327.270104)
			(xy 35.669659 -327.278122) (xy 35.755079 -327.29409) (xy 35.838661 -327.317871) (xy 35.919693 -327.349263)
			(xy 35.997482 -327.387997) (xy 36.071366 -327.433744) (xy 36.140713 -327.486113) (xy 36.204933 -327.544657)
			(xy 36.263477 -327.608877) (xy 36.315846 -327.678224) (xy 36.361593 -327.752108) (xy 36.400327 -327.829897)
			(xy 36.431719 -327.910929) (xy 36.4555 -327.994511) (xy 36.471468 -328.079931) (xy 36.479486 -328.16646)
			(xy 36.479988 -328.20991) (xy 36.479486 -328.25336) (xy 36.471468 -328.339889) (xy 36.4555 -328.425309)
			(xy 36.431719 -328.508891) (xy 36.400327 -328.589923) (xy 36.361593 -328.667712) (xy 36.315846 -328.741596)
			(xy 36.263477 -328.810943) (xy 36.240293 -328.836375) (xy 55.045348 -328.836375) (xy 55.045348 -328.765053)
			(xy 55.053334 -328.694179) (xy 55.069204 -328.624644) (xy 55.092761 -328.557324) (xy 55.123706 -328.493065)
			(xy 55.161652 -328.432674) (xy 55.206121 -328.376912) (xy 55.256554 -328.326479) (xy 55.312316 -328.28201)
			(xy 55.372707 -328.244064) (xy 55.436966 -328.213119) (xy 55.504286 -328.189562) (xy 55.573821 -328.173692)
			(xy 55.644695 -328.165706) (xy 55.716017 -328.165706) (xy 55.786891 -328.173692) (xy 55.856426 -328.189562)
			(xy 55.923746 -328.213119) (xy 55.988005 -328.244064) (xy 56.048396 -328.28201) (xy 56.104158 -328.326479)
			(xy 56.154591 -328.376912) (xy 56.19906 -328.432674) (xy 56.237006 -328.493065) (xy 56.267951 -328.557324)
			(xy 56.291508 -328.624644) (xy 56.307378 -328.694179) (xy 56.315364 -328.765053) (xy 56.315864 -328.800714)
			(xy 56.315364 -328.836375) (xy 56.93206 -328.836375) (xy 56.93206 -328.765053) (xy 56.940046 -328.694179)
			(xy 56.955916 -328.624644) (xy 56.979473 -328.557324) (xy 57.010418 -328.493065) (xy 57.048364 -328.432674)
			(xy 57.092833 -328.376912) (xy 57.143266 -328.326479) (xy 57.199028 -328.28201) (xy 57.259419 -328.244064)
			(xy 57.323678 -328.213119) (xy 57.390998 -328.189562) (xy 57.460533 -328.173692) (xy 57.531407 -328.165706)
			(xy 57.602729 -328.165706) (xy 57.673603 -328.173692) (xy 57.743138 -328.189562) (xy 57.810458 -328.213119)
			(xy 57.874717 -328.244064) (xy 57.935108 -328.28201) (xy 57.99087 -328.326479) (xy 58.041303 -328.376912)
			(xy 58.085772 -328.432674) (xy 58.123718 -328.493065) (xy 58.154663 -328.557324) (xy 58.17822 -328.624644)
			(xy 58.19409 -328.694179) (xy 58.202076 -328.765053) (xy 58.202576 -328.800714) (xy 58.202076 -328.836375)
			(xy 59.173102 -328.836375) (xy 59.173102 -328.765053) (xy 59.181088 -328.694179) (xy 59.196958 -328.624644)
			(xy 59.220515 -328.557324) (xy 59.25146 -328.493065) (xy 59.289406 -328.432674) (xy 59.333875 -328.376912)
			(xy 59.384308 -328.326479) (xy 59.44007 -328.28201) (xy 59.500461 -328.244064) (xy 59.56472 -328.213119)
			(xy 59.63204 -328.189562) (xy 59.701575 -328.173692) (xy 59.772449 -328.165706) (xy 59.843771 -328.165706)
			(xy 59.914645 -328.173692) (xy 59.98418 -328.189562) (xy 60.0515 -328.213119) (xy 60.115759 -328.244064)
			(xy 60.17615 -328.28201) (xy 60.231912 -328.326479) (xy 60.282345 -328.376912) (xy 60.326814 -328.432674)
			(xy 60.36476 -328.493065) (xy 60.395705 -328.557324) (xy 60.419262 -328.624644) (xy 60.435132 -328.694179)
			(xy 60.443118 -328.765053) (xy 60.443618 -328.800714) (xy 60.443118 -328.836375) (xy 61.077086 -328.836375)
			(xy 61.077086 -328.765053) (xy 61.085072 -328.694179) (xy 61.100942 -328.624644) (xy 61.124499 -328.557324)
			(xy 61.155444 -328.493065) (xy 61.19339 -328.432674) (xy 61.237859 -328.376912) (xy 61.288292 -328.326479)
			(xy 61.344054 -328.28201) (xy 61.404445 -328.244064) (xy 61.468704 -328.213119) (xy 61.536024 -328.189562)
			(xy 61.605559 -328.173692) (xy 61.676433 -328.165706) (xy 61.747755 -328.165706) (xy 61.818629 -328.173692)
			(xy 61.888164 -328.189562) (xy 61.955484 -328.213119) (xy 62.019743 -328.244064) (xy 62.080134 -328.28201)
			(xy 62.135896 -328.326479) (xy 62.186329 -328.376912) (xy 62.230798 -328.432674) (xy 62.268744 -328.493065)
			(xy 62.299689 -328.557324) (xy 62.304811 -328.571961) (xy 65.298566 -328.571961) (xy 65.298566 -328.500639)
			(xy 65.306552 -328.429765) (xy 65.322422 -328.36023) (xy 65.345979 -328.29291) (xy 65.376924 -328.228651)
			(xy 65.41487 -328.16826) (xy 65.459339 -328.112498) (xy 65.509772 -328.062065) (xy 65.565534 -328.017596)
			(xy 65.625925 -327.97965) (xy 65.690184 -327.948705) (xy 65.757504 -327.925148) (xy 65.827039 -327.909278)
			(xy 65.897913 -327.901292) (xy 65.969235 -327.901292) (xy 66.040109 -327.909278) (xy 66.109644 -327.925148)
			(xy 66.176964 -327.948705) (xy 66.241223 -327.97965) (xy 66.301614 -328.017596) (xy 66.357376 -328.062065)
			(xy 66.407809 -328.112498) (xy 66.452278 -328.16826) (xy 66.490224 -328.228651) (xy 66.521169 -328.29291)
			(xy 66.544726 -328.36023) (xy 66.560596 -328.429765) (xy 66.568582 -328.500639) (xy 66.569082 -328.5363)
			(xy 66.568582 -328.571961) (xy 68.10298 -328.571961) (xy 68.10298 -328.500639) (xy 68.110966 -328.429765)
			(xy 68.126836 -328.36023) (xy 68.150393 -328.29291) (xy 68.181338 -328.228651) (xy 68.219284 -328.16826)
			(xy 68.263753 -328.112498) (xy 68.314186 -328.062065) (xy 68.369948 -328.017596) (xy 68.430339 -327.97965)
			(xy 68.494598 -327.948705) (xy 68.561918 -327.925148) (xy 68.631453 -327.909278) (xy 68.702327 -327.901292)
			(xy 68.773649 -327.901292) (xy 68.844523 -327.909278) (xy 68.914058 -327.925148) (xy 68.981378 -327.948705)
			(xy 69.045637 -327.97965) (xy 69.106028 -328.017596) (xy 69.16179 -328.062065) (xy 69.212223 -328.112498)
			(xy 69.256692 -328.16826) (xy 69.294638 -328.228651) (xy 69.325583 -328.29291) (xy 69.34914 -328.36023)
			(xy 69.36501 -328.429765) (xy 69.372996 -328.500639) (xy 69.373496 -328.5363) (xy 69.372996 -328.571961)
			(xy 69.36501 -328.642835) (xy 69.34914 -328.71237) (xy 69.325583 -328.77969) (xy 69.294638 -328.843949)
			(xy 69.256692 -328.90434) (xy 69.212223 -328.960102) (xy 69.16179 -329.010535) (xy 69.106028 -329.055004)
			(xy 69.045637 -329.09295) (xy 68.981378 -329.123895) (xy 68.914058 -329.147452) (xy 68.844523 -329.163322)
			(xy 68.773649 -329.171308) (xy 68.702327 -329.171308) (xy 68.631453 -329.163322) (xy 68.561918 -329.147452)
			(xy 68.494598 -329.123895) (xy 68.430339 -329.09295) (xy 68.369948 -329.055004) (xy 68.314186 -329.010535)
			(xy 68.263753 -328.960102) (xy 68.219284 -328.90434) (xy 68.181338 -328.843949) (xy 68.150393 -328.77969)
			(xy 68.126836 -328.71237) (xy 68.110966 -328.642835) (xy 68.10298 -328.571961) (xy 66.568582 -328.571961)
			(xy 66.560596 -328.642835) (xy 66.544726 -328.71237) (xy 66.521169 -328.77969) (xy 66.490224 -328.843949)
			(xy 66.452278 -328.90434) (xy 66.407809 -328.960102) (xy 66.357376 -329.010535) (xy 66.301614 -329.055004)
			(xy 66.241223 -329.09295) (xy 66.176964 -329.123895) (xy 66.109644 -329.147452) (xy 66.040109 -329.163322)
			(xy 65.969235 -329.171308) (xy 65.897913 -329.171308) (xy 65.827039 -329.163322) (xy 65.757504 -329.147452)
			(xy 65.690184 -329.123895) (xy 65.625925 -329.09295) (xy 65.565534 -329.055004) (xy 65.509772 -329.010535)
			(xy 65.459339 -328.960102) (xy 65.41487 -328.90434) (xy 65.376924 -328.843949) (xy 65.345979 -328.77969)
			(xy 65.322422 -328.71237) (xy 65.306552 -328.642835) (xy 65.298566 -328.571961) (xy 62.304811 -328.571961)
			(xy 62.323246 -328.624644) (xy 62.339116 -328.694179) (xy 62.347102 -328.765053) (xy 62.347602 -328.800714)
			(xy 62.347102 -328.836375) (xy 62.339116 -328.907249) (xy 62.323246 -328.976784) (xy 62.299689 -329.044104)
			(xy 62.268744 -329.108363) (xy 62.230798 -329.168754) (xy 62.186329 -329.224516) (xy 62.135896 -329.274949)
			(xy 62.080134 -329.319418) (xy 62.019743 -329.357364) (xy 61.955484 -329.388309) (xy 61.888164 -329.411866)
			(xy 61.818629 -329.427736) (xy 61.747755 -329.435722) (xy 61.676433 -329.435722) (xy 61.605559 -329.427736)
			(xy 61.536024 -329.411866) (xy 61.468704 -329.388309) (xy 61.404445 -329.357364) (xy 61.344054 -329.319418)
			(xy 61.288292 -329.274949) (xy 61.237859 -329.224516) (xy 61.19339 -329.168754) (xy 61.155444 -329.108363)
			(xy 61.124499 -329.044104) (xy 61.100942 -328.976784) (xy 61.085072 -328.907249) (xy 61.077086 -328.836375)
			(xy 60.443118 -328.836375) (xy 60.435132 -328.907249) (xy 60.419262 -328.976784) (xy 60.395705 -329.044104)
			(xy 60.36476 -329.108363) (xy 60.326814 -329.168754) (xy 60.282345 -329.224516) (xy 60.231912 -329.274949)
			(xy 60.17615 -329.319418) (xy 60.115759 -329.357364) (xy 60.0515 -329.388309) (xy 59.98418 -329.411866)
			(xy 59.914645 -329.427736) (xy 59.843771 -329.435722) (xy 59.772449 -329.435722) (xy 59.701575 -329.427736)
			(xy 59.63204 -329.411866) (xy 59.56472 -329.388309) (xy 59.500461 -329.357364) (xy 59.44007 -329.319418)
			(xy 59.384308 -329.274949) (xy 59.333875 -329.224516) (xy 59.289406 -329.168754) (xy 59.25146 -329.108363)
			(xy 59.220515 -329.044104) (xy 59.196958 -328.976784) (xy 59.181088 -328.907249) (xy 59.173102 -328.836375)
			(xy 58.202076 -328.836375) (xy 58.19409 -328.907249) (xy 58.17822 -328.976784) (xy 58.154663 -329.044104)
			(xy 58.123718 -329.108363) (xy 58.085772 -329.168754) (xy 58.041303 -329.224516) (xy 57.99087 -329.274949)
			(xy 57.935108 -329.319418) (xy 57.874717 -329.357364) (xy 57.810458 -329.388309) (xy 57.743138 -329.411866)
			(xy 57.673603 -329.427736) (xy 57.602729 -329.435722) (xy 57.531407 -329.435722) (xy 57.460533 -329.427736)
			(xy 57.390998 -329.411866) (xy 57.323678 -329.388309) (xy 57.259419 -329.357364) (xy 57.199028 -329.319418)
			(xy 57.143266 -329.274949) (xy 57.092833 -329.224516) (xy 57.048364 -329.168754) (xy 57.010418 -329.108363)
			(xy 56.979473 -329.044104) (xy 56.955916 -328.976784) (xy 56.940046 -328.907249) (xy 56.93206 -328.836375)
			(xy 56.315364 -328.836375) (xy 56.307378 -328.907249) (xy 56.291508 -328.976784) (xy 56.267951 -329.044104)
			(xy 56.237006 -329.108363) (xy 56.19906 -329.168754) (xy 56.154591 -329.224516) (xy 56.104158 -329.274949)
			(xy 56.048396 -329.319418) (xy 55.988005 -329.357364) (xy 55.923746 -329.388309) (xy 55.856426 -329.411866)
			(xy 55.786891 -329.427736) (xy 55.716017 -329.435722) (xy 55.644695 -329.435722) (xy 55.573821 -329.427736)
			(xy 55.504286 -329.411866) (xy 55.436966 -329.388309) (xy 55.372707 -329.357364) (xy 55.312316 -329.319418)
			(xy 55.256554 -329.274949) (xy 55.206121 -329.224516) (xy 55.161652 -329.168754) (xy 55.123706 -329.108363)
			(xy 55.092761 -329.044104) (xy 55.069204 -328.976784) (xy 55.053334 -328.907249) (xy 55.045348 -328.836375)
			(xy 36.240293 -328.836375) (xy 36.204933 -328.875163) (xy 36.140713 -328.933707) (xy 36.071366 -328.986076)
			(xy 35.997482 -329.031823) (xy 35.919693 -329.070557) (xy 35.838661 -329.101949) (xy 35.755079 -329.12573)
			(xy 35.669659 -329.141698) (xy 35.58313 -329.149716) (xy 35.49623 -329.149716) (xy 35.409701 -329.141698)
			(xy 35.324281 -329.12573) (xy 35.240699 -329.101949) (xy 35.159667 -329.070557) (xy 35.081878 -329.031823)
			(xy 35.007994 -328.986076) (xy 34.938647 -328.933707) (xy 34.874427 -328.875163) (xy 34.815883 -328.810943)
			(xy 34.763514 -328.741596) (xy 34.717767 -328.667712) (xy 34.679033 -328.589923) (xy 34.647641 -328.508891)
			(xy 34.62386 -328.425309) (xy 34.607892 -328.339889) (xy 34.599874 -328.25336) (xy 31.398557 -328.25336)
			(xy 31.39658 -328.296318) (xy 31.384682 -328.382009) (xy 31.364962 -328.466245) (xy 31.337589 -328.548314)
			(xy 31.302793 -328.627521) (xy 31.260868 -328.703198) (xy 31.212169 -328.774703) (xy 31.157109 -328.841433)
			(xy 31.096151 -328.902823) (xy 31.029813 -328.958355) (xy 30.958653 -329.007558) (xy 30.883276 -329.050017)
			(xy 30.804316 -329.085373) (xy 30.722444 -329.113326) (xy 30.638349 -329.133641) (xy 30.552744 -329.146145)
			(xy 30.466352 -329.150734) (xy 30.379905 -329.147368) (xy 30.294131 -329.136075) (xy 30.209758 -329.116951)
			(xy 30.127498 -329.090158) (xy 30.08757 -329.07351) (xy 30.066403 -329.064941) (xy 30.021906 -329.054702)
			(xy 29.976295 -329.052576) (xy 29.931038 -329.058634) (xy 29.887591 -329.072679) (xy 29.847352 -329.094259)
			(xy 29.811616 -329.122681) (xy 29.781532 -329.15703) (xy 29.758068 -329.196201) (xy 29.74198 -329.238933)
			(xy 29.733784 -329.283852) (xy 29.73324 -329.306682) (xy 29.73324 -329.653138) (xy 29.733718 -329.67598)
			(xy 29.741878 -329.72093) (xy 29.757945 -329.763696) (xy 29.781402 -329.802898) (xy 29.811492 -329.837274)
			(xy 29.847245 -329.865713) (xy 29.887507 -329.8873) (xy 29.930982 -329.901337) (xy 29.976265 -329.907373)
			(xy 30.021899 -329.905213) (xy 30.06641 -329.894926) (xy 30.08757 -329.88631) (xy 30.127491 -329.869645)
			(xy 30.20975 -329.842851) (xy 30.294124 -329.823727) (xy 30.379897 -329.812433) (xy 30.466345 -329.809066)
			(xy 30.552736 -329.813654) (xy 30.638341 -329.826158) (xy 30.722436 -329.846472) (xy 30.804309 -329.874424)
			(xy 30.883269 -329.90978) (xy 30.958647 -329.952238) (xy 31.029806 -330.00144) (xy 31.096145 -330.056971)
			(xy 31.157103 -330.118361) (xy 31.212165 -330.185091) (xy 31.260864 -330.256596) (xy 31.302789 -330.332272)
			(xy 31.337586 -330.411479) (xy 31.36496 -330.493547) (xy 31.38468 -330.577783) (xy 31.39658 -330.663474)
			(xy 31.400557 -330.749896) (xy 31.398557 -330.79336) (xy 34.599874 -330.79336) (xy 34.599874 -330.70646)
			(xy 34.607892 -330.619931) (xy 34.62386 -330.534511) (xy 34.647641 -330.450929) (xy 34.679033 -330.369897)
			(xy 34.717767 -330.292108) (xy 34.763514 -330.218224) (xy 34.815883 -330.148877) (xy 34.874427 -330.084657)
			(xy 34.938647 -330.026113) (xy 35.007994 -329.973744) (xy 35.081878 -329.927997) (xy 35.159667 -329.889263)
			(xy 35.240699 -329.857871) (xy 35.324281 -329.83409) (xy 35.409701 -329.818122) (xy 35.49623 -329.810104)
			(xy 35.58313 -329.810104) (xy 35.669659 -329.818122) (xy 35.755079 -329.83409) (xy 35.838661 -329.857871)
			(xy 35.919693 -329.889263) (xy 35.997482 -329.927997) (xy 36.071366 -329.973744) (xy 36.12331 -330.012971)
			(xy 51.403494 -330.012971) (xy 51.403494 -329.931861) (xy 51.411444 -329.851142) (xy 51.427267 -329.771591)
			(xy 51.450812 -329.693975) (xy 51.481851 -329.619039) (xy 51.520086 -329.547507) (xy 51.565148 -329.480067)
			(xy 51.616603 -329.417368) (xy 51.673956 -329.360015) (xy 51.736655 -329.30856) (xy 51.804095 -329.263498)
			(xy 51.875627 -329.225263) (xy 51.950563 -329.194224) (xy 52.028179 -329.170679) (xy 52.10773 -329.154856)
			(xy 52.188449 -329.146906) (xy 52.269559 -329.146906) (xy 52.350278 -329.154856) (xy 52.429829 -329.170679)
			(xy 52.507445 -329.194224) (xy 52.582381 -329.225263) (xy 52.653913 -329.263498) (xy 52.721353 -329.30856)
			(xy 52.784052 -329.360015) (xy 52.841405 -329.417368) (xy 52.89286 -329.480067) (xy 52.937922 -329.547507)
			(xy 52.976157 -329.619039) (xy 53.007196 -329.693975) (xy 53.030741 -329.771591) (xy 53.046564 -329.851142)
			(xy 53.054514 -329.931861) (xy 53.055012 -329.972416) (xy 53.054514 -330.012971) (xy 53.046564 -330.09369)
			(xy 53.030741 -330.173241) (xy 53.007196 -330.250857) (xy 52.976157 -330.325793) (xy 52.937922 -330.397325)
			(xy 52.89286 -330.464765) (xy 52.841405 -330.527464) (xy 52.784052 -330.584817) (xy 52.721353 -330.636272)
			(xy 52.653913 -330.681334) (xy 52.582381 -330.719569) (xy 52.539547 -330.737311) (xy 55.045348 -330.737311)
			(xy 55.045348 -330.665989) (xy 55.053334 -330.595115) (xy 55.069204 -330.52558) (xy 55.092761 -330.45826)
			(xy 55.123706 -330.394001) (xy 55.161652 -330.33361) (xy 55.206121 -330.277848) (xy 55.256554 -330.227415)
			(xy 55.312316 -330.182946) (xy 55.372707 -330.145) (xy 55.436966 -330.114055) (xy 55.504286 -330.090498)
			(xy 55.573821 -330.074628) (xy 55.644695 -330.066642) (xy 55.716017 -330.066642) (xy 55.786891 -330.074628)
			(xy 55.856426 -330.090498) (xy 55.923746 -330.114055) (xy 55.988005 -330.145) (xy 56.048396 -330.182946)
			(xy 56.104158 -330.227415) (xy 56.154591 -330.277848) (xy 56.19906 -330.33361) (xy 56.237006 -330.394001)
			(xy 56.267951 -330.45826) (xy 56.291508 -330.52558) (xy 56.307378 -330.595115) (xy 56.315364 -330.665989)
			(xy 56.315864 -330.70165) (xy 56.315364 -330.737311) (xy 56.93206 -330.737311) (xy 56.93206 -330.665989)
			(xy 56.940046 -330.595115) (xy 56.955916 -330.52558) (xy 56.979473 -330.45826) (xy 57.010418 -330.394001)
			(xy 57.048364 -330.33361) (xy 57.092833 -330.277848) (xy 57.143266 -330.227415) (xy 57.199028 -330.182946)
			(xy 57.259419 -330.145) (xy 57.323678 -330.114055) (xy 57.390998 -330.090498) (xy 57.460533 -330.074628)
			(xy 57.531407 -330.066642) (xy 57.602729 -330.066642) (xy 57.673603 -330.074628) (xy 57.743138 -330.090498)
			(xy 57.810458 -330.114055) (xy 57.874717 -330.145) (xy 57.935108 -330.182946) (xy 57.99087 -330.227415)
			(xy 58.041303 -330.277848) (xy 58.085772 -330.33361) (xy 58.123718 -330.394001) (xy 58.154663 -330.45826)
			(xy 58.17822 -330.52558) (xy 58.19409 -330.595115) (xy 58.202076 -330.665989) (xy 58.202576 -330.70165)
			(xy 58.202076 -330.737311) (xy 59.173102 -330.737311) (xy 59.173102 -330.665989) (xy 59.181088 -330.595115)
			(xy 59.196958 -330.52558) (xy 59.220515 -330.45826) (xy 59.25146 -330.394001) (xy 59.289406 -330.33361)
			(xy 59.333875 -330.277848) (xy 59.384308 -330.227415) (xy 59.44007 -330.182946) (xy 59.500461 -330.145)
			(xy 59.56472 -330.114055) (xy 59.63204 -330.090498) (xy 59.701575 -330.074628) (xy 59.772449 -330.066642)
			(xy 59.843771 -330.066642) (xy 59.914645 -330.074628) (xy 59.98418 -330.090498) (xy 60.0515 -330.114055)
			(xy 60.115759 -330.145) (xy 60.17615 -330.182946) (xy 60.231912 -330.227415) (xy 60.282345 -330.277848)
			(xy 60.326814 -330.33361) (xy 60.36476 -330.394001) (xy 60.395705 -330.45826) (xy 60.419262 -330.52558)
			(xy 60.435132 -330.595115) (xy 60.443118 -330.665989) (xy 60.443618 -330.70165) (xy 60.443118 -330.737311)
			(xy 61.077086 -330.737311) (xy 61.077086 -330.665989) (xy 61.085072 -330.595115) (xy 61.100942 -330.52558)
			(xy 61.124499 -330.45826) (xy 61.155444 -330.394001) (xy 61.19339 -330.33361) (xy 61.237859 -330.277848)
			(xy 61.288292 -330.227415) (xy 61.344054 -330.182946) (xy 61.404445 -330.145) (xy 61.468704 -330.114055)
			(xy 61.536024 -330.090498) (xy 61.605559 -330.074628) (xy 61.676433 -330.066642) (xy 61.747755 -330.066642)
			(xy 61.818629 -330.074628) (xy 61.888164 -330.090498) (xy 61.955484 -330.114055) (xy 62.019743 -330.145)
			(xy 62.080134 -330.182946) (xy 62.135896 -330.227415) (xy 62.186329 -330.277848) (xy 62.230798 -330.33361)
			(xy 62.268744 -330.394001) (xy 62.299689 -330.45826) (xy 62.323246 -330.52558) (xy 62.339116 -330.595115)
			(xy 62.347102 -330.665989) (xy 62.347602 -330.70165) (xy 62.347102 -330.737311) (xy 62.339116 -330.808185)
			(xy 62.323246 -330.87772) (xy 62.300207 -330.943559) (xy 65.298566 -330.943559) (xy 65.298566 -330.872237)
			(xy 65.306552 -330.801363) (xy 65.322422 -330.731828) (xy 65.345979 -330.664508) (xy 65.376924 -330.600249)
			(xy 65.41487 -330.539858) (xy 65.459339 -330.484096) (xy 65.509772 -330.433663) (xy 65.565534 -330.389194)
			(xy 65.625925 -330.351248) (xy 65.690184 -330.320303) (xy 65.757504 -330.296746) (xy 65.827039 -330.280876)
			(xy 65.897913 -330.27289) (xy 65.969235 -330.27289) (xy 66.040109 -330.280876) (xy 66.109644 -330.296746)
			(xy 66.176964 -330.320303) (xy 66.241223 -330.351248) (xy 66.301614 -330.389194) (xy 66.357376 -330.433663)
			(xy 66.407809 -330.484096) (xy 66.452278 -330.539858) (xy 66.490224 -330.600249) (xy 66.521169 -330.664508)
			(xy 66.544726 -330.731828) (xy 66.560596 -330.801363) (xy 66.568582 -330.872237) (xy 66.569082 -330.907898)
			(xy 66.568582 -330.943559) (xy 68.10298 -330.943559) (xy 68.10298 -330.872237) (xy 68.110966 -330.801363)
			(xy 68.126836 -330.731828) (xy 68.150393 -330.664508) (xy 68.181338 -330.600249) (xy 68.219284 -330.539858)
			(xy 68.263753 -330.484096) (xy 68.314186 -330.433663) (xy 68.369948 -330.389194) (xy 68.430339 -330.351248)
			(xy 68.494598 -330.320303) (xy 68.561918 -330.296746) (xy 68.631453 -330.280876) (xy 68.702327 -330.27289)
			(xy 68.773649 -330.27289) (xy 68.844523 -330.280876) (xy 68.914058 -330.296746) (xy 68.981378 -330.320303)
			(xy 69.045637 -330.351248) (xy 69.106028 -330.389194) (xy 69.16179 -330.433663) (xy 69.212223 -330.484096)
			(xy 69.256692 -330.539858) (xy 69.294638 -330.600249) (xy 69.325583 -330.664508) (xy 69.34914 -330.731828)
			(xy 69.36501 -330.801363) (xy 69.372996 -330.872237) (xy 69.373496 -330.907898) (xy 69.372996 -330.943559)
			(xy 69.36501 -331.014433) (xy 69.34914 -331.083968) (xy 69.325583 -331.151288) (xy 69.294638 -331.215547)
			(xy 69.256692 -331.275938) (xy 69.212223 -331.3317) (xy 69.16179 -331.382133) (xy 69.106028 -331.426602)
			(xy 69.045637 -331.464548) (xy 68.981378 -331.495493) (xy 68.914058 -331.51905) (xy 68.844523 -331.53492)
			(xy 68.773649 -331.542906) (xy 68.702327 -331.542906) (xy 68.631453 -331.53492) (xy 68.561918 -331.51905)
			(xy 68.494598 -331.495493) (xy 68.430339 -331.464548) (xy 68.369948 -331.426602) (xy 68.314186 -331.382133)
			(xy 68.263753 -331.3317) (xy 68.219284 -331.275938) (xy 68.181338 -331.215547) (xy 68.150393 -331.151288)
			(xy 68.126836 -331.083968) (xy 68.110966 -331.014433) (xy 68.10298 -330.943559) (xy 66.568582 -330.943559)
			(xy 66.560596 -331.014433) (xy 66.544726 -331.083968) (xy 66.521169 -331.151288) (xy 66.490224 -331.215547)
			(xy 66.452278 -331.275938) (xy 66.407809 -331.3317) (xy 66.357376 -331.382133) (xy 66.301614 -331.426602)
			(xy 66.241223 -331.464548) (xy 66.176964 -331.495493) (xy 66.109644 -331.51905) (xy 66.040109 -331.53492)
			(xy 65.969235 -331.542906) (xy 65.897913 -331.542906) (xy 65.827039 -331.53492) (xy 65.757504 -331.51905)
			(xy 65.690184 -331.495493) (xy 65.625925 -331.464548) (xy 65.565534 -331.426602) (xy 65.509772 -331.382133)
			(xy 65.459339 -331.3317) (xy 65.41487 -331.275938) (xy 65.376924 -331.215547) (xy 65.345979 -331.151288)
			(xy 65.322422 -331.083968) (xy 65.306552 -331.014433) (xy 65.298566 -330.943559) (xy 62.300207 -330.943559)
			(xy 62.299689 -330.94504) (xy 62.268744 -331.009299) (xy 62.230798 -331.06969) (xy 62.186329 -331.125452)
			(xy 62.135896 -331.175885) (xy 62.080134 -331.220354) (xy 62.019743 -331.2583) (xy 61.955484 -331.289245)
			(xy 61.888164 -331.312802) (xy 61.818629 -331.328672) (xy 61.747755 -331.336658) (xy 61.676433 -331.336658)
			(xy 61.605559 -331.328672) (xy 61.536024 -331.312802) (xy 61.468704 -331.289245) (xy 61.404445 -331.2583)
			(xy 61.344054 -331.220354) (xy 61.288292 -331.175885) (xy 61.237859 -331.125452) (xy 61.19339 -331.06969)
			(xy 61.155444 -331.009299) (xy 61.124499 -330.94504) (xy 61.100942 -330.87772) (xy 61.085072 -330.808185)
			(xy 61.077086 -330.737311) (xy 60.443118 -330.737311) (xy 60.435132 -330.808185) (xy 60.419262 -330.87772)
			(xy 60.395705 -330.94504) (xy 60.36476 -331.009299) (xy 60.326814 -331.06969) (xy 60.282345 -331.125452)
			(xy 60.231912 -331.175885) (xy 60.17615 -331.220354) (xy 60.115759 -331.2583) (xy 60.0515 -331.289245)
			(xy 59.98418 -331.312802) (xy 59.914645 -331.328672) (xy 59.843771 -331.336658) (xy 59.772449 -331.336658)
			(xy 59.701575 -331.328672) (xy 59.63204 -331.312802) (xy 59.56472 -331.289245) (xy 59.500461 -331.2583)
			(xy 59.44007 -331.220354) (xy 59.384308 -331.175885) (xy 59.333875 -331.125452) (xy 59.289406 -331.06969)
			(xy 59.25146 -331.009299) (xy 59.220515 -330.94504) (xy 59.196958 -330.87772) (xy 59.181088 -330.808185)
			(xy 59.173102 -330.737311) (xy 58.202076 -330.737311) (xy 58.19409 -330.808185) (xy 58.17822 -330.87772)
			(xy 58.154663 -330.94504) (xy 58.123718 -331.009299) (xy 58.085772 -331.06969) (xy 58.041303 -331.125452)
			(xy 57.99087 -331.175885) (xy 57.935108 -331.220354) (xy 57.874717 -331.2583) (xy 57.810458 -331.289245)
			(xy 57.743138 -331.312802) (xy 57.673603 -331.328672) (xy 57.602729 -331.336658) (xy 57.531407 -331.336658)
			(xy 57.460533 -331.328672) (xy 57.390998 -331.312802) (xy 57.323678 -331.289245) (xy 57.259419 -331.2583)
			(xy 57.199028 -331.220354) (xy 57.143266 -331.175885) (xy 57.092833 -331.125452) (xy 57.048364 -331.06969)
			(xy 57.010418 -331.009299) (xy 56.979473 -330.94504) (xy 56.955916 -330.87772) (xy 56.940046 -330.808185)
			(xy 56.93206 -330.737311) (xy 56.315364 -330.737311) (xy 56.307378 -330.808185) (xy 56.291508 -330.87772)
			(xy 56.267951 -330.94504) (xy 56.237006 -331.009299) (xy 56.19906 -331.06969) (xy 56.154591 -331.125452)
			(xy 56.104158 -331.175885) (xy 56.048396 -331.220354) (xy 55.988005 -331.2583) (xy 55.923746 -331.289245)
			(xy 55.856426 -331.312802) (xy 55.786891 -331.328672) (xy 55.716017 -331.336658) (xy 55.644695 -331.336658)
			(xy 55.573821 -331.328672) (xy 55.504286 -331.312802) (xy 55.436966 -331.289245) (xy 55.372707 -331.2583)
			(xy 55.312316 -331.220354) (xy 55.256554 -331.175885) (xy 55.206121 -331.125452) (xy 55.161652 -331.06969)
			(xy 55.123706 -331.009299) (xy 55.092761 -330.94504) (xy 55.069204 -330.87772) (xy 55.053334 -330.808185)
			(xy 55.045348 -330.737311) (xy 52.539547 -330.737311) (xy 52.507445 -330.750608) (xy 52.429829 -330.774153)
			(xy 52.350278 -330.789976) (xy 52.269559 -330.797926) (xy 52.188449 -330.797926) (xy 52.10773 -330.789976)
			(xy 52.028179 -330.774153) (xy 51.950563 -330.750608) (xy 51.875627 -330.719569) (xy 51.804095 -330.681334)
			(xy 51.736655 -330.636272) (xy 51.673956 -330.584817) (xy 51.616603 -330.527464) (xy 51.565148 -330.464765)
			(xy 51.520086 -330.397325) (xy 51.481851 -330.325793) (xy 51.450812 -330.250857) (xy 51.427267 -330.173241)
			(xy 51.411444 -330.09369) (xy 51.403494 -330.012971) (xy 36.12331 -330.012971) (xy 36.140713 -330.026113)
			(xy 36.204933 -330.084657) (xy 36.263477 -330.148877) (xy 36.315846 -330.218224) (xy 36.361593 -330.292108)
			(xy 36.400327 -330.369897) (xy 36.431719 -330.450929) (xy 36.4555 -330.534511) (xy 36.471468 -330.619931)
			(xy 36.479486 -330.70646) (xy 36.479988 -330.74991) (xy 36.479486 -330.79336) (xy 36.471468 -330.879889)
			(xy 36.4555 -330.965309) (xy 36.431719 -331.048891) (xy 36.400327 -331.129923) (xy 36.361593 -331.207712)
			(xy 36.315846 -331.281596) (xy 36.263477 -331.350943) (xy 36.204933 -331.415163) (xy 36.140713 -331.473707)
			(xy 36.071366 -331.526076) (xy 35.997482 -331.571823) (xy 35.919693 -331.610557) (xy 35.838661 -331.641949)
			(xy 35.755079 -331.66573) (xy 35.669659 -331.681698) (xy 35.58313 -331.689716) (xy 35.49623 -331.689716)
			(xy 35.409701 -331.681698) (xy 35.324281 -331.66573) (xy 35.240699 -331.641949) (xy 35.159667 -331.610557)
			(xy 35.081878 -331.571823) (xy 35.007994 -331.526076) (xy 34.938647 -331.473707) (xy 34.874427 -331.415163)
			(xy 34.815883 -331.350943) (xy 34.763514 -331.281596) (xy 34.717767 -331.207712) (xy 34.679033 -331.129923)
			(xy 34.647641 -331.048891) (xy 34.62386 -330.965309) (xy 34.607892 -330.879889) (xy 34.599874 -330.79336)
			(xy 31.398557 -330.79336) (xy 31.39658 -330.836318) (xy 31.384682 -330.922009) (xy 31.364962 -331.006245)
			(xy 31.337589 -331.088314) (xy 31.302793 -331.167521) (xy 31.260868 -331.243198) (xy 31.212169 -331.314703)
			(xy 31.157109 -331.381433) (xy 31.096151 -331.442823) (xy 31.029813 -331.498355) (xy 30.958653 -331.547558)
			(xy 30.883276 -331.590017) (xy 30.804316 -331.625373) (xy 30.722444 -331.653326) (xy 30.638349 -331.673641)
			(xy 30.552744 -331.686145) (xy 30.466352 -331.690734) (xy 30.379905 -331.687368) (xy 30.294131 -331.676075)
			(xy 30.209758 -331.656951) (xy 30.127498 -331.630158) (xy 30.08757 -331.61351) (xy 30.066403 -331.604941)
			(xy 30.021906 -331.594702) (xy 29.976295 -331.592576) (xy 29.931038 -331.598634) (xy 29.887591 -331.612679)
			(xy 29.847352 -331.634259) (xy 29.811616 -331.662681) (xy 29.781532 -331.69703) (xy 29.758068 -331.736201)
			(xy 29.74198 -331.778933) (xy 29.733784 -331.823852) (xy 29.73324 -331.846682) (xy 29.73324 -332.193138)
			(xy 29.73338 -332.199843) (xy 38.925238 -332.199843) (xy 38.925238 -332.128521) (xy 38.933224 -332.057647)
			(xy 38.949094 -331.988112) (xy 38.972651 -331.920792) (xy 39.003596 -331.856533) (xy 39.041542 -331.796142)
			(xy 39.086011 -331.74038) (xy 39.136444 -331.689947) (xy 39.192206 -331.645478) (xy 39.252597 -331.607532)
			(xy 39.316856 -331.576587) (xy 39.384176 -331.55303) (xy 39.453711 -331.53716) (xy 39.524585 -331.529174)
			(xy 39.595907 -331.529174) (xy 39.666781 -331.53716) (xy 39.736316 -331.55303) (xy 39.803636 -331.576587)
			(xy 39.867895 -331.607532) (xy 39.928286 -331.645478) (xy 39.984048 -331.689947) (xy 40.034481 -331.74038)
			(xy 40.07895 -331.796142) (xy 40.116896 -331.856533) (xy 40.147841 -331.920792) (xy 40.171398 -331.988112)
			(xy 40.187268 -332.057647) (xy 40.195254 -332.128521) (xy 40.195754 -332.164182) (xy 40.195254 -332.199843)
			(xy 40.187268 -332.270717) (xy 40.171398 -332.340252) (xy 40.147841 -332.407572) (xy 40.116896 -332.471831)
			(xy 40.097715 -332.502357) (xy 55.079638 -332.502357) (xy 55.079638 -332.431035) (xy 55.087624 -332.360161)
			(xy 55.103494 -332.290626) (xy 55.127051 -332.223306) (xy 55.157996 -332.159047) (xy 55.195942 -332.098656)
			(xy 55.240411 -332.042894) (xy 55.290844 -331.992461) (xy 55.346606 -331.947992) (xy 55.406997 -331.910046)
			(xy 55.471256 -331.879101) (xy 55.538576 -331.855544) (xy 55.608111 -331.839674) (xy 55.678985 -331.831688)
			(xy 55.750307 -331.831688) (xy 55.821181 -331.839674) (xy 55.890716 -331.855544) (xy 55.958036 -331.879101)
			(xy 56.022295 -331.910046) (xy 56.082686 -331.947992) (xy 56.138448 -331.992461) (xy 56.188881 -332.042894)
			(xy 56.23335 -332.098656) (xy 56.271296 -332.159047) (xy 56.302241 -332.223306) (xy 56.325798 -332.290626)
			(xy 56.341668 -332.360161) (xy 56.349654 -332.431035) (xy 56.350154 -332.466696) (xy 56.349654 -332.502357)
			(xy 56.96635 -332.502357) (xy 56.96635 -332.431035) (xy 56.974336 -332.360161) (xy 56.990206 -332.290626)
			(xy 57.013763 -332.223306) (xy 57.044708 -332.159047) (xy 57.082654 -332.098656) (xy 57.127123 -332.042894)
			(xy 57.177556 -331.992461) (xy 57.233318 -331.947992) (xy 57.293709 -331.910046) (xy 57.357968 -331.879101)
			(xy 57.425288 -331.855544) (xy 57.494823 -331.839674) (xy 57.565697 -331.831688) (xy 57.637019 -331.831688)
			(xy 57.707893 -331.839674) (xy 57.777428 -331.855544) (xy 57.844748 -331.879101) (xy 57.909007 -331.910046)
			(xy 57.969398 -331.947992) (xy 58.02516 -331.992461) (xy 58.075593 -332.042894) (xy 58.120062 -332.098656)
			(xy 58.158008 -332.159047) (xy 58.188953 -332.223306) (xy 58.21251 -332.290626) (xy 58.22838 -332.360161)
			(xy 58.236366 -332.431035) (xy 58.236866 -332.466696) (xy 58.236366 -332.502357) (xy 59.207392 -332.502357)
			(xy 59.207392 -332.431035) (xy 59.215378 -332.360161) (xy 59.231248 -332.290626) (xy 59.254805 -332.223306)
			(xy 59.28575 -332.159047) (xy 59.323696 -332.098656) (xy 59.368165 -332.042894) (xy 59.418598 -331.992461)
			(xy 59.47436 -331.947992) (xy 59.534751 -331.910046) (xy 59.59901 -331.879101) (xy 59.66633 -331.855544)
			(xy 59.735865 -331.839674) (xy 59.806739 -331.831688) (xy 59.878061 -331.831688) (xy 59.948935 -331.839674)
			(xy 60.01847 -331.855544) (xy 60.08579 -331.879101) (xy 60.150049 -331.910046) (xy 60.21044 -331.947992)
			(xy 60.266202 -331.992461) (xy 60.316635 -332.042894) (xy 60.361104 -332.098656) (xy 60.39905 -332.159047)
			(xy 60.429995 -332.223306) (xy 60.453552 -332.290626) (xy 60.469422 -332.360161) (xy 60.477408 -332.431035)
			(xy 60.477908 -332.466696) (xy 60.477408 -332.502357) (xy 61.111376 -332.502357) (xy 61.111376 -332.431035)
			(xy 61.119362 -332.360161) (xy 61.135232 -332.290626) (xy 61.158789 -332.223306) (xy 61.189734 -332.159047)
			(xy 61.22768 -332.098656) (xy 61.272149 -332.042894) (xy 61.322582 -331.992461) (xy 61.378344 -331.947992)
			(xy 61.438735 -331.910046) (xy 61.502994 -331.879101) (xy 61.570314 -331.855544) (xy 61.639849 -331.839674)
			(xy 61.710723 -331.831688) (xy 61.782045 -331.831688) (xy 61.852919 -331.839674) (xy 61.922454 -331.855544)
			(xy 61.989774 -331.879101) (xy 62.054033 -331.910046) (xy 62.114424 -331.947992) (xy 62.170186 -331.992461)
			(xy 62.220619 -332.042894) (xy 62.265088 -332.098656) (xy 62.303034 -332.159047) (xy 62.333979 -332.223306)
			(xy 62.357536 -332.290626) (xy 62.373406 -332.360161) (xy 62.381392 -332.431035) (xy 62.381892 -332.466696)
			(xy 62.381392 -332.502357) (xy 62.373406 -332.573231) (xy 62.357536 -332.642766) (xy 62.333979 -332.710086)
			(xy 62.303034 -332.774345) (xy 62.265088 -332.834736) (xy 62.220619 -332.890498) (xy 62.204646 -332.906471)
			(xy 65.298566 -332.906471) (xy 65.298566 -332.835149) (xy 65.306552 -332.764275) (xy 65.322422 -332.69474)
			(xy 65.345979 -332.62742) (xy 65.376924 -332.563161) (xy 65.41487 -332.50277) (xy 65.459339 -332.447008)
			(xy 65.509772 -332.396575) (xy 65.565534 -332.352106) (xy 65.625925 -332.31416) (xy 65.690184 -332.283215)
			(xy 65.757504 -332.259658) (xy 65.827039 -332.243788) (xy 65.897913 -332.235802) (xy 65.969235 -332.235802)
			(xy 66.040109 -332.243788) (xy 66.109644 -332.259658) (xy 66.176964 -332.283215) (xy 66.241223 -332.31416)
			(xy 66.301614 -332.352106) (xy 66.357376 -332.396575) (xy 66.407809 -332.447008) (xy 66.452278 -332.50277)
			(xy 66.490224 -332.563161) (xy 66.521169 -332.62742) (xy 66.544726 -332.69474) (xy 66.560596 -332.764275)
			(xy 66.568582 -332.835149) (xy 66.569082 -332.87081) (xy 66.568582 -332.906471) (xy 68.10298 -332.906471)
			(xy 68.10298 -332.835149) (xy 68.110966 -332.764275) (xy 68.126836 -332.69474) (xy 68.150393 -332.62742)
			(xy 68.181338 -332.563161) (xy 68.219284 -332.50277) (xy 68.263753 -332.447008) (xy 68.314186 -332.396575)
			(xy 68.369948 -332.352106) (xy 68.430339 -332.31416) (xy 68.494598 -332.283215) (xy 68.561918 -332.259658)
			(xy 68.631453 -332.243788) (xy 68.702327 -332.235802) (xy 68.773649 -332.235802) (xy 68.844523 -332.243788)
			(xy 68.914058 -332.259658) (xy 68.981378 -332.283215) (xy 69.045637 -332.31416) (xy 69.106028 -332.352106)
			(xy 69.16179 -332.396575) (xy 69.212223 -332.447008) (xy 69.256692 -332.50277) (xy 69.294638 -332.563161)
			(xy 69.325583 -332.62742) (xy 69.34914 -332.69474) (xy 69.36501 -332.764275) (xy 69.372996 -332.835149)
			(xy 69.373496 -332.87081) (xy 69.372996 -332.906471) (xy 69.36501 -332.977345) (xy 69.34914 -333.04688)
			(xy 69.325583 -333.1142) (xy 69.294638 -333.178459) (xy 69.256692 -333.23885) (xy 69.212223 -333.294612)
			(xy 69.16179 -333.345045) (xy 69.106028 -333.389514) (xy 69.045637 -333.42746) (xy 68.981378 -333.458405)
			(xy 68.914058 -333.481962) (xy 68.844523 -333.497832) (xy 68.773649 -333.505818) (xy 68.702327 -333.505818)
			(xy 68.631453 -333.497832) (xy 68.561918 -333.481962) (xy 68.494598 -333.458405) (xy 68.430339 -333.42746)
			(xy 68.369948 -333.389514) (xy 68.314186 -333.345045) (xy 68.263753 -333.294612) (xy 68.219284 -333.23885)
			(xy 68.181338 -333.178459) (xy 68.150393 -333.1142) (xy 68.126836 -333.04688) (xy 68.110966 -332.977345)
			(xy 68.10298 -332.906471) (xy 66.568582 -332.906471) (xy 66.560596 -332.977345) (xy 66.544726 -333.04688)
			(xy 66.521169 -333.1142) (xy 66.490224 -333.178459) (xy 66.452278 -333.23885) (xy 66.407809 -333.294612)
			(xy 66.357376 -333.345045) (xy 66.301614 -333.389514) (xy 66.241223 -333.42746) (xy 66.176964 -333.458405)
			(xy 66.109644 -333.481962) (xy 66.040109 -333.497832) (xy 65.969235 -333.505818) (xy 65.897913 -333.505818)
			(xy 65.827039 -333.497832) (xy 65.757504 -333.481962) (xy 65.690184 -333.458405) (xy 65.625925 -333.42746)
			(xy 65.565534 -333.389514) (xy 65.509772 -333.345045) (xy 65.459339 -333.294612) (xy 65.41487 -333.23885)
			(xy 65.376924 -333.178459) (xy 65.345979 -333.1142) (xy 65.322422 -333.04688) (xy 65.306552 -332.977345)
			(xy 65.298566 -332.906471) (xy 62.204646 -332.906471) (xy 62.170186 -332.940931) (xy 62.114424 -332.9854)
			(xy 62.054033 -333.023346) (xy 61.989774 -333.054291) (xy 61.922454 -333.077848) (xy 61.852919 -333.093718)
			(xy 61.782045 -333.101704) (xy 61.710723 -333.101704) (xy 61.639849 -333.093718) (xy 61.570314 -333.077848)
			(xy 61.502994 -333.054291) (xy 61.438735 -333.023346) (xy 61.378344 -332.9854) (xy 61.322582 -332.940931)
			(xy 61.272149 -332.890498) (xy 61.22768 -332.834736) (xy 61.189734 -332.774345) (xy 61.158789 -332.710086)
			(xy 61.135232 -332.642766) (xy 61.119362 -332.573231) (xy 61.111376 -332.502357) (xy 60.477408 -332.502357)
			(xy 60.469422 -332.573231) (xy 60.453552 -332.642766) (xy 60.429995 -332.710086) (xy 60.39905 -332.774345)
			(xy 60.361104 -332.834736) (xy 60.316635 -332.890498) (xy 60.266202 -332.940931) (xy 60.21044 -332.9854)
			(xy 60.150049 -333.023346) (xy 60.08579 -333.054291) (xy 60.01847 -333.077848) (xy 59.948935 -333.093718)
			(xy 59.878061 -333.101704) (xy 59.806739 -333.101704) (xy 59.735865 -333.093718) (xy 59.66633 -333.077848)
			(xy 59.59901 -333.054291) (xy 59.534751 -333.023346) (xy 59.47436 -332.9854) (xy 59.418598 -332.940931)
			(xy 59.368165 -332.890498) (xy 59.323696 -332.834736) (xy 59.28575 -332.774345) (xy 59.254805 -332.710086)
			(xy 59.231248 -332.642766) (xy 59.215378 -332.573231) (xy 59.207392 -332.502357) (xy 58.236366 -332.502357)
			(xy 58.22838 -332.573231) (xy 58.21251 -332.642766) (xy 58.188953 -332.710086) (xy 58.158008 -332.774345)
			(xy 58.120062 -332.834736) (xy 58.075593 -332.890498) (xy 58.02516 -332.940931) (xy 57.969398 -332.9854)
			(xy 57.909007 -333.023346) (xy 57.844748 -333.054291) (xy 57.777428 -333.077848) (xy 57.707893 -333.093718)
			(xy 57.637019 -333.101704) (xy 57.565697 -333.101704) (xy 57.494823 -333.093718) (xy 57.425288 -333.077848)
			(xy 57.357968 -333.054291) (xy 57.293709 -333.023346) (xy 57.233318 -332.9854) (xy 57.177556 -332.940931)
			(xy 57.127123 -332.890498) (xy 57.082654 -332.834736) (xy 57.044708 -332.774345) (xy 57.013763 -332.710086)
			(xy 56.990206 -332.642766) (xy 56.974336 -332.573231) (xy 56.96635 -332.502357) (xy 56.349654 -332.502357)
			(xy 56.341668 -332.573231) (xy 56.325798 -332.642766) (xy 56.302241 -332.710086) (xy 56.271296 -332.774345)
			(xy 56.23335 -332.834736) (xy 56.188881 -332.890498) (xy 56.138448 -332.940931) (xy 56.082686 -332.9854)
			(xy 56.022295 -333.023346) (xy 55.958036 -333.054291) (xy 55.890716 -333.077848) (xy 55.821181 -333.093718)
			(xy 55.750307 -333.101704) (xy 55.678985 -333.101704) (xy 55.608111 -333.093718) (xy 55.538576 -333.077848)
			(xy 55.471256 -333.054291) (xy 55.406997 -333.023346) (xy 55.346606 -332.9854) (xy 55.290844 -332.940931)
			(xy 55.240411 -332.890498) (xy 55.195942 -332.834736) (xy 55.157996 -332.774345) (xy 55.127051 -332.710086)
			(xy 55.103494 -332.642766) (xy 55.087624 -332.573231) (xy 55.079638 -332.502357) (xy 40.097715 -332.502357)
			(xy 40.07895 -332.532222) (xy 40.034481 -332.587984) (xy 39.984048 -332.638417) (xy 39.928286 -332.682886)
			(xy 39.867895 -332.720832) (xy 39.803636 -332.751777) (xy 39.736316 -332.775334) (xy 39.666781 -332.791204)
			(xy 39.595907 -332.79919) (xy 39.524585 -332.79919) (xy 39.453711 -332.791204) (xy 39.384176 -332.775334)
			(xy 39.316856 -332.751777) (xy 39.252597 -332.720832) (xy 39.192206 -332.682886) (xy 39.136444 -332.638417)
			(xy 39.086011 -332.587984) (xy 39.041542 -332.532222) (xy 39.003596 -332.471831) (xy 38.972651 -332.407572)
			(xy 38.949094 -332.340252) (xy 38.933224 -332.270717) (xy 38.925238 -332.199843) (xy 29.73338 -332.199843)
			(xy 29.733718 -332.21598) (xy 29.741878 -332.26093) (xy 29.757945 -332.303696) (xy 29.781402 -332.342898)
			(xy 29.811492 -332.377274) (xy 29.847245 -332.405713) (xy 29.887507 -332.4273) (xy 29.930982 -332.441337)
			(xy 29.976265 -332.447373) (xy 30.021899 -332.445213) (xy 30.06641 -332.434926) (xy 30.08757 -332.42631)
			(xy 30.127491 -332.409645) (xy 30.20975 -332.382851) (xy 30.294124 -332.363727) (xy 30.379897 -332.352433)
			(xy 30.466345 -332.349066) (xy 30.552736 -332.353654) (xy 30.638341 -332.366158) (xy 30.722436 -332.386472)
			(xy 30.804309 -332.414424) (xy 30.883269 -332.44978) (xy 30.958647 -332.492238) (xy 31.029806 -332.54144)
			(xy 31.096145 -332.596971) (xy 31.157103 -332.658361) (xy 31.212165 -332.725091) (xy 31.260864 -332.796596)
			(xy 31.302789 -332.872272) (xy 31.337586 -332.951479) (xy 31.36496 -333.033547) (xy 31.38468 -333.117783)
			(xy 31.39658 -333.203474) (xy 31.400557 -333.289896) (xy 31.398557 -333.33336) (xy 34.599874 -333.33336)
			(xy 34.599874 -333.24646) (xy 34.607892 -333.159931) (xy 34.62386 -333.074511) (xy 34.647641 -332.990929)
			(xy 34.679033 -332.909897) (xy 34.717767 -332.832108) (xy 34.763514 -332.758224) (xy 34.815883 -332.688877)
			(xy 34.874427 -332.624657) (xy 34.938647 -332.566113) (xy 35.007994 -332.513744) (xy 35.081878 -332.467997)
			(xy 35.159667 -332.429263) (xy 35.240699 -332.397871) (xy 35.324281 -332.37409) (xy 35.409701 -332.358122)
			(xy 35.49623 -332.350104) (xy 35.58313 -332.350104) (xy 35.669659 -332.358122) (xy 35.755079 -332.37409)
			(xy 35.838661 -332.397871) (xy 35.919693 -332.429263) (xy 35.997482 -332.467997) (xy 36.071366 -332.513744)
			(xy 36.140713 -332.566113) (xy 36.204933 -332.624657) (xy 36.263477 -332.688877) (xy 36.315846 -332.758224)
			(xy 36.361593 -332.832108) (xy 36.400327 -332.909897) (xy 36.431719 -332.990929) (xy 36.4555 -333.074511)
			(xy 36.471468 -333.159931) (xy 36.479486 -333.24646) (xy 36.479988 -333.28991) (xy 36.479486 -333.33336)
			(xy 36.471468 -333.419889) (xy 36.4555 -333.505309) (xy 36.431719 -333.588891) (xy 36.400327 -333.669923)
			(xy 36.361593 -333.747712) (xy 36.315846 -333.821596) (xy 36.263477 -333.890943) (xy 36.204933 -333.955163)
			(xy 36.140713 -334.013707) (xy 36.071366 -334.066076) (xy 35.997482 -334.111823) (xy 35.919693 -334.150557)
			(xy 35.838661 -334.181949) (xy 35.755079 -334.20573) (xy 35.669659 -334.221698) (xy 35.58313 -334.229716)
			(xy 35.49623 -334.229716) (xy 35.409701 -334.221698) (xy 35.324281 -334.20573) (xy 35.240699 -334.181949)
			(xy 35.159667 -334.150557) (xy 35.081878 -334.111823) (xy 35.007994 -334.066076) (xy 34.938647 -334.013707)
			(xy 34.874427 -333.955163) (xy 34.815883 -333.890943) (xy 34.763514 -333.821596) (xy 34.717767 -333.747712)
			(xy 34.679033 -333.669923) (xy 34.647641 -333.588891) (xy 34.62386 -333.505309) (xy 34.607892 -333.419889)
			(xy 34.599874 -333.33336) (xy 31.398557 -333.33336) (xy 31.39658 -333.376318) (xy 31.384682 -333.462009)
			(xy 31.364962 -333.546245) (xy 31.337589 -333.628314) (xy 31.302793 -333.707521) (xy 31.260868 -333.783198)
			(xy 31.212169 -333.854703) (xy 31.157109 -333.921433) (xy 31.096151 -333.982823) (xy 31.029813 -334.038355)
			(xy 30.958653 -334.087558) (xy 30.883276 -334.130017) (xy 30.804316 -334.165373) (xy 30.722444 -334.193326)
			(xy 30.638349 -334.213641) (xy 30.552744 -334.226145) (xy 30.466352 -334.230734) (xy 30.379905 -334.227368)
			(xy 30.294131 -334.216075) (xy 30.209758 -334.196951) (xy 30.127498 -334.170158) (xy 30.08757 -334.15351)
			(xy 30.066403 -334.144941) (xy 30.021906 -334.134702) (xy 29.976295 -334.132576) (xy 29.931038 -334.138634)
			(xy 29.887591 -334.152679) (xy 29.847352 -334.174259) (xy 29.811616 -334.202681) (xy 29.781532 -334.23703)
			(xy 29.758068 -334.276201) (xy 29.74198 -334.318933) (xy 29.733784 -334.363852) (xy 29.73324 -334.386682)
			(xy 29.73324 -334.733138) (xy 29.733718 -334.75598) (xy 29.741878 -334.80093) (xy 29.757945 -334.843696)
			(xy 29.774075 -334.870653) (xy 38.925238 -334.870653) (xy 38.925238 -334.799331) (xy 38.933224 -334.728457)
			(xy 38.949094 -334.658922) (xy 38.972651 -334.591602) (xy 39.003596 -334.527343) (xy 39.041542 -334.466952)
			(xy 39.086011 -334.41119) (xy 39.136444 -334.360757) (xy 39.192206 -334.316288) (xy 39.252597 -334.278342)
			(xy 39.316856 -334.247397) (xy 39.384176 -334.22384) (xy 39.453711 -334.20797) (xy 39.524585 -334.199984)
			(xy 39.595907 -334.199984) (xy 39.666781 -334.20797) (xy 39.736316 -334.22384) (xy 39.803636 -334.247397)
			(xy 39.867895 -334.278342) (xy 39.928286 -334.316288) (xy 39.984048 -334.360757) (xy 40.034481 -334.41119)
			(xy 40.07895 -334.466952) (xy 40.108216 -334.513529) (xy 55.036204 -334.513529) (xy 55.036204 -334.442207)
			(xy 55.04419 -334.371333) (xy 55.06006 -334.301798) (xy 55.083617 -334.234478) (xy 55.114562 -334.170219)
			(xy 55.152508 -334.109828) (xy 55.196977 -334.054066) (xy 55.24741 -334.003633) (xy 55.303172 -333.959164)
			(xy 55.363563 -333.921218) (xy 55.427822 -333.890273) (xy 55.495142 -333.866716) (xy 55.564677 -333.850846)
			(xy 55.635551 -333.84286) (xy 55.706873 -333.84286) (xy 55.777747 -333.850846) (xy 55.847282 -333.866716)
			(xy 55.914602 -333.890273) (xy 55.978861 -333.921218) (xy 56.039252 -333.959164) (xy 56.095014 -334.003633)
			(xy 56.145447 -334.054066) (xy 56.189916 -334.109828) (xy 56.227862 -334.170219) (xy 56.258807 -334.234478)
			(xy 56.282364 -334.301798) (xy 56.298234 -334.371333) (xy 56.30622 -334.442207) (xy 56.30672 -334.477868)
			(xy 56.30622 -334.513529) (xy 56.922916 -334.513529) (xy 56.922916 -334.442207) (xy 56.930902 -334.371333)
			(xy 56.946772 -334.301798) (xy 56.970329 -334.234478) (xy 57.001274 -334.170219) (xy 57.03922 -334.109828)
			(xy 57.083689 -334.054066) (xy 57.134122 -334.003633) (xy 57.189884 -333.959164) (xy 57.250275 -333.921218)
			(xy 57.314534 -333.890273) (xy 57.381854 -333.866716) (xy 57.451389 -333.850846) (xy 57.522263 -333.84286)
			(xy 57.593585 -333.84286) (xy 57.664459 -333.850846) (xy 57.733994 -333.866716) (xy 57.801314 -333.890273)
			(xy 57.865573 -333.921218) (xy 57.925964 -333.959164) (xy 57.981726 -334.003633) (xy 58.032159 -334.054066)
			(xy 58.076628 -334.109828) (xy 58.114574 -334.170219) (xy 58.145519 -334.234478) (xy 58.169076 -334.301798)
			(xy 58.184946 -334.371333) (xy 58.192932 -334.442207) (xy 58.193432 -334.477868) (xy 58.192932 -334.513529)
			(xy 59.163958 -334.513529) (xy 59.163958 -334.442207) (xy 59.171944 -334.371333) (xy 59.187814 -334.301798)
			(xy 59.211371 -334.234478) (xy 59.242316 -334.170219) (xy 59.280262 -334.109828) (xy 59.324731 -334.054066)
			(xy 59.375164 -334.003633) (xy 59.430926 -333.959164) (xy 59.491317 -333.921218) (xy 59.555576 -333.890273)
			(xy 59.622896 -333.866716) (xy 59.692431 -333.850846) (xy 59.763305 -333.84286) (xy 59.834627 -333.84286)
			(xy 59.905501 -333.850846) (xy 59.975036 -333.866716) (xy 60.042356 -333.890273) (xy 60.106615 -333.921218)
			(xy 60.167006 -333.959164) (xy 60.222768 -334.003633) (xy 60.273201 -334.054066) (xy 60.31767 -334.109828)
			(xy 60.355616 -334.170219) (xy 60.386561 -334.234478) (xy 60.410118 -334.301798) (xy 60.425988 -334.371333)
			(xy 60.433974 -334.442207) (xy 60.434474 -334.477868) (xy 60.433974 -334.513529) (xy 61.067942 -334.513529)
			(xy 61.067942 -334.442207) (xy 61.075928 -334.371333) (xy 61.091798 -334.301798) (xy 61.115355 -334.234478)
			(xy 61.1463 -334.170219) (xy 61.184246 -334.109828) (xy 61.228715 -334.054066) (xy 61.279148 -334.003633)
			(xy 61.33491 -333.959164) (xy 61.395301 -333.921218) (xy 61.45956 -333.890273) (xy 61.52688 -333.866716)
			(xy 61.596415 -333.850846) (xy 61.667289 -333.84286) (xy 61.738611 -333.84286) (xy 61.809485 -333.850846)
			(xy 61.87902 -333.866716) (xy 61.94634 -333.890273) (xy 62.010599 -333.921218) (xy 62.07099 -333.959164)
			(xy 62.126752 -334.003633) (xy 62.177185 -334.054066) (xy 62.221654 -334.109828) (xy 62.2596 -334.170219)
			(xy 62.290545 -334.234478) (xy 62.314102 -334.301798) (xy 62.329972 -334.371333) (xy 62.337958 -334.442207)
			(xy 62.338458 -334.477868) (xy 62.337958 -334.513529) (xy 62.329972 -334.584403) (xy 62.314102 -334.653938)
			(xy 62.290545 -334.721258) (xy 62.2596 -334.785517) (xy 62.221654 -334.845908) (xy 62.177185 -334.90167)
			(xy 62.126752 -334.952103) (xy 62.07099 -334.996572) (xy 62.010599 -335.034518) (xy 61.978498 -335.049977)
			(xy 65.298566 -335.049977) (xy 65.298566 -334.978655) (xy 65.306552 -334.907781) (xy 65.322422 -334.838246)
			(xy 65.345979 -334.770926) (xy 65.376924 -334.706667) (xy 65.41487 -334.646276) (xy 65.459339 -334.590514)
			(xy 65.509772 -334.540081) (xy 65.565534 -334.495612) (xy 65.625925 -334.457666) (xy 65.690184 -334.426721)
			(xy 65.757504 -334.403164) (xy 65.827039 -334.387294) (xy 65.897913 -334.379308) (xy 65.969235 -334.379308)
			(xy 66.040109 -334.387294) (xy 66.109644 -334.403164) (xy 66.176964 -334.426721) (xy 66.241223 -334.457666)
			(xy 66.301614 -334.495612) (xy 66.357376 -334.540081) (xy 66.407809 -334.590514) (xy 66.452278 -334.646276)
			(xy 66.490224 -334.706667) (xy 66.521169 -334.770926) (xy 66.544726 -334.838246) (xy 66.560596 -334.907781)
			(xy 66.568582 -334.978655) (xy 66.569082 -335.014316) (xy 66.568582 -335.049977) (xy 68.10298 -335.049977)
			(xy 68.10298 -334.978655) (xy 68.110966 -334.907781) (xy 68.126836 -334.838246) (xy 68.150393 -334.770926)
			(xy 68.181338 -334.706667) (xy 68.219284 -334.646276) (xy 68.263753 -334.590514) (xy 68.314186 -334.540081)
			(xy 68.369948 -334.495612) (xy 68.430339 -334.457666) (xy 68.494598 -334.426721) (xy 68.561918 -334.403164)
			(xy 68.631453 -334.387294) (xy 68.702327 -334.379308) (xy 68.773649 -334.379308) (xy 68.844523 -334.387294)
			(xy 68.914058 -334.403164) (xy 68.981378 -334.426721) (xy 69.045637 -334.457666) (xy 69.106028 -334.495612)
			(xy 69.16179 -334.540081) (xy 69.212223 -334.590514) (xy 69.256692 -334.646276) (xy 69.294638 -334.706667)
			(xy 69.325583 -334.770926) (xy 69.34914 -334.838246) (xy 69.36501 -334.907781) (xy 69.372996 -334.978655)
			(xy 69.373496 -335.014316) (xy 69.372996 -335.049977) (xy 69.36501 -335.120851) (xy 69.34914 -335.190386)
			(xy 69.325583 -335.257706) (xy 69.294638 -335.321965) (xy 69.256692 -335.382356) (xy 69.212223 -335.438118)
			(xy 69.16179 -335.488551) (xy 69.106028 -335.53302) (xy 69.045637 -335.570966) (xy 68.981378 -335.601911)
			(xy 68.914058 -335.625468) (xy 68.844523 -335.641338) (xy 68.773649 -335.649324) (xy 68.702327 -335.649324)
			(xy 68.631453 -335.641338) (xy 68.561918 -335.625468) (xy 68.494598 -335.601911) (xy 68.430339 -335.570966)
			(xy 68.369948 -335.53302) (xy 68.314186 -335.488551) (xy 68.263753 -335.438118) (xy 68.219284 -335.382356)
			(xy 68.181338 -335.321965) (xy 68.150393 -335.257706) (xy 68.126836 -335.190386) (xy 68.110966 -335.120851)
			(xy 68.10298 -335.049977) (xy 66.568582 -335.049977) (xy 66.560596 -335.120851) (xy 66.544726 -335.190386)
			(xy 66.521169 -335.257706) (xy 66.490224 -335.321965) (xy 66.452278 -335.382356) (xy 66.407809 -335.438118)
			(xy 66.357376 -335.488551) (xy 66.301614 -335.53302) (xy 66.241223 -335.570966) (xy 66.176964 -335.601911)
			(xy 66.109644 -335.625468) (xy 66.040109 -335.641338) (xy 65.969235 -335.649324) (xy 65.897913 -335.649324)
			(xy 65.827039 -335.641338) (xy 65.757504 -335.625468) (xy 65.690184 -335.601911) (xy 65.625925 -335.570966)
			(xy 65.565534 -335.53302) (xy 65.509772 -335.488551) (xy 65.459339 -335.438118) (xy 65.41487 -335.382356)
			(xy 65.376924 -335.321965) (xy 65.345979 -335.257706) (xy 65.322422 -335.190386) (xy 65.306552 -335.120851)
			(xy 65.298566 -335.049977) (xy 61.978498 -335.049977) (xy 61.94634 -335.065463) (xy 61.87902 -335.08902)
			(xy 61.809485 -335.10489) (xy 61.738611 -335.112876) (xy 61.667289 -335.112876) (xy 61.596415 -335.10489)
			(xy 61.52688 -335.08902) (xy 61.45956 -335.065463) (xy 61.395301 -335.034518) (xy 61.33491 -334.996572)
			(xy 61.279148 -334.952103) (xy 61.228715 -334.90167) (xy 61.184246 -334.845908) (xy 61.1463 -334.785517)
			(xy 61.115355 -334.721258) (xy 61.091798 -334.653938) (xy 61.075928 -334.584403) (xy 61.067942 -334.513529)
			(xy 60.433974 -334.513529) (xy 60.425988 -334.584403) (xy 60.410118 -334.653938) (xy 60.386561 -334.721258)
			(xy 60.355616 -334.785517) (xy 60.31767 -334.845908) (xy 60.273201 -334.90167) (xy 60.222768 -334.952103)
			(xy 60.167006 -334.996572) (xy 60.106615 -335.034518) (xy 60.042356 -335.065463) (xy 59.975036 -335.08902)
			(xy 59.905501 -335.10489) (xy 59.834627 -335.112876) (xy 59.763305 -335.112876) (xy 59.692431 -335.10489)
			(xy 59.622896 -335.08902) (xy 59.555576 -335.065463) (xy 59.491317 -335.034518) (xy 59.430926 -334.996572)
			(xy 59.375164 -334.952103) (xy 59.324731 -334.90167) (xy 59.280262 -334.845908) (xy 59.242316 -334.785517)
			(xy 59.211371 -334.721258) (xy 59.187814 -334.653938) (xy 59.171944 -334.584403) (xy 59.163958 -334.513529)
			(xy 58.192932 -334.513529) (xy 58.184946 -334.584403) (xy 58.169076 -334.653938) (xy 58.145519 -334.721258)
			(xy 58.114574 -334.785517) (xy 58.076628 -334.845908) (xy 58.032159 -334.90167) (xy 57.981726 -334.952103)
			(xy 57.925964 -334.996572) (xy 57.865573 -335.034518) (xy 57.801314 -335.065463) (xy 57.733994 -335.08902)
			(xy 57.664459 -335.10489) (xy 57.593585 -335.112876) (xy 57.522263 -335.112876) (xy 57.451389 -335.10489)
			(xy 57.381854 -335.08902) (xy 57.314534 -335.065463) (xy 57.250275 -335.034518) (xy 57.189884 -334.996572)
			(xy 57.134122 -334.952103) (xy 57.083689 -334.90167) (xy 57.03922 -334.845908) (xy 57.001274 -334.785517)
			(xy 56.970329 -334.721258) (xy 56.946772 -334.653938) (xy 56.930902 -334.584403) (xy 56.922916 -334.513529)
			(xy 56.30622 -334.513529) (xy 56.298234 -334.584403) (xy 56.282364 -334.653938) (xy 56.258807 -334.721258)
			(xy 56.227862 -334.785517) (xy 56.189916 -334.845908) (xy 56.145447 -334.90167) (xy 56.095014 -334.952103)
			(xy 56.039252 -334.996572) (xy 55.978861 -335.034518) (xy 55.914602 -335.065463) (xy 55.847282 -335.08902)
			(xy 55.777747 -335.10489) (xy 55.706873 -335.112876) (xy 55.635551 -335.112876) (xy 55.564677 -335.10489)
			(xy 55.495142 -335.08902) (xy 55.427822 -335.065463) (xy 55.363563 -335.034518) (xy 55.303172 -334.996572)
			(xy 55.24741 -334.952103) (xy 55.196977 -334.90167) (xy 55.152508 -334.845908) (xy 55.114562 -334.785517)
			(xy 55.083617 -334.721258) (xy 55.06006 -334.653938) (xy 55.04419 -334.584403) (xy 55.036204 -334.513529)
			(xy 40.108216 -334.513529) (xy 40.116896 -334.527343) (xy 40.147841 -334.591602) (xy 40.171398 -334.658922)
			(xy 40.187268 -334.728457) (xy 40.195254 -334.799331) (xy 40.195754 -334.834992) (xy 40.195254 -334.870653)
			(xy 40.187268 -334.941527) (xy 40.171398 -335.011062) (xy 40.147841 -335.078382) (xy 40.116896 -335.142641)
			(xy 40.07895 -335.203032) (xy 40.034481 -335.258794) (xy 39.984048 -335.309227) (xy 39.928286 -335.353696)
			(xy 39.867895 -335.391642) (xy 39.803636 -335.422587) (xy 39.736316 -335.446144) (xy 39.666781 -335.462014)
			(xy 39.595907 -335.47) (xy 39.524585 -335.47) (xy 39.453711 -335.462014) (xy 39.384176 -335.446144)
			(xy 39.316856 -335.422587) (xy 39.252597 -335.391642) (xy 39.192206 -335.353696) (xy 39.136444 -335.309227)
			(xy 39.086011 -335.258794) (xy 39.041542 -335.203032) (xy 39.003596 -335.142641) (xy 38.972651 -335.078382)
			(xy 38.949094 -335.011062) (xy 38.933224 -334.941527) (xy 38.925238 -334.870653) (xy 29.774075 -334.870653)
			(xy 29.781402 -334.882898) (xy 29.811492 -334.917274) (xy 29.847245 -334.945713) (xy 29.887507 -334.9673)
			(xy 29.930982 -334.981337) (xy 29.976265 -334.987373) (xy 30.021899 -334.985213) (xy 30.06641 -334.974926)
			(xy 30.08757 -334.96631) (xy 30.127491 -334.949645) (xy 30.20975 -334.922851) (xy 30.294124 -334.903727)
			(xy 30.379897 -334.892433) (xy 30.466345 -334.889066) (xy 30.552736 -334.893654) (xy 30.638341 -334.906158)
			(xy 30.722436 -334.926472) (xy 30.804309 -334.954424) (xy 30.883269 -334.98978) (xy 30.958647 -335.032238)
			(xy 31.029806 -335.08144) (xy 31.096145 -335.136971) (xy 31.157103 -335.198361) (xy 31.212165 -335.265091)
			(xy 31.260864 -335.336596) (xy 31.302789 -335.412272) (xy 31.337586 -335.491479) (xy 31.36496 -335.573547)
			(xy 31.38468 -335.657783) (xy 31.39658 -335.743474) (xy 31.400557 -335.829896) (xy 31.398557 -335.87336)
			(xy 34.599874 -335.87336) (xy 34.599874 -335.78646) (xy 34.607892 -335.699931) (xy 34.62386 -335.614511)
			(xy 34.647641 -335.530929) (xy 34.679033 -335.449897) (xy 34.717767 -335.372108) (xy 34.763514 -335.298224)
			(xy 34.815883 -335.228877) (xy 34.874427 -335.164657) (xy 34.938647 -335.106113) (xy 35.007994 -335.053744)
			(xy 35.081878 -335.007997) (xy 35.159667 -334.969263) (xy 35.240699 -334.937871) (xy 35.324281 -334.91409)
			(xy 35.409701 -334.898122) (xy 35.49623 -334.890104) (xy 35.58313 -334.890104) (xy 35.669659 -334.898122)
			(xy 35.755079 -334.91409) (xy 35.838661 -334.937871) (xy 35.919693 -334.969263) (xy 35.997482 -335.007997)
			(xy 36.071366 -335.053744) (xy 36.140713 -335.106113) (xy 36.204933 -335.164657) (xy 36.263477 -335.228877)
			(xy 36.315846 -335.298224) (xy 36.361593 -335.372108) (xy 36.400327 -335.449897) (xy 36.431719 -335.530929)
			(xy 36.4555 -335.614511) (xy 36.471468 -335.699931) (xy 36.479486 -335.78646) (xy 36.479988 -335.82991)
			(xy 36.479486 -335.87336) (xy 36.471468 -335.959889) (xy 36.4555 -336.045309) (xy 36.431719 -336.128891)
			(xy 36.400327 -336.209923) (xy 36.361593 -336.287712) (xy 36.315846 -336.361596) (xy 36.283785 -336.404051)
			(xy 55.036204 -336.404051) (xy 55.036204 -336.332729) (xy 55.04419 -336.261855) (xy 55.06006 -336.19232)
			(xy 55.083617 -336.125) (xy 55.114562 -336.060741) (xy 55.152508 -336.00035) (xy 55.196977 -335.944588)
			(xy 55.24741 -335.894155) (xy 55.303172 -335.849686) (xy 55.363563 -335.81174) (xy 55.427822 -335.780795)
			(xy 55.495142 -335.757238) (xy 55.564677 -335.741368) (xy 55.635551 -335.733382) (xy 55.706873 -335.733382)
			(xy 55.777747 -335.741368) (xy 55.847282 -335.757238) (xy 55.914602 -335.780795) (xy 55.978861 -335.81174)
			(xy 56.039252 -335.849686) (xy 56.095014 -335.894155) (xy 56.145447 -335.944588) (xy 56.189916 -336.00035)
			(xy 56.227862 -336.060741) (xy 56.258807 -336.125) (xy 56.282364 -336.19232) (xy 56.298234 -336.261855)
			(xy 56.30622 -336.332729) (xy 56.30672 -336.36839) (xy 56.30622 -336.404051) (xy 56.922916 -336.404051)
			(xy 56.922916 -336.332729) (xy 56.930902 -336.261855) (xy 56.946772 -336.19232) (xy 56.970329 -336.125)
			(xy 57.001274 -336.060741) (xy 57.03922 -336.00035) (xy 57.083689 -335.944588) (xy 57.134122 -335.894155)
			(xy 57.189884 -335.849686) (xy 57.250275 -335.81174) (xy 57.314534 -335.780795) (xy 57.381854 -335.757238)
			(xy 57.451389 -335.741368) (xy 57.522263 -335.733382) (xy 57.593585 -335.733382) (xy 57.664459 -335.741368)
			(xy 57.733994 -335.757238) (xy 57.801314 -335.780795) (xy 57.865573 -335.81174) (xy 57.925964 -335.849686)
			(xy 57.981726 -335.894155) (xy 58.032159 -335.944588) (xy 58.076628 -336.00035) (xy 58.114574 -336.060741)
			(xy 58.145519 -336.125) (xy 58.169076 -336.19232) (xy 58.184946 -336.261855) (xy 58.192932 -336.332729)
			(xy 58.193432 -336.36839) (xy 58.192932 -336.404051) (xy 59.163958 -336.404051) (xy 59.163958 -336.332729)
			(xy 59.171944 -336.261855) (xy 59.187814 -336.19232) (xy 59.211371 -336.125) (xy 59.242316 -336.060741)
			(xy 59.280262 -336.00035) (xy 59.324731 -335.944588) (xy 59.375164 -335.894155) (xy 59.430926 -335.849686)
			(xy 59.491317 -335.81174) (xy 59.555576 -335.780795) (xy 59.622896 -335.757238) (xy 59.692431 -335.741368)
			(xy 59.763305 -335.733382) (xy 59.834627 -335.733382) (xy 59.905501 -335.741368) (xy 59.975036 -335.757238)
			(xy 60.042356 -335.780795) (xy 60.106615 -335.81174) (xy 60.167006 -335.849686) (xy 60.222768 -335.894155)
			(xy 60.273201 -335.944588) (xy 60.31767 -336.00035) (xy 60.355616 -336.060741) (xy 60.386561 -336.125)
			(xy 60.410118 -336.19232) (xy 60.425988 -336.261855) (xy 60.433974 -336.332729) (xy 60.434474 -336.36839)
			(xy 60.433974 -336.404051) (xy 61.067942 -336.404051) (xy 61.067942 -336.332729) (xy 61.075928 -336.261855)
			(xy 61.091798 -336.19232) (xy 61.115355 -336.125) (xy 61.1463 -336.060741) (xy 61.184246 -336.00035)
			(xy 61.228715 -335.944588) (xy 61.279148 -335.894155) (xy 61.33491 -335.849686) (xy 61.395301 -335.81174)
			(xy 61.45956 -335.780795) (xy 61.52688 -335.757238) (xy 61.596415 -335.741368) (xy 61.667289 -335.733382)
			(xy 61.738611 -335.733382) (xy 61.809485 -335.741368) (xy 61.87902 -335.757238) (xy 61.94634 -335.780795)
			(xy 62.010599 -335.81174) (xy 62.07099 -335.849686) (xy 62.126752 -335.894155) (xy 62.177185 -335.944588)
			(xy 62.221654 -336.00035) (xy 62.2596 -336.060741) (xy 62.290545 -336.125) (xy 62.314102 -336.19232)
			(xy 62.329972 -336.261855) (xy 62.337958 -336.332729) (xy 62.338458 -336.36839) (xy 62.337958 -336.404051)
			(xy 62.329972 -336.474925) (xy 62.314102 -336.54446) (xy 62.290545 -336.61178) (xy 62.2596 -336.676039)
			(xy 62.221654 -336.73643) (xy 62.177185 -336.792192) (xy 62.126752 -336.842625) (xy 62.07099 -336.887094)
			(xy 62.010599 -336.92504) (xy 61.94634 -336.955985) (xy 61.87902 -336.979542) (xy 61.809485 -336.995412)
			(xy 61.738611 -337.003398) (xy 61.667289 -337.003398) (xy 61.596415 -336.995412) (xy 61.52688 -336.979542)
			(xy 61.45956 -336.955985) (xy 61.395301 -336.92504) (xy 61.33491 -336.887094) (xy 61.279148 -336.842625)
			(xy 61.228715 -336.792192) (xy 61.184246 -336.73643) (xy 61.1463 -336.676039) (xy 61.115355 -336.61178)
			(xy 61.091798 -336.54446) (xy 61.075928 -336.474925) (xy 61.067942 -336.404051) (xy 60.433974 -336.404051)
			(xy 60.425988 -336.474925) (xy 60.410118 -336.54446) (xy 60.386561 -336.61178) (xy 60.355616 -336.676039)
			(xy 60.31767 -336.73643) (xy 60.273201 -336.792192) (xy 60.222768 -336.842625) (xy 60.167006 -336.887094)
			(xy 60.106615 -336.92504) (xy 60.042356 -336.955985) (xy 59.975036 -336.979542) (xy 59.905501 -336.995412)
			(xy 59.834627 -337.003398) (xy 59.763305 -337.003398) (xy 59.692431 -336.995412) (xy 59.622896 -336.979542)
			(xy 59.555576 -336.955985) (xy 59.491317 -336.92504) (xy 59.430926 -336.887094) (xy 59.375164 -336.842625)
			(xy 59.324731 -336.792192) (xy 59.280262 -336.73643) (xy 59.242316 -336.676039) (xy 59.211371 -336.61178)
			(xy 59.187814 -336.54446) (xy 59.171944 -336.474925) (xy 59.163958 -336.404051) (xy 58.192932 -336.404051)
			(xy 58.184946 -336.474925) (xy 58.169076 -336.54446) (xy 58.145519 -336.61178) (xy 58.114574 -336.676039)
			(xy 58.076628 -336.73643) (xy 58.032159 -336.792192) (xy 57.981726 -336.842625) (xy 57.925964 -336.887094)
			(xy 57.865573 -336.92504) (xy 57.801314 -336.955985) (xy 57.733994 -336.979542) (xy 57.664459 -336.995412)
			(xy 57.593585 -337.003398) (xy 57.522263 -337.003398) (xy 57.451389 -336.995412) (xy 57.381854 -336.979542)
			(xy 57.314534 -336.955985) (xy 57.250275 -336.92504) (xy 57.189884 -336.887094) (xy 57.134122 -336.842625)
			(xy 57.083689 -336.792192) (xy 57.03922 -336.73643) (xy 57.001274 -336.676039) (xy 56.970329 -336.61178)
			(xy 56.946772 -336.54446) (xy 56.930902 -336.474925) (xy 56.922916 -336.404051) (xy 56.30622 -336.404051)
			(xy 56.298234 -336.474925) (xy 56.282364 -336.54446) (xy 56.258807 -336.61178) (xy 56.227862 -336.676039)
			(xy 56.189916 -336.73643) (xy 56.145447 -336.792192) (xy 56.095014 -336.842625) (xy 56.039252 -336.887094)
			(xy 55.978861 -336.92504) (xy 55.914602 -336.955985) (xy 55.847282 -336.979542) (xy 55.777747 -336.995412)
			(xy 55.706873 -337.003398) (xy 55.635551 -337.003398) (xy 55.564677 -336.995412) (xy 55.495142 -336.979542)
			(xy 55.427822 -336.955985) (xy 55.363563 -336.92504) (xy 55.303172 -336.887094) (xy 55.24741 -336.842625)
			(xy 55.196977 -336.792192) (xy 55.152508 -336.73643) (xy 55.114562 -336.676039) (xy 55.083617 -336.61178)
			(xy 55.06006 -336.54446) (xy 55.04419 -336.474925) (xy 55.036204 -336.404051) (xy 36.283785 -336.404051)
			(xy 36.263477 -336.430943) (xy 36.204933 -336.495163) (xy 36.140713 -336.553707) (xy 36.071366 -336.606076)
			(xy 35.997482 -336.651823) (xy 35.919693 -336.690557) (xy 35.838661 -336.721949) (xy 35.755079 -336.74573)
			(xy 35.669659 -336.761698) (xy 35.58313 -336.769716) (xy 35.49623 -336.769716) (xy 35.409701 -336.761698)
			(xy 35.324281 -336.74573) (xy 35.240699 -336.721949) (xy 35.159667 -336.690557) (xy 35.081878 -336.651823)
			(xy 35.007994 -336.606076) (xy 34.938647 -336.553707) (xy 34.874427 -336.495163) (xy 34.815883 -336.430943)
			(xy 34.763514 -336.361596) (xy 34.717767 -336.287712) (xy 34.679033 -336.209923) (xy 34.647641 -336.128891)
			(xy 34.62386 -336.045309) (xy 34.607892 -335.959889) (xy 34.599874 -335.87336) (xy 31.398557 -335.87336)
			(xy 31.39658 -335.916318) (xy 31.384682 -336.002009) (xy 31.364962 -336.086245) (xy 31.337589 -336.168314)
			(xy 31.302793 -336.247521) (xy 31.260868 -336.323198) (xy 31.212169 -336.394703) (xy 31.157109 -336.461433)
			(xy 31.096151 -336.522823) (xy 31.029813 -336.578355) (xy 30.958653 -336.627558) (xy 30.883276 -336.670017)
			(xy 30.804316 -336.705373) (xy 30.722444 -336.733326) (xy 30.638349 -336.753641) (xy 30.552744 -336.766145)
			(xy 30.466352 -336.770734) (xy 30.379905 -336.767368) (xy 30.294131 -336.756075) (xy 30.209758 -336.736951)
			(xy 30.127498 -336.710158) (xy 30.08757 -336.69351) (xy 30.066403 -336.684941) (xy 30.021906 -336.674702)
			(xy 29.976295 -336.672576) (xy 29.931038 -336.678634) (xy 29.887591 -336.692679) (xy 29.847352 -336.714259)
			(xy 29.811616 -336.742681) (xy 29.781532 -336.77703) (xy 29.758068 -336.816201) (xy 29.74198 -336.858933)
			(xy 29.733784 -336.903852) (xy 29.73324 -336.926682) (xy 29.73324 -337.273138) (xy 29.733718 -337.29598)
			(xy 29.741878 -337.34093) (xy 29.757945 -337.383696) (xy 29.781402 -337.422898) (xy 29.811492 -337.457274)
			(xy 29.847245 -337.485713) (xy 29.887507 -337.5073) (xy 29.930982 -337.521337) (xy 29.976265 -337.527373)
			(xy 30.021899 -337.525213) (xy 30.06641 -337.514926) (xy 30.08757 -337.50631) (xy 30.127491 -337.489645)
			(xy 30.20975 -337.462851) (xy 30.294124 -337.443727) (xy 30.379897 -337.432433) (xy 30.466345 -337.429066)
			(xy 30.552736 -337.433654) (xy 30.638341 -337.446158) (xy 30.722436 -337.466472) (xy 30.804309 -337.494424)
			(xy 30.883269 -337.52978) (xy 30.958647 -337.572238) (xy 31.029806 -337.62144) (xy 31.096145 -337.676971)
			(xy 31.157103 -337.738361) (xy 31.212165 -337.805091) (xy 31.260864 -337.876596) (xy 31.302789 -337.952272)
			(xy 31.337586 -338.031479) (xy 31.36496 -338.113547) (xy 31.38468 -338.197783) (xy 31.39658 -338.283474)
			(xy 31.400557 -338.369896) (xy 31.398557 -338.41336) (xy 34.599874 -338.41336) (xy 34.599874 -338.32646)
			(xy 34.607892 -338.239931) (xy 34.62386 -338.154511) (xy 34.647641 -338.070929) (xy 34.679033 -337.989897)
			(xy 34.717767 -337.912108) (xy 34.763514 -337.838224) (xy 34.815883 -337.768877) (xy 34.874427 -337.704657)
			(xy 34.938647 -337.646113) (xy 35.007994 -337.593744) (xy 35.081878 -337.547997) (xy 35.159667 -337.509263)
			(xy 35.240699 -337.477871) (xy 35.324281 -337.45409) (xy 35.409701 -337.438122) (xy 35.49623 -337.430104)
			(xy 35.58313 -337.430104) (xy 35.669659 -337.438122) (xy 35.755079 -337.45409) (xy 35.838661 -337.477871)
			(xy 35.919693 -337.509263) (xy 35.979259 -337.538923) (xy 38.925238 -337.538923) (xy 38.925238 -337.467601)
			(xy 38.933224 -337.396727) (xy 38.949094 -337.327192) (xy 38.972651 -337.259872) (xy 39.003596 -337.195613)
			(xy 39.041542 -337.135222) (xy 39.086011 -337.07946) (xy 39.136444 -337.029027) (xy 39.192206 -336.984558)
			(xy 39.252597 -336.946612) (xy 39.316856 -336.915667) (xy 39.384176 -336.89211) (xy 39.453711 -336.87624)
			(xy 39.524585 -336.868254) (xy 39.595907 -336.868254) (xy 39.666781 -336.87624) (xy 39.736316 -336.89211)
			(xy 39.803636 -336.915667) (xy 39.867895 -336.946612) (xy 39.928286 -336.984558) (xy 39.984048 -337.029027)
			(xy 40.034481 -337.07946) (xy 40.07895 -337.135222) (xy 40.116896 -337.195613) (xy 40.147841 -337.259872)
			(xy 40.171398 -337.327192) (xy 40.187268 -337.396727) (xy 40.195254 -337.467601) (xy 40.195754 -337.503262)
			(xy 40.195254 -337.538923) (xy 40.187268 -337.609797) (xy 40.171398 -337.679332) (xy 40.147841 -337.746652)
			(xy 40.116896 -337.810911) (xy 40.07895 -337.871302) (xy 40.034481 -337.927064) (xy 39.984048 -337.977497)
			(xy 39.928286 -338.021966) (xy 39.867895 -338.059912) (xy 39.803636 -338.090857) (xy 39.736316 -338.114414)
			(xy 39.666781 -338.130284) (xy 39.595907 -338.13827) (xy 39.524585 -338.13827) (xy 39.453711 -338.130284)
			(xy 39.384176 -338.114414) (xy 39.316856 -338.090857) (xy 39.252597 -338.059912) (xy 39.192206 -338.021966)
			(xy 39.136444 -337.977497) (xy 39.086011 -337.927064) (xy 39.041542 -337.871302) (xy 39.003596 -337.810911)
			(xy 38.972651 -337.746652) (xy 38.949094 -337.679332) (xy 38.933224 -337.609797) (xy 38.925238 -337.538923)
			(xy 35.979259 -337.538923) (xy 35.997482 -337.547997) (xy 36.071366 -337.593744) (xy 36.140713 -337.646113)
			(xy 36.204933 -337.704657) (xy 36.263477 -337.768877) (xy 36.315846 -337.838224) (xy 36.361593 -337.912108)
			(xy 36.400327 -337.989897) (xy 36.431719 -338.070929) (xy 36.4555 -338.154511) (xy 36.471468 -338.239931)
			(xy 36.479486 -338.32646) (xy 36.479988 -338.36991) (xy 36.479486 -338.41336) (xy 36.476536 -338.445195)
			(xy 55.036204 -338.445195) (xy 55.036204 -338.373873) (xy 55.04419 -338.302999) (xy 55.06006 -338.233464)
			(xy 55.083617 -338.166144) (xy 55.114562 -338.101885) (xy 55.152508 -338.041494) (xy 55.196977 -337.985732)
			(xy 55.24741 -337.935299) (xy 55.303172 -337.89083) (xy 55.363563 -337.852884) (xy 55.427822 -337.821939)
			(xy 55.495142 -337.798382) (xy 55.564677 -337.782512) (xy 55.635551 -337.774526) (xy 55.706873 -337.774526)
			(xy 55.777747 -337.782512) (xy 55.847282 -337.798382) (xy 55.914602 -337.821939) (xy 55.978861 -337.852884)
			(xy 56.039252 -337.89083) (xy 56.095014 -337.935299) (xy 56.145447 -337.985732) (xy 56.189916 -338.041494)
			(xy 56.227862 -338.101885) (xy 56.258807 -338.166144) (xy 56.282364 -338.233464) (xy 56.298234 -338.302999)
			(xy 56.30622 -338.373873) (xy 56.30672 -338.409534) (xy 56.30622 -338.445195) (xy 56.922916 -338.445195)
			(xy 56.922916 -338.373873) (xy 56.930902 -338.302999) (xy 56.946772 -338.233464) (xy 56.970329 -338.166144)
			(xy 57.001274 -338.101885) (xy 57.03922 -338.041494) (xy 57.083689 -337.985732) (xy 57.134122 -337.935299)
			(xy 57.189884 -337.89083) (xy 57.250275 -337.852884) (xy 57.314534 -337.821939) (xy 57.381854 -337.798382)
			(xy 57.451389 -337.782512) (xy 57.522263 -337.774526) (xy 57.593585 -337.774526) (xy 57.664459 -337.782512)
			(xy 57.733994 -337.798382) (xy 57.801314 -337.821939) (xy 57.865573 -337.852884) (xy 57.925964 -337.89083)
			(xy 57.981726 -337.935299) (xy 58.032159 -337.985732) (xy 58.076628 -338.041494) (xy 58.114574 -338.101885)
			(xy 58.145519 -338.166144) (xy 58.169076 -338.233464) (xy 58.184946 -338.302999) (xy 58.192932 -338.373873)
			(xy 58.193432 -338.409534) (xy 58.192932 -338.445195) (xy 59.163958 -338.445195) (xy 59.163958 -338.373873)
			(xy 59.171944 -338.302999) (xy 59.187814 -338.233464) (xy 59.211371 -338.166144) (xy 59.242316 -338.101885)
			(xy 59.280262 -338.041494) (xy 59.324731 -337.985732) (xy 59.375164 -337.935299) (xy 59.430926 -337.89083)
			(xy 59.491317 -337.852884) (xy 59.555576 -337.821939) (xy 59.622896 -337.798382) (xy 59.692431 -337.782512)
			(xy 59.763305 -337.774526) (xy 59.834627 -337.774526) (xy 59.905501 -337.782512) (xy 59.975036 -337.798382)
			(xy 60.042356 -337.821939) (xy 60.106615 -337.852884) (xy 60.167006 -337.89083) (xy 60.222768 -337.935299)
			(xy 60.273201 -337.985732) (xy 60.31767 -338.041494) (xy 60.355616 -338.101885) (xy 60.386561 -338.166144)
			(xy 60.410118 -338.233464) (xy 60.425988 -338.302999) (xy 60.433974 -338.373873) (xy 60.434474 -338.409534)
			(xy 60.433974 -338.445195) (xy 61.067942 -338.445195) (xy 61.067942 -338.373873) (xy 61.075928 -338.302999)
			(xy 61.091798 -338.233464) (xy 61.115355 -338.166144) (xy 61.1463 -338.101885) (xy 61.184246 -338.041494)
			(xy 61.228715 -337.985732) (xy 61.279148 -337.935299) (xy 61.33491 -337.89083) (xy 61.395301 -337.852884)
			(xy 61.45956 -337.821939) (xy 61.52688 -337.798382) (xy 61.596415 -337.782512) (xy 61.667289 -337.774526)
			(xy 61.738611 -337.774526) (xy 61.809485 -337.782512) (xy 61.87902 -337.798382) (xy 61.94634 -337.821939)
			(xy 62.010599 -337.852884) (xy 62.07099 -337.89083) (xy 62.126752 -337.935299) (xy 62.177185 -337.985732)
			(xy 62.221654 -338.041494) (xy 62.2596 -338.101885) (xy 62.290545 -338.166144) (xy 62.314102 -338.233464)
			(xy 62.329972 -338.302999) (xy 62.337958 -338.373873) (xy 62.338458 -338.409534) (xy 62.337958 -338.445195)
			(xy 62.329972 -338.516069) (xy 62.314102 -338.585604) (xy 62.290545 -338.652924) (xy 62.2596 -338.717183)
			(xy 62.221654 -338.777574) (xy 62.177185 -338.833336) (xy 62.126752 -338.883769) (xy 62.07099 -338.928238)
			(xy 62.010599 -338.966184) (xy 61.94634 -338.997129) (xy 61.87902 -339.020686) (xy 61.809485 -339.036556)
			(xy 61.738611 -339.044542) (xy 61.667289 -339.044542) (xy 61.596415 -339.036556) (xy 61.52688 -339.020686)
			(xy 61.45956 -338.997129) (xy 61.395301 -338.966184) (xy 61.33491 -338.928238) (xy 61.279148 -338.883769)
			(xy 61.228715 -338.833336) (xy 61.184246 -338.777574) (xy 61.1463 -338.717183) (xy 61.115355 -338.652924)
			(xy 61.091798 -338.585604) (xy 61.075928 -338.516069) (xy 61.067942 -338.445195) (xy 60.433974 -338.445195)
			(xy 60.425988 -338.516069) (xy 60.410118 -338.585604) (xy 60.386561 -338.652924) (xy 60.355616 -338.717183)
			(xy 60.31767 -338.777574) (xy 60.273201 -338.833336) (xy 60.222768 -338.883769) (xy 60.167006 -338.928238)
			(xy 60.106615 -338.966184) (xy 60.042356 -338.997129) (xy 59.975036 -339.020686) (xy 59.905501 -339.036556)
			(xy 59.834627 -339.044542) (xy 59.763305 -339.044542) (xy 59.692431 -339.036556) (xy 59.622896 -339.020686)
			(xy 59.555576 -338.997129) (xy 59.491317 -338.966184) (xy 59.430926 -338.928238) (xy 59.375164 -338.883769)
			(xy 59.324731 -338.833336) (xy 59.280262 -338.777574) (xy 59.242316 -338.717183) (xy 59.211371 -338.652924)
			(xy 59.187814 -338.585604) (xy 59.171944 -338.516069) (xy 59.163958 -338.445195) (xy 58.192932 -338.445195)
			(xy 58.184946 -338.516069) (xy 58.169076 -338.585604) (xy 58.145519 -338.652924) (xy 58.114574 -338.717183)
			(xy 58.076628 -338.777574) (xy 58.032159 -338.833336) (xy 57.981726 -338.883769) (xy 57.925964 -338.928238)
			(xy 57.865573 -338.966184) (xy 57.801314 -338.997129) (xy 57.733994 -339.020686) (xy 57.664459 -339.036556)
			(xy 57.593585 -339.044542) (xy 57.522263 -339.044542) (xy 57.451389 -339.036556) (xy 57.381854 -339.020686)
			(xy 57.314534 -338.997129) (xy 57.250275 -338.966184) (xy 57.189884 -338.928238) (xy 57.134122 -338.883769)
			(xy 57.083689 -338.833336) (xy 57.03922 -338.777574) (xy 57.001274 -338.717183) (xy 56.970329 -338.652924)
			(xy 56.946772 -338.585604) (xy 56.930902 -338.516069) (xy 56.922916 -338.445195) (xy 56.30622 -338.445195)
			(xy 56.298234 -338.516069) (xy 56.282364 -338.585604) (xy 56.258807 -338.652924) (xy 56.227862 -338.717183)
			(xy 56.189916 -338.777574) (xy 56.145447 -338.833336) (xy 56.095014 -338.883769) (xy 56.039252 -338.928238)
			(xy 55.978861 -338.966184) (xy 55.914602 -338.997129) (xy 55.847282 -339.020686) (xy 55.777747 -339.036556)
			(xy 55.706873 -339.044542) (xy 55.635551 -339.044542) (xy 55.564677 -339.036556) (xy 55.495142 -339.020686)
			(xy 55.427822 -338.997129) (xy 55.363563 -338.966184) (xy 55.303172 -338.928238) (xy 55.24741 -338.883769)
			(xy 55.196977 -338.833336) (xy 55.152508 -338.777574) (xy 55.114562 -338.717183) (xy 55.083617 -338.652924)
			(xy 55.06006 -338.585604) (xy 55.04419 -338.516069) (xy 55.036204 -338.445195) (xy 36.476536 -338.445195)
			(xy 36.471468 -338.499889) (xy 36.4555 -338.585309) (xy 36.431719 -338.668891) (xy 36.400327 -338.749923)
			(xy 36.361593 -338.827712) (xy 36.315846 -338.901596) (xy 36.263477 -338.970943) (xy 36.204933 -339.035163)
			(xy 36.140713 -339.093707) (xy 36.071366 -339.146076) (xy 35.997482 -339.191823) (xy 35.919693 -339.230557)
			(xy 35.838661 -339.261949) (xy 35.755079 -339.28573) (xy 35.669659 -339.301698) (xy 35.58313 -339.309716)
			(xy 35.49623 -339.309716) (xy 35.409701 -339.301698) (xy 35.324281 -339.28573) (xy 35.240699 -339.261949)
			(xy 35.159667 -339.230557) (xy 35.081878 -339.191823) (xy 35.007994 -339.146076) (xy 34.938647 -339.093707)
			(xy 34.874427 -339.035163) (xy 34.815883 -338.970943) (xy 34.763514 -338.901596) (xy 34.717767 -338.827712)
			(xy 34.679033 -338.749923) (xy 34.647641 -338.668891) (xy 34.62386 -338.585309) (xy 34.607892 -338.499889)
			(xy 34.599874 -338.41336) (xy 31.398557 -338.41336) (xy 31.39658 -338.456318) (xy 31.384682 -338.542009)
			(xy 31.364962 -338.626245) (xy 31.337589 -338.708314) (xy 31.302793 -338.787521) (xy 31.260868 -338.863198)
			(xy 31.212169 -338.934703) (xy 31.157109 -339.001433) (xy 31.096151 -339.062823) (xy 31.029813 -339.118355)
			(xy 30.958653 -339.167558) (xy 30.883276 -339.210017) (xy 30.804316 -339.245373) (xy 30.722444 -339.273326)
			(xy 30.638349 -339.293641) (xy 30.552744 -339.306145) (xy 30.466352 -339.310734) (xy 30.379905 -339.307368)
			(xy 30.294131 -339.296075) (xy 30.209758 -339.276951) (xy 30.127498 -339.250158) (xy 30.08757 -339.23351)
			(xy 30.066403 -339.224941) (xy 30.021906 -339.214702) (xy 29.976295 -339.212576) (xy 29.931038 -339.218634)
			(xy 29.887591 -339.232679) (xy 29.847352 -339.254259) (xy 29.811616 -339.282681) (xy 29.781532 -339.31703)
			(xy 29.758068 -339.356201) (xy 29.74198 -339.398933) (xy 29.733784 -339.443852) (xy 29.73324 -339.466682)
			(xy 29.73324 -339.813138) (xy 29.733718 -339.83598) (xy 29.741878 -339.88093) (xy 29.752995 -339.910521)
			(xy 38.925238 -339.910521) (xy 38.925238 -339.839199) (xy 38.933224 -339.768325) (xy 38.949094 -339.69879)
			(xy 38.972651 -339.63147) (xy 39.003596 -339.567211) (xy 39.041542 -339.50682) (xy 39.086011 -339.451058)
			(xy 39.136444 -339.400625) (xy 39.192206 -339.356156) (xy 39.252597 -339.31821) (xy 39.316856 -339.287265)
			(xy 39.384176 -339.263708) (xy 39.453711 -339.247838) (xy 39.524585 -339.239852) (xy 39.595907 -339.239852)
			(xy 39.666781 -339.247838) (xy 39.736316 -339.263708) (xy 39.803636 -339.287265) (xy 39.867895 -339.31821)
			(xy 39.928286 -339.356156) (xy 39.984048 -339.400625) (xy 40.034481 -339.451058) (xy 40.07895 -339.50682)
			(xy 40.116896 -339.567211) (xy 40.147841 -339.63147) (xy 40.171398 -339.69879) (xy 40.187268 -339.768325)
			(xy 40.195254 -339.839199) (xy 40.195754 -339.87486) (xy 40.195254 -339.910521) (xy 40.187268 -339.981395)
			(xy 40.171398 -340.05093) (xy 40.147841 -340.11825) (xy 40.116896 -340.182509) (xy 40.07895 -340.2429)
			(xy 40.034481 -340.298662) (xy 39.984048 -340.349095) (xy 39.976617 -340.355021) (xy 55.036204 -340.355021)
			(xy 55.036204 -340.283699) (xy 55.04419 -340.212825) (xy 55.06006 -340.14329) (xy 55.083617 -340.07597)
			(xy 55.114562 -340.011711) (xy 55.152508 -339.95132) (xy 55.196977 -339.895558) (xy 55.24741 -339.845125)
			(xy 55.303172 -339.800656) (xy 55.363563 -339.76271) (xy 55.427822 -339.731765) (xy 55.495142 -339.708208)
			(xy 55.564677 -339.692338) (xy 55.635551 -339.684352) (xy 55.706873 -339.684352) (xy 55.777747 -339.692338)
			(xy 55.847282 -339.708208) (xy 55.914602 -339.731765) (xy 55.978861 -339.76271) (xy 56.039252 -339.800656)
			(xy 56.095014 -339.845125) (xy 56.145447 -339.895558) (xy 56.189916 -339.95132) (xy 56.227862 -340.011711)
			(xy 56.258807 -340.07597) (xy 56.282364 -340.14329) (xy 56.298234 -340.212825) (xy 56.30622 -340.283699)
			(xy 56.30672 -340.31936) (xy 56.30622 -340.355021) (xy 56.922916 -340.355021) (xy 56.922916 -340.283699)
			(xy 56.930902 -340.212825) (xy 56.946772 -340.14329) (xy 56.970329 -340.07597) (xy 57.001274 -340.011711)
			(xy 57.03922 -339.95132) (xy 57.083689 -339.895558) (xy 57.134122 -339.845125) (xy 57.189884 -339.800656)
			(xy 57.250275 -339.76271) (xy 57.314534 -339.731765) (xy 57.381854 -339.708208) (xy 57.451389 -339.692338)
			(xy 57.522263 -339.684352) (xy 57.593585 -339.684352) (xy 57.664459 -339.692338) (xy 57.733994 -339.708208)
			(xy 57.801314 -339.731765) (xy 57.865573 -339.76271) (xy 57.925964 -339.800656) (xy 57.981726 -339.845125)
			(xy 58.032159 -339.895558) (xy 58.076628 -339.95132) (xy 58.114574 -340.011711) (xy 58.145519 -340.07597)
			(xy 58.169076 -340.14329) (xy 58.184946 -340.212825) (xy 58.192932 -340.283699) (xy 58.193432 -340.31936)
			(xy 58.192932 -340.355021) (xy 59.163958 -340.355021) (xy 59.163958 -340.283699) (xy 59.171944 -340.212825)
			(xy 59.187814 -340.14329) (xy 59.211371 -340.07597) (xy 59.242316 -340.011711) (xy 59.280262 -339.95132)
			(xy 59.324731 -339.895558) (xy 59.375164 -339.845125) (xy 59.430926 -339.800656) (xy 59.491317 -339.76271)
			(xy 59.555576 -339.731765) (xy 59.622896 -339.708208) (xy 59.692431 -339.692338) (xy 59.763305 -339.684352)
			(xy 59.834627 -339.684352) (xy 59.905501 -339.692338) (xy 59.975036 -339.708208) (xy 60.042356 -339.731765)
			(xy 60.106615 -339.76271) (xy 60.167006 -339.800656) (xy 60.222768 -339.845125) (xy 60.273201 -339.895558)
			(xy 60.31767 -339.95132) (xy 60.355616 -340.011711) (xy 60.386561 -340.07597) (xy 60.410118 -340.14329)
			(xy 60.425988 -340.212825) (xy 60.433974 -340.283699) (xy 60.434474 -340.31936) (xy 60.433974 -340.355021)
			(xy 61.067942 -340.355021) (xy 61.067942 -340.283699) (xy 61.075928 -340.212825) (xy 61.091798 -340.14329)
			(xy 61.115355 -340.07597) (xy 61.1463 -340.011711) (xy 61.184246 -339.95132) (xy 61.228715 -339.895558)
			(xy 61.279148 -339.845125) (xy 61.33491 -339.800656) (xy 61.395301 -339.76271) (xy 61.45956 -339.731765)
			(xy 61.52688 -339.708208) (xy 61.596415 -339.692338) (xy 61.667289 -339.684352) (xy 61.738611 -339.684352)
			(xy 61.809485 -339.692338) (xy 61.87902 -339.708208) (xy 61.94634 -339.731765) (xy 62.010599 -339.76271)
			(xy 62.07099 -339.800656) (xy 62.126752 -339.845125) (xy 62.177185 -339.895558) (xy 62.221654 -339.95132)
			(xy 62.2596 -340.011711) (xy 62.290545 -340.07597) (xy 62.314102 -340.14329) (xy 62.329972 -340.212825)
			(xy 62.337958 -340.283699) (xy 62.338458 -340.31936) (xy 62.337958 -340.355021) (xy 62.329972 -340.425895)
			(xy 62.314102 -340.49543) (xy 62.290545 -340.56275) (xy 62.2596 -340.627009) (xy 62.221654 -340.6874)
			(xy 62.177185 -340.743162) (xy 62.126752 -340.793595) (xy 62.07099 -340.838064) (xy 62.010599 -340.87601)
			(xy 61.94634 -340.906955) (xy 61.87902 -340.930512) (xy 61.809485 -340.946382) (xy 61.738611 -340.954368)
			(xy 61.667289 -340.954368) (xy 61.596415 -340.946382) (xy 61.52688 -340.930512) (xy 61.45956 -340.906955)
			(xy 61.395301 -340.87601) (xy 61.33491 -340.838064) (xy 61.279148 -340.793595) (xy 61.228715 -340.743162)
			(xy 61.184246 -340.6874) (xy 61.1463 -340.627009) (xy 61.115355 -340.56275) (xy 61.091798 -340.49543)
			(xy 61.075928 -340.425895) (xy 61.067942 -340.355021) (xy 60.433974 -340.355021) (xy 60.425988 -340.425895)
			(xy 60.410118 -340.49543) (xy 60.386561 -340.56275) (xy 60.355616 -340.627009) (xy 60.31767 -340.6874)
			(xy 60.273201 -340.743162) (xy 60.222768 -340.793595) (xy 60.167006 -340.838064) (xy 60.106615 -340.87601)
			(xy 60.042356 -340.906955) (xy 59.975036 -340.930512) (xy 59.905501 -340.946382) (xy 59.834627 -340.954368)
			(xy 59.763305 -340.954368) (xy 59.692431 -340.946382) (xy 59.622896 -340.930512) (xy 59.555576 -340.906955)
			(xy 59.491317 -340.87601) (xy 59.430926 -340.838064) (xy 59.375164 -340.793595) (xy 59.324731 -340.743162)
			(xy 59.280262 -340.6874) (xy 59.242316 -340.627009) (xy 59.211371 -340.56275) (xy 59.187814 -340.49543)
			(xy 59.171944 -340.425895) (xy 59.163958 -340.355021) (xy 58.192932 -340.355021) (xy 58.184946 -340.425895)
			(xy 58.169076 -340.49543) (xy 58.145519 -340.56275) (xy 58.114574 -340.627009) (xy 58.076628 -340.6874)
			(xy 58.032159 -340.743162) (xy 57.981726 -340.793595) (xy 57.925964 -340.838064) (xy 57.865573 -340.87601)
			(xy 57.801314 -340.906955) (xy 57.733994 -340.930512) (xy 57.664459 -340.946382) (xy 57.593585 -340.954368)
			(xy 57.522263 -340.954368) (xy 57.451389 -340.946382) (xy 57.381854 -340.930512) (xy 57.314534 -340.906955)
			(xy 57.250275 -340.87601) (xy 57.189884 -340.838064) (xy 57.134122 -340.793595) (xy 57.083689 -340.743162)
			(xy 57.03922 -340.6874) (xy 57.001274 -340.627009) (xy 56.970329 -340.56275) (xy 56.946772 -340.49543)
			(xy 56.930902 -340.425895) (xy 56.922916 -340.355021) (xy 56.30622 -340.355021) (xy 56.298234 -340.425895)
			(xy 56.282364 -340.49543) (xy 56.258807 -340.56275) (xy 56.227862 -340.627009) (xy 56.189916 -340.6874)
			(xy 56.145447 -340.743162) (xy 56.095014 -340.793595) (xy 56.039252 -340.838064) (xy 55.978861 -340.87601)
			(xy 55.914602 -340.906955) (xy 55.847282 -340.930512) (xy 55.777747 -340.946382) (xy 55.706873 -340.954368)
			(xy 55.635551 -340.954368) (xy 55.564677 -340.946382) (xy 55.495142 -340.930512) (xy 55.427822 -340.906955)
			(xy 55.363563 -340.87601) (xy 55.303172 -340.838064) (xy 55.24741 -340.793595) (xy 55.196977 -340.743162)
			(xy 55.152508 -340.6874) (xy 55.114562 -340.627009) (xy 55.083617 -340.56275) (xy 55.06006 -340.49543)
			(xy 55.04419 -340.425895) (xy 55.036204 -340.355021) (xy 39.976617 -340.355021) (xy 39.928286 -340.393564)
			(xy 39.867895 -340.43151) (xy 39.803636 -340.462455) (xy 39.736316 -340.486012) (xy 39.666781 -340.501882)
			(xy 39.595907 -340.509868) (xy 39.524585 -340.509868) (xy 39.453711 -340.501882) (xy 39.384176 -340.486012)
			(xy 39.316856 -340.462455) (xy 39.252597 -340.43151) (xy 39.192206 -340.393564) (xy 39.136444 -340.349095)
			(xy 39.086011 -340.298662) (xy 39.041542 -340.2429) (xy 39.003596 -340.182509) (xy 38.972651 -340.11825)
			(xy 38.949094 -340.05093) (xy 38.933224 -339.981395) (xy 38.925238 -339.910521) (xy 29.752995 -339.910521)
			(xy 29.757945 -339.923696) (xy 29.781402 -339.962898) (xy 29.811492 -339.997274) (xy 29.847245 -340.025713)
			(xy 29.887507 -340.0473) (xy 29.930982 -340.061337) (xy 29.976265 -340.067373) (xy 30.021899 -340.065213)
			(xy 30.06641 -340.054926) (xy 30.08757 -340.04631) (xy 30.127491 -340.029645) (xy 30.20975 -340.002851)
			(xy 30.294124 -339.983727) (xy 30.379897 -339.972433) (xy 30.466345 -339.969066) (xy 30.552736 -339.973654)
			(xy 30.638341 -339.986158) (xy 30.722436 -340.006472) (xy 30.804309 -340.034424) (xy 30.883269 -340.06978)
			(xy 30.958647 -340.112238) (xy 31.029806 -340.16144) (xy 31.096145 -340.216971) (xy 31.157103 -340.278361)
			(xy 31.212165 -340.345091) (xy 31.260864 -340.416596) (xy 31.302789 -340.492272) (xy 31.337586 -340.571479)
			(xy 31.36496 -340.653547) (xy 31.38468 -340.737783) (xy 31.39658 -340.823474) (xy 31.400557 -340.909896)
			(xy 31.398557 -340.95336) (xy 34.599874 -340.95336) (xy 34.599874 -340.86646) (xy 34.607892 -340.779931)
			(xy 34.62386 -340.694511) (xy 34.647641 -340.610929) (xy 34.679033 -340.529897) (xy 34.717767 -340.452108)
			(xy 34.763514 -340.378224) (xy 34.815883 -340.308877) (xy 34.874427 -340.244657) (xy 34.938647 -340.186113)
			(xy 35.007994 -340.133744) (xy 35.081878 -340.087997) (xy 35.159667 -340.049263) (xy 35.240699 -340.017871)
			(xy 35.324281 -339.99409) (xy 35.409701 -339.978122) (xy 35.49623 -339.970104) (xy 35.58313 -339.970104)
			(xy 35.669659 -339.978122) (xy 35.755079 -339.99409) (xy 35.838661 -340.017871) (xy 35.919693 -340.049263)
			(xy 35.997482 -340.087997) (xy 36.071366 -340.133744) (xy 36.140713 -340.186113) (xy 36.204933 -340.244657)
			(xy 36.263477 -340.308877) (xy 36.315846 -340.378224) (xy 36.361593 -340.452108) (xy 36.400327 -340.529897)
			(xy 36.431719 -340.610929) (xy 36.4555 -340.694511) (xy 36.471468 -340.779931) (xy 36.479486 -340.86646)
			(xy 36.479988 -340.90991) (xy 36.479486 -340.95336) (xy 36.471468 -341.039889) (xy 36.4555 -341.125309)
			(xy 36.431719 -341.208891) (xy 36.400327 -341.289923) (xy 36.361593 -341.367712) (xy 36.315846 -341.441596)
			(xy 36.263477 -341.510943) (xy 36.204933 -341.575163) (xy 36.140713 -341.633707) (xy 36.071366 -341.686076)
			(xy 35.997482 -341.731823) (xy 35.919693 -341.770557) (xy 35.838661 -341.801949) (xy 35.755079 -341.82573)
			(xy 35.669659 -341.841698) (xy 35.58313 -341.849716) (xy 35.49623 -341.849716) (xy 35.409701 -341.841698)
			(xy 35.324281 -341.82573) (xy 35.240699 -341.801949) (xy 35.159667 -341.770557) (xy 35.081878 -341.731823)
			(xy 35.007994 -341.686076) (xy 34.938647 -341.633707) (xy 34.874427 -341.575163) (xy 34.815883 -341.510943)
			(xy 34.763514 -341.441596) (xy 34.717767 -341.367712) (xy 34.679033 -341.289923) (xy 34.647641 -341.208891)
			(xy 34.62386 -341.125309) (xy 34.607892 -341.039889) (xy 34.599874 -340.95336) (xy 31.398557 -340.95336)
			(xy 31.39658 -340.996318) (xy 31.384682 -341.082009) (xy 31.364962 -341.166245) (xy 31.337589 -341.248314)
			(xy 31.302793 -341.327521) (xy 31.260868 -341.403198) (xy 31.212169 -341.474703) (xy 31.157109 -341.541433)
			(xy 31.096151 -341.602823) (xy 31.029813 -341.658355) (xy 30.958653 -341.707558) (xy 30.883276 -341.750017)
			(xy 30.804316 -341.785373) (xy 30.722444 -341.813326) (xy 30.638349 -341.833641) (xy 30.552744 -341.846145)
			(xy 30.466352 -341.850734) (xy 30.379905 -341.847368) (xy 30.294131 -341.836075) (xy 30.209758 -341.816951)
			(xy 30.127498 -341.790158) (xy 30.08757 -341.77351) (xy 30.066403 -341.764941) (xy 30.021906 -341.754702)
			(xy 29.976295 -341.752576) (xy 29.931038 -341.758634) (xy 29.887591 -341.772679) (xy 29.847352 -341.794259)
			(xy 29.811616 -341.822681) (xy 29.781532 -341.85703) (xy 29.771706 -341.873433) (xy 38.925238 -341.873433)
			(xy 38.925238 -341.802111) (xy 38.933224 -341.731237) (xy 38.949094 -341.661702) (xy 38.972651 -341.594382)
			(xy 39.003596 -341.530123) (xy 39.041542 -341.469732) (xy 39.086011 -341.41397) (xy 39.136444 -341.363537)
			(xy 39.192206 -341.319068) (xy 39.252597 -341.281122) (xy 39.316856 -341.250177) (xy 39.384176 -341.22662)
			(xy 39.453711 -341.21075) (xy 39.524585 -341.202764) (xy 39.595907 -341.202764) (xy 39.666781 -341.21075)
			(xy 39.736316 -341.22662) (xy 39.803636 -341.250177) (xy 39.867895 -341.281122) (xy 39.928286 -341.319068)
			(xy 39.984048 -341.363537) (xy 40.034481 -341.41397) (xy 40.07895 -341.469732) (xy 40.116896 -341.530123)
			(xy 40.147841 -341.594382) (xy 40.171398 -341.661702) (xy 40.187268 -341.731237) (xy 40.195254 -341.802111)
			(xy 40.195754 -341.837772) (xy 40.195254 -341.873433) (xy 40.187268 -341.944307) (xy 40.171398 -342.013842)
			(xy 40.147841 -342.081162) (xy 40.116896 -342.145421) (xy 40.07895 -342.205812) (xy 40.034481 -342.261574)
			(xy 39.984048 -342.312007) (xy 39.928286 -342.356476) (xy 39.867895 -342.394422) (xy 39.803636 -342.425367)
			(xy 39.736316 -342.448924) (xy 39.666781 -342.464794) (xy 39.595907 -342.47278) (xy 39.524585 -342.47278)
			(xy 39.453711 -342.464794) (xy 39.384176 -342.448924) (xy 39.316856 -342.425367) (xy 39.252597 -342.394422)
			(xy 39.192206 -342.356476) (xy 39.136444 -342.312007) (xy 39.086011 -342.261574) (xy 39.041542 -342.205812)
			(xy 39.003596 -342.145421) (xy 38.972651 -342.081162) (xy 38.949094 -342.013842) (xy 38.933224 -341.944307)
			(xy 38.925238 -341.873433) (xy 29.771706 -341.873433) (xy 29.758068 -341.896201) (xy 29.74198 -341.938933)
			(xy 29.733784 -341.983852) (xy 29.73324 -342.006682) (xy 29.73324 -342.353138) (xy 29.733718 -342.37598)
			(xy 29.741878 -342.42093) (xy 29.757945 -342.463696) (xy 29.781402 -342.502898) (xy 29.811492 -342.537274)
			(xy 29.847245 -342.565713) (xy 29.887507 -342.5873) (xy 29.930982 -342.601337) (xy 29.976265 -342.607373)
			(xy 30.021899 -342.605213) (xy 30.06641 -342.594926) (xy 30.08757 -342.58631) (xy 30.127491 -342.569645)
			(xy 30.20975 -342.542851) (xy 30.294124 -342.523727) (xy 30.379897 -342.512433) (xy 30.466345 -342.509066)
			(xy 30.552736 -342.513654) (xy 30.638341 -342.526158) (xy 30.722436 -342.546472) (xy 30.804309 -342.574424)
			(xy 30.883269 -342.60978) (xy 30.958647 -342.652238) (xy 31.029806 -342.70144) (xy 31.096145 -342.756971)
			(xy 31.157103 -342.818361) (xy 31.212165 -342.885091) (xy 31.260864 -342.956596) (xy 31.302789 -343.032272)
			(xy 31.337586 -343.111479) (xy 31.36496 -343.193547) (xy 31.38468 -343.277783) (xy 31.39658 -343.363474)
			(xy 31.400557 -343.449896) (xy 31.398557 -343.49336) (xy 34.599874 -343.49336) (xy 34.599874 -343.40646)
			(xy 34.607892 -343.319931) (xy 34.62386 -343.234511) (xy 34.647641 -343.150929) (xy 34.679033 -343.069897)
			(xy 34.717767 -342.992108) (xy 34.763514 -342.918224) (xy 34.815883 -342.848877) (xy 34.874427 -342.784657)
			(xy 34.938647 -342.726113) (xy 35.007994 -342.673744) (xy 35.081878 -342.627997) (xy 35.159667 -342.589263)
			(xy 35.240699 -342.557871) (xy 35.324281 -342.53409) (xy 35.409701 -342.518122) (xy 35.49623 -342.510104)
			(xy 35.58313 -342.510104) (xy 35.669659 -342.518122) (xy 35.755079 -342.53409) (xy 35.838661 -342.557871)
			(xy 35.919693 -342.589263) (xy 35.997482 -342.627997) (xy 36.071366 -342.673744) (xy 36.140713 -342.726113)
			(xy 36.204933 -342.784657) (xy 36.263477 -342.848877) (xy 36.315846 -342.918224) (xy 36.361593 -342.992108)
			(xy 36.400327 -343.069897) (xy 36.431719 -343.150929) (xy 36.4555 -343.234511) (xy 36.471468 -343.319931)
			(xy 36.479486 -343.40646) (xy 36.479988 -343.44991) (xy 36.479486 -343.49336) (xy 36.471468 -343.579889)
			(xy 36.4555 -343.665309) (xy 36.431719 -343.748891) (xy 36.400327 -343.829923) (xy 36.361593 -343.907712)
			(xy 36.315846 -343.981596) (xy 36.289156 -344.016939) (xy 38.925238 -344.016939) (xy 38.925238 -343.945617)
			(xy 38.933224 -343.874743) (xy 38.949094 -343.805208) (xy 38.972651 -343.737888) (xy 39.003596 -343.673629)
			(xy 39.041542 -343.613238) (xy 39.086011 -343.557476) (xy 39.136444 -343.507043) (xy 39.192206 -343.462574)
			(xy 39.252597 -343.424628) (xy 39.316856 -343.393683) (xy 39.384176 -343.370126) (xy 39.453711 -343.354256)
			(xy 39.524585 -343.34627) (xy 39.595907 -343.34627) (xy 39.666781 -343.354256) (xy 39.736316 -343.370126)
			(xy 39.803636 -343.393683) (xy 39.867895 -343.424628) (xy 39.928286 -343.462574) (xy 39.984048 -343.507043)
			(xy 40.034481 -343.557476) (xy 40.07895 -343.613238) (xy 40.116896 -343.673629) (xy 40.147841 -343.737888)
			(xy 40.171398 -343.805208) (xy 40.187268 -343.874743) (xy 40.195254 -343.945617) (xy 40.195754 -343.981278)
			(xy 40.195254 -344.016939) (xy 40.187268 -344.087813) (xy 40.171398 -344.157348) (xy 40.147841 -344.224668)
			(xy 40.116896 -344.288927) (xy 40.07895 -344.349318) (xy 40.034481 -344.40508) (xy 39.984048 -344.455513)
			(xy 39.928286 -344.499982) (xy 39.867895 -344.537928) (xy 39.803636 -344.568873) (xy 39.736316 -344.59243)
			(xy 39.666781 -344.6083) (xy 39.595907 -344.616286) (xy 39.524585 -344.616286) (xy 39.453711 -344.6083)
			(xy 39.384176 -344.59243) (xy 39.316856 -344.568873) (xy 39.252597 -344.537928) (xy 39.192206 -344.499982)
			(xy 39.136444 -344.455513) (xy 39.086011 -344.40508) (xy 39.041542 -344.349318) (xy 39.003596 -344.288927)
			(xy 38.972651 -344.224668) (xy 38.949094 -344.157348) (xy 38.933224 -344.087813) (xy 38.925238 -344.016939)
			(xy 36.289156 -344.016939) (xy 36.263477 -344.050943) (xy 36.204933 -344.115163) (xy 36.140713 -344.173707)
			(xy 36.071366 -344.226076) (xy 35.997482 -344.271823) (xy 35.919693 -344.310557) (xy 35.838661 -344.341949)
			(xy 35.755079 -344.36573) (xy 35.669659 -344.381698) (xy 35.58313 -344.389716) (xy 35.49623 -344.389716)
			(xy 35.409701 -344.381698) (xy 35.324281 -344.36573) (xy 35.240699 -344.341949) (xy 35.159667 -344.310557)
			(xy 35.081878 -344.271823) (xy 35.007994 -344.226076) (xy 34.938647 -344.173707) (xy 34.874427 -344.115163)
			(xy 34.815883 -344.050943) (xy 34.763514 -343.981596) (xy 34.717767 -343.907712) (xy 34.679033 -343.829923)
			(xy 34.647641 -343.748891) (xy 34.62386 -343.665309) (xy 34.607892 -343.579889) (xy 34.599874 -343.49336)
			(xy 31.398557 -343.49336) (xy 31.39658 -343.536318) (xy 31.384682 -343.622009) (xy 31.364962 -343.706245)
			(xy 31.337589 -343.788314) (xy 31.302793 -343.867521) (xy 31.260868 -343.943198) (xy 31.212169 -344.014703)
			(xy 31.157109 -344.081433) (xy 31.096151 -344.142823) (xy 31.029813 -344.198355) (xy 30.958653 -344.247558)
			(xy 30.883276 -344.290017) (xy 30.804316 -344.325373) (xy 30.722444 -344.353326) (xy 30.638349 -344.373641)
			(xy 30.552744 -344.386145) (xy 30.466352 -344.390734) (xy 30.379905 -344.387368) (xy 30.294131 -344.376075)
			(xy 30.209758 -344.356951) (xy 30.127498 -344.330158) (xy 30.08757 -344.31351) (xy 30.066403 -344.304941)
			(xy 30.021906 -344.294702) (xy 29.976295 -344.292576) (xy 29.931038 -344.298634) (xy 29.887591 -344.312679)
			(xy 29.847352 -344.334259) (xy 29.811616 -344.362681) (xy 29.781532 -344.39703) (xy 29.758068 -344.436201)
			(xy 29.74198 -344.478933) (xy 29.733784 -344.523852) (xy 29.73324 -344.546682) (xy 29.73324 -344.893138)
			(xy 29.733718 -344.91598) (xy 29.741878 -344.96093) (xy 29.757945 -345.003696) (xy 29.781402 -345.042898)
			(xy 29.811492 -345.077274) (xy 29.847245 -345.105713) (xy 29.887507 -345.1273) (xy 29.930982 -345.141337)
			(xy 29.976265 -345.147373) (xy 30.021899 -345.145213) (xy 30.06641 -345.134926) (xy 30.08757 -345.12631)
			(xy 30.127491 -345.109645) (xy 30.20975 -345.082851) (xy 30.294124 -345.063727) (xy 30.379897 -345.052433)
			(xy 30.466345 -345.049066) (xy 30.552736 -345.053654) (xy 30.638341 -345.066158) (xy 30.722436 -345.086472)
			(xy 30.804309 -345.114424) (xy 30.883269 -345.14978) (xy 30.958647 -345.192238) (xy 31.029806 -345.24144)
			(xy 31.096145 -345.296971) (xy 31.157103 -345.358361) (xy 31.212165 -345.425091) (xy 31.260864 -345.496596)
			(xy 31.302789 -345.572272) (xy 31.337586 -345.651479) (xy 31.36496 -345.733547) (xy 31.38468 -345.817783)
			(xy 31.39658 -345.903474) (xy 31.400557 -345.989896) (xy 31.398557 -346.03336) (xy 34.599874 -346.03336)
			(xy 34.599874 -345.94646) (xy 34.607892 -345.859931) (xy 34.62386 -345.774511) (xy 34.647641 -345.690929)
			(xy 34.679033 -345.609897) (xy 34.717767 -345.532108) (xy 34.763514 -345.458224) (xy 34.815883 -345.388877)
			(xy 34.874427 -345.324657) (xy 34.938647 -345.266113) (xy 35.007994 -345.213744) (xy 35.081878 -345.167997)
			(xy 35.159667 -345.129263) (xy 35.240699 -345.097871) (xy 35.324281 -345.07409) (xy 35.409701 -345.058122)
			(xy 35.49623 -345.050104) (xy 35.58313 -345.050104) (xy 35.669659 -345.058122) (xy 35.755079 -345.07409)
			(xy 35.838661 -345.097871) (xy 35.919693 -345.129263) (xy 35.997482 -345.167997) (xy 36.071366 -345.213744)
			(xy 36.140713 -345.266113) (xy 36.204933 -345.324657) (xy 36.263477 -345.388877) (xy 36.315846 -345.458224)
			(xy 36.361593 -345.532108) (xy 36.400327 -345.609897) (xy 36.431719 -345.690929) (xy 36.4555 -345.774511)
			(xy 36.471468 -345.859931) (xy 36.479486 -345.94646) (xy 36.479988 -345.98991) (xy 36.479486 -346.03336)
			(xy 36.471468 -346.119889) (xy 36.4555 -346.205309) (xy 36.431719 -346.288891) (xy 36.400327 -346.369923)
			(xy 36.361593 -346.447712) (xy 36.315846 -346.521596) (xy 36.263477 -346.590943) (xy 36.204933 -346.655163)
			(xy 36.140713 -346.713707) (xy 36.071366 -346.766076) (xy 35.997482 -346.811823) (xy 35.919693 -346.850557)
			(xy 35.838661 -346.881949) (xy 35.755079 -346.90573) (xy 35.669659 -346.921698) (xy 35.58313 -346.929716)
			(xy 35.49623 -346.929716) (xy 35.409701 -346.921698) (xy 35.324281 -346.90573) (xy 35.240699 -346.881949)
			(xy 35.159667 -346.850557) (xy 35.081878 -346.811823) (xy 35.007994 -346.766076) (xy 34.938647 -346.713707)
			(xy 34.874427 -346.655163) (xy 34.815883 -346.590943) (xy 34.763514 -346.521596) (xy 34.717767 -346.447712)
			(xy 34.679033 -346.369923) (xy 34.647641 -346.288891) (xy 34.62386 -346.205309) (xy 34.607892 -346.119889)
			(xy 34.599874 -346.03336) (xy 31.398557 -346.03336) (xy 31.39658 -346.076318) (xy 31.384682 -346.162009)
			(xy 31.364962 -346.246245) (xy 31.337589 -346.328314) (xy 31.302793 -346.407521) (xy 31.260868 -346.483198)
			(xy 31.212169 -346.554703) (xy 31.157109 -346.621433) (xy 31.096151 -346.682823) (xy 31.029813 -346.738355)
			(xy 30.958653 -346.787558) (xy 30.883276 -346.830017) (xy 30.804316 -346.865373) (xy 30.722444 -346.893326)
			(xy 30.638349 -346.913641) (xy 30.552744 -346.926145) (xy 30.466352 -346.930734) (xy 30.379905 -346.927368)
			(xy 30.294131 -346.916075) (xy 30.209758 -346.896951) (xy 30.127498 -346.870158) (xy 30.08757 -346.85351)
			(xy 30.066403 -346.844941) (xy 30.021906 -346.834702) (xy 29.976295 -346.832576) (xy 29.931038 -346.838634)
			(xy 29.887591 -346.852679) (xy 29.847352 -346.874259) (xy 29.811616 -346.902681) (xy 29.781532 -346.93703)
			(xy 29.758068 -346.976201) (xy 29.74198 -347.018933) (xy 29.733784 -347.063852) (xy 29.73324 -347.086682)
			(xy 29.73324 -347.433138) (xy 29.733718 -347.45598) (xy 29.741878 -347.50093) (xy 29.757945 -347.543696)
			(xy 29.781402 -347.582898) (xy 29.811492 -347.617274) (xy 29.847245 -347.645713) (xy 29.887507 -347.6673)
			(xy 29.930982 -347.681337) (xy 29.976265 -347.687373) (xy 30.021899 -347.685213) (xy 30.06641 -347.674926)
			(xy 30.08757 -347.66631) (xy 30.127123 -347.649782) (xy 30.208615 -347.62316) (xy 30.292192 -347.604067)
			(xy 30.377159 -347.592662) (xy 30.462813 -347.58904) (xy 30.54844 -347.593229) (xy 30.633331 -347.605196)
			(xy 30.716779 -347.624841) (xy 30.798093 -347.652002) (xy 30.876597 -347.686451) (xy 30.951638 -347.727904)
			(xy 31.022595 -347.776017) (xy 31.088877 -347.830389) (xy 31.149934 -347.890569) (xy 31.205259 -347.956057)
			(xy 31.254393 -348.02631) (xy 31.296928 -348.100744) (xy 31.33251 -348.178741) (xy 31.360844 -348.259653)
			(xy 31.381695 -348.342809) (xy 31.394889 -348.427517) (xy 31.400317 -348.513075) (xy 31.398641 -348.57336)
			(xy 34.599874 -348.57336) (xy 34.599874 -348.48646) (xy 34.607892 -348.399931) (xy 34.62386 -348.314511)
			(xy 34.647641 -348.230929) (xy 34.679033 -348.149897) (xy 34.717767 -348.072108) (xy 34.763514 -347.998224)
			(xy 34.815883 -347.928877) (xy 34.874427 -347.864657) (xy 34.938647 -347.806113) (xy 35.007994 -347.753744)
			(xy 35.081878 -347.707997) (xy 35.159667 -347.669263) (xy 35.240699 -347.637871) (xy 35.324281 -347.61409)
			(xy 35.409701 -347.598122) (xy 35.49623 -347.590104) (xy 35.58313 -347.590104) (xy 35.669659 -347.598122)
			(xy 35.755079 -347.61409) (xy 35.838661 -347.637871) (xy 35.919693 -347.669263) (xy 35.997482 -347.707997)
			(xy 36.071366 -347.753744) (xy 36.140713 -347.806113) (xy 36.204933 -347.864657) (xy 36.263477 -347.928877)
			(xy 36.315846 -347.998224) (xy 36.361593 -348.072108) (xy 36.400327 -348.149897) (xy 36.431719 -348.230929)
			(xy 36.4555 -348.314511) (xy 36.471468 -348.399931) (xy 36.479486 -348.48646) (xy 36.479988 -348.52991)
			(xy 36.479486 -348.57336) (xy 36.471468 -348.659889) (xy 36.4555 -348.745309) (xy 36.431719 -348.828891)
			(xy 36.400327 -348.909923) (xy 36.361593 -348.987712) (xy 36.315846 -349.061596) (xy 36.263477 -349.130943)
			(xy 36.204933 -349.195163) (xy 36.140713 -349.253707) (xy 36.071366 -349.306076) (xy 35.997482 -349.351823)
			(xy 35.919693 -349.390557) (xy 35.838661 -349.421949) (xy 35.755079 -349.44573) (xy 35.669659 -349.461698)
			(xy 35.58313 -349.469716) (xy 35.49623 -349.469716) (xy 35.409701 -349.461698) (xy 35.324281 -349.44573)
			(xy 35.240699 -349.421949) (xy 35.159667 -349.390557) (xy 35.081878 -349.351823) (xy 35.007994 -349.306076)
			(xy 34.938647 -349.253707) (xy 34.874427 -349.195163) (xy 34.815883 -349.130943) (xy 34.763514 -349.061596)
			(xy 34.717767 -348.987712) (xy 34.679033 -348.909923) (xy 34.647641 -348.828891) (xy 34.62386 -348.745309)
			(xy 34.607892 -348.659889) (xy 34.599874 -348.57336) (xy 31.398641 -348.57336) (xy 31.397934 -348.598772)
			(xy 31.38776 -348.683896) (xy 31.369878 -348.76774) (xy 31.35757 -348.808802) (xy 31.343668 -348.851754)
			(xy 31.308743 -348.935012) (xy 31.265998 -349.014538) (xy 31.215826 -349.0896) (xy 31.158689 -349.159507)
			(xy 31.095114 -349.223614) (xy 31.025687 -349.281332) (xy 30.951046 -349.332128) (xy 30.871879 -349.375535)
			(xy 30.788916 -349.411153) (xy 30.70292 -349.438654) (xy 30.614684 -349.457785) (xy 30.569916 -349.463614)
			(xy 30.526228 -349.468948) (xy 30.494986 -349.499936) (xy 30.483538 -349.512078) (xy 30.46685 -349.540964)
			(xy 30.458207 -349.573186) (xy 30.458198 -349.606546) (xy 30.466824 -349.638773) (xy 30.483497 -349.667668)
			(xy 30.494986 -349.679768) (xy 30.648148 -349.832676) (xy 43.051984 -349.832676)
		)
		(stroke
			(width 0)
			(type solid)
		)
		(fill yes)
		(layer "In5.Cu")
		(net "GND")
	)
	(gr_poly
		(pts
			(xy 101.000052 -529.49094) (xy 101.055822 -529.490433) (xy 101.167051 -529.482101) (xy 101.277346 -529.46548)
			(xy 101.38609 -529.440662) (xy 101.492675 -529.407788) (xy 101.596506 -529.367039) (xy 101.697001 -529.318645)
			(xy 101.793598 -529.262876) (xy 101.885758 -529.200044) (xy 101.972964 -529.130501) (xy 102.054729 -529.054635)
			(xy 102.130596 -528.97287) (xy 102.20014 -528.885664) (xy 102.262972 -528.793505) (xy 102.318742 -528.696908)
			(xy 102.367136 -528.596413) (xy 102.407885 -528.492583) (xy 102.44076 -528.385998) (xy 102.465578 -528.277253)
			(xy 102.4822 -528.166959) (xy 102.490533 -528.05573) (xy 102.491032 -527.99996) (xy 102.491032 -1.999996)
			(xy 102.490523 -1.944227) (xy 102.482188 -1.833002) (xy 102.465563 -1.72271) (xy 102.440743 -1.613969)
			(xy 102.407866 -1.507387) (xy 102.367116 -1.40356) (xy 102.31872 -1.303069) (xy 102.26295 -1.206475)
			(xy 102.200118 -1.11432) (xy 102.130574 -1.027117) (xy 102.054708 -0.945356) (xy 101.972944 -0.869492)
			(xy 101.885739 -0.799951) (xy 101.793581 -0.737122) (xy 101.696985 -0.681355) (xy 101.596492 -0.632964)
			(xy 101.492664 -0.592217) (xy 101.386081 -0.559343) (xy 101.277339 -0.534527) (xy 101.167047 -0.517907)
			(xy 101.055821 -0.509575) (xy 101.000052 -0.509016) (xy 26.500074 -0.509016) (xy 26.454278 -0.509546)
			(xy 26.363077 -0.517999) (xy 26.273045 -0.534832) (xy 26.184949 -0.559899) (xy 26.099543 -0.592988)
			(xy 26.017554 -0.633817) (xy 25.939682 -0.682036) (xy 25.866592 -0.737234) (xy 25.798906 -0.798941)
			(xy 25.737202 -0.86663) (xy 25.682007 -0.939724) (xy 25.633792 -1.017598) (xy 25.592968 -1.099589)
			(xy 25.559883 -1.184997) (xy 25.53482 -1.273093) (xy 25.517992 -1.363126) (xy 25.509543 -1.454328)
			(xy 25.508966 -1.500124) (xy 25.508966 -2.500122) (xy 25.50847 -2.563238) (xy 25.500544 -2.689221)
			(xy 25.484723 -2.814458) (xy 25.461069 -2.938455) (xy 25.429676 -3.060721) (xy 25.390668 -3.180775)
			(xy 25.344199 -3.298143) (xy 25.290452 -3.412362) (xy 25.229639 -3.52298) (xy 25.162 -3.629561) (xy 25.087803 -3.731685)
			(xy 25.007339 -3.828949) (xy 24.920927 -3.920968) (xy 24.828907 -4.00738) (xy 24.731644 -4.087844)
			(xy 24.62952 -4.162041) (xy 24.522938 -4.22968) (xy 24.41232 -4.290493) (xy 24.298101 -4.34424) (xy 24.180733 -4.390709)
			(xy 24.060679 -4.429717) (xy 23.938413 -4.46111) (xy 23.814416 -4.484763) (xy 23.689179 -4.500584)
			(xy 23.563196 -4.50851) (xy 23.50008 -4.509008) (xy 1.500124 -4.509008) (xy 1.454327 -4.509537) (xy 1.363123 -4.517988)
			(xy 1.273088 -4.534819) (xy 1.18499 -4.559885) (xy 1.099581 -4.592972) (xy 1.018224 -4.633484) (xy 29.519874 -4.633484)
			(xy 29.519874 -4.546584) (xy 29.527892 -4.460055) (xy 29.54386 -4.374635) (xy 29.567641 -4.291053)
			(xy 29.599033 -4.210021) (xy 29.637767 -4.132232) (xy 29.683514 -4.058348) (xy 29.735883 -3.989001)
			(xy 29.794427 -3.924781) (xy 29.858647 -3.866237) (xy 29.927994 -3.813868) (xy 30.001878 -3.768121)
			(xy 30.079667 -3.729387) (xy 30.160699 -3.697995) (xy 30.244281 -3.674214) (xy 30.329701 -3.658246)
			(xy 30.41623 -3.650228) (xy 30.45968 -3.649726) (xy 30.50313 -3.650228) (xy 30.589659 -3.658246)
			(xy 30.675079 -3.674214) (xy 30.758661 -3.697995) (xy 30.839693 -3.729387) (xy 30.917482 -3.768121)
			(xy 30.991366 -3.813868) (xy 31.060713 -3.866237) (xy 31.124933 -3.924781) (xy 31.183477 -3.989001)
			(xy 31.235846 -4.058348) (xy 31.281593 -4.132232) (xy 31.320327 -4.210021) (xy 31.351719 -4.291053)
			(xy 31.3755 -4.374635) (xy 31.391468 -4.460055) (xy 31.399486 -4.546584) (xy 31.399486 -4.633484)
			(xy 34.599874 -4.633484) (xy 34.599874 -4.546584) (xy 34.607892 -4.460055) (xy 34.62386 -4.374635)
			(xy 34.647641 -4.291053) (xy 34.679033 -4.210021) (xy 34.717767 -4.132232) (xy 34.763514 -4.058348)
			(xy 34.815883 -3.989001) (xy 34.874427 -3.924781) (xy 34.938647 -3.866237) (xy 35.007994 -3.813868)
			(xy 35.081878 -3.768121) (xy 35.159667 -3.729387) (xy 35.240699 -3.697995) (xy 35.324281 -3.674214)
			(xy 35.409701 -3.658246) (xy 35.49623 -3.650228) (xy 35.53968 -3.649726) (xy 35.58313 -3.650228)
			(xy 35.669659 -3.658246) (xy 35.755079 -3.674214) (xy 35.838661 -3.697995) (xy 35.919693 -3.729387)
			(xy 35.997482 -3.768121) (xy 36.071366 -3.813868) (xy 36.140713 -3.866237) (xy 36.204933 -3.924781)
			(xy 36.263477 -3.989001) (xy 36.315846 -4.058348) (xy 36.361593 -4.132232) (xy 36.400327 -4.210021)
			(xy 36.431719 -4.291053) (xy 36.4555 -4.374635) (xy 36.471468 -4.460055) (xy 36.479486 -4.546584)
			(xy 36.479486 -4.633484) (xy 36.471468 -4.720013) (xy 36.4555 -4.805433) (xy 36.431719 -4.889015)
			(xy 36.400327 -4.970047) (xy 36.361593 -5.047836) (xy 36.315846 -5.12172) (xy 36.263477 -5.191067)
			(xy 36.204933 -5.255287) (xy 36.140713 -5.313831) (xy 36.071366 -5.3662) (xy 35.997482 -5.411947)
			(xy 35.919693 -5.450681) (xy 35.838661 -5.482073) (xy 35.755079 -5.505854) (xy 35.669659 -5.521822)
			(xy 35.58313 -5.52984) (xy 35.49623 -5.52984) (xy 35.409701 -5.521822) (xy 35.324281 -5.505854) (xy 35.240699 -5.482073)
			(xy 35.159667 -5.450681) (xy 35.081878 -5.411947) (xy 35.007994 -5.3662) (xy 34.938647 -5.313831)
			(xy 34.874427 -5.255287) (xy 34.815883 -5.191067) (xy 34.763514 -5.12172) (xy 34.717767 -5.047836)
			(xy 34.679033 -4.970047) (xy 34.647641 -4.889015) (xy 34.62386 -4.805433) (xy 34.607892 -4.720013)
			(xy 34.599874 -4.633484) (xy 31.399486 -4.633484) (xy 31.391468 -4.720013) (xy 31.3755 -4.805433)
			(xy 31.351719 -4.889015) (xy 31.320327 -4.970047) (xy 31.281593 -5.047836) (xy 31.235846 -5.12172)
			(xy 31.183477 -5.191067) (xy 31.124933 -5.255287) (xy 31.060713 -5.313831) (xy 30.991366 -5.3662)
			(xy 30.917482 -5.411947) (xy 30.839693 -5.450681) (xy 30.758661 -5.482073) (xy 30.675079 -5.505854)
			(xy 30.589659 -5.521822) (xy 30.50313 -5.52984) (xy 30.41623 -5.52984) (xy 30.329701 -5.521822) (xy 30.244281 -5.505854)
			(xy 30.160699 -5.482073) (xy 30.079667 -5.450681) (xy 30.001878 -5.411947) (xy 29.927994 -5.3662)
			(xy 29.858647 -5.313831) (xy 29.794427 -5.255287) (xy 29.735883 -5.191067) (xy 29.683514 -5.12172)
			(xy 29.637767 -5.047836) (xy 29.599033 -4.970047) (xy 29.567641 -4.889015) (xy 29.54386 -4.805433)
			(xy 29.527892 -4.720013) (xy 29.519874 -4.633484) (xy 1.018224 -4.633484) (xy 1.017589 -4.6338) (xy 0.939714 -4.682018)
			(xy 0.86662 -4.737216) (xy 0.798931 -4.798923) (xy 0.737224 -4.866612) (xy 0.682026 -4.939706) (xy 0.633808 -5.017581)
			(xy 0.59298 -5.099573) (xy 0.559893 -5.184982) (xy 0.534827 -5.27308) (xy 0.517996 -5.363115) (xy 0.509545 -5.454319)
			(xy 0.509016 -5.500116) (xy 0.509016 -6.378617) (xy 3.67918 -6.378617) (xy 3.67918 -6.297507) (xy 3.68713 -6.216788)
			(xy 3.702953 -6.137237) (xy 3.726498 -6.059621) (xy 3.757537 -5.984685) (xy 3.795772 -5.913153) (xy 3.840834 -5.845713)
			(xy 3.892289 -5.783014) (xy 3.949642 -5.725661) (xy 4.012341 -5.674206) (xy 4.079781 -5.629144) (xy 4.151313 -5.590909)
			(xy 4.226249 -5.55987) (xy 4.303865 -5.536325) (xy 4.383416 -5.520502) (xy 4.464135 -5.512552) (xy 4.50469 -5.512054)
			(xy 4.545245 -5.512552) (xy 4.625964 -5.520502) (xy 4.705515 -5.536325) (xy 4.783131 -5.55987) (xy 4.858067 -5.590909)
			(xy 4.929599 -5.629144) (xy 4.997039 -5.674206) (xy 5.059738 -5.725661) (xy 5.117091 -5.783014) (xy 5.168546 -5.845713)
			(xy 5.213608 -5.913153) (xy 5.251843 -5.984685) (xy 5.282882 -6.059621) (xy 5.306427 -6.137237) (xy 5.32225 -6.216788)
			(xy 5.3302 -6.297507) (xy 5.3302 -6.378617) (xy 6.21918 -6.378617) (xy 6.21918 -6.297507) (xy 6.22713 -6.216788)
			(xy 6.242953 -6.137237) (xy 6.266498 -6.059621) (xy 6.297537 -5.984685) (xy 6.335772 -5.913153) (xy 6.380834 -5.845713)
			(xy 6.432289 -5.783014) (xy 6.489642 -5.725661) (xy 6.552341 -5.674206) (xy 6.619781 -5.629144) (xy 6.691313 -5.590909)
			(xy 6.766249 -5.55987) (xy 6.843865 -5.536325) (xy 6.923416 -5.520502) (xy 7.004135 -5.512552) (xy 7.04469 -5.512054)
			(xy 7.085245 -5.512552) (xy 7.165964 -5.520502) (xy 7.245515 -5.536325) (xy 7.323131 -5.55987) (xy 7.398067 -5.590909)
			(xy 7.469599 -5.629144) (xy 7.537039 -5.674206) (xy 7.599738 -5.725661) (xy 7.657091 -5.783014) (xy 7.708546 -5.845713)
			(xy 7.753608 -5.913153) (xy 7.791843 -5.984685) (xy 7.822882 -6.059621) (xy 7.846427 -6.137237) (xy 7.86225 -6.216788)
			(xy 7.8702 -6.297507) (xy 7.8702 -6.378617) (xy 11.29918 -6.378617) (xy 11.29918 -6.297507) (xy 11.30713 -6.216788)
			(xy 11.322953 -6.137237) (xy 11.346498 -6.059621) (xy 11.377537 -5.984685) (xy 11.415772 -5.913153)
			(xy 11.460834 -5.845713) (xy 11.512289 -5.783014) (xy 11.569642 -5.725661) (xy 11.632341 -5.674206)
			(xy 11.699781 -5.629144) (xy 11.771313 -5.590909) (xy 11.846249 -5.55987) (xy 11.923865 -5.536325)
			(xy 12.003416 -5.520502) (xy 12.084135 -5.512552) (xy 12.12469 -5.512054) (xy 12.165245 -5.512552)
			(xy 12.245964 -5.520502) (xy 12.325515 -5.536325) (xy 12.403131 -5.55987) (xy 12.478067 -5.590909)
			(xy 12.549599 -5.629144) (xy 12.617039 -5.674206) (xy 12.679738 -5.725661) (xy 12.737091 -5.783014)
			(xy 12.788546 -5.845713) (xy 12.833608 -5.913153) (xy 12.871843 -5.984685) (xy 12.902882 -6.059621)
			(xy 12.926427 -6.137237) (xy 12.94225 -6.216788) (xy 12.9502 -6.297507) (xy 12.9502 -6.378617) (xy 12.94225 -6.459336)
			(xy 12.926427 -6.538887) (xy 12.902882 -6.616503) (xy 12.883855 -6.662438) (xy 26.785569 -6.662438)
			(xy 26.791669 -6.607001) (xy 26.805775 -6.553044) (xy 26.827587 -6.501715) (xy 26.856641 -6.454109)
			(xy 26.892316 -6.411241) (xy 26.933853 -6.374024) (xy 26.980366 -6.343251) (xy 27.030863 -6.319579)
			(xy 27.08427 -6.303511) (xy 27.139446 -6.295391) (xy 27.167332 -6.294882) (xy 27.195218 -6.295391)
			(xy 27.250394 -6.303511) (xy 27.303801 -6.319579) (xy 27.354298 -6.343251) (xy 27.400811 -6.374024)
			(xy 27.442348 -6.411241) (xy 27.478023 -6.454109) (xy 27.507077 -6.501715) (xy 27.528889 -6.553044)
			(xy 27.542995 -6.607001) (xy 27.549095 -6.662438) (xy 27.547058 -6.718172) (xy 27.536928 -6.773015)
			(xy 27.518921 -6.825799) (xy 27.49342 -6.875399) (xy 27.460969 -6.920757) (xy 27.42226 -6.960906)
			(xy 27.378117 -6.994992) (xy 27.329482 -7.022288) (xy 27.277391 -7.042211) (xy 27.222954 -7.054337)
			(xy 27.167332 -7.058408) (xy 27.11171 -7.054337) (xy 27.057273 -7.042211) (xy 27.005182 -7.022288)
			(xy 26.956547 -6.994992) (xy 26.912404 -6.960906) (xy 26.873695 -6.920757) (xy 26.841244 -6.875399)
			(xy 26.815743 -6.825799) (xy 26.797736 -6.773015) (xy 26.787606 -6.718172) (xy 26.785569 -6.662438)
			(xy 12.883855 -6.662438) (xy 12.871843 -6.691439) (xy 12.833608 -6.762971) (xy 12.788546 -6.830411)
			(xy 12.737091 -6.89311) (xy 12.679738 -6.950463) (xy 12.617039 -7.001918) (xy 12.549599 -7.04698)
			(xy 12.478067 -7.085215) (xy 12.403131 -7.116254) (xy 12.325515 -7.139799) (xy 12.245964 -7.155622)
			(xy 12.165245 -7.163572) (xy 12.084135 -7.163572) (xy 12.003416 -7.155622) (xy 11.923865 -7.139799)
			(xy 11.846249 -7.116254) (xy 11.771313 -7.085215) (xy 11.699781 -7.04698) (xy 11.632341 -7.001918)
			(xy 11.569642 -6.950463) (xy 11.512289 -6.89311) (xy 11.460834 -6.830411) (xy 11.415772 -6.762971)
			(xy 11.377537 -6.691439) (xy 11.346498 -6.616503) (xy 11.322953 -6.538887) (xy 11.30713 -6.459336)
			(xy 11.29918 -6.378617) (xy 7.8702 -6.378617) (xy 7.86225 -6.459336) (xy 7.846427 -6.538887) (xy 7.822882 -6.616503)
			(xy 7.791843 -6.691439) (xy 7.753608 -6.762971) (xy 7.708546 -6.830411) (xy 7.657091 -6.89311) (xy 7.599738 -6.950463)
			(xy 7.537039 -7.001918) (xy 7.469599 -7.04698) (xy 7.398067 -7.085215) (xy 7.323131 -7.116254) (xy 7.245515 -7.139799)
			(xy 7.165964 -7.155622) (xy 7.085245 -7.163572) (xy 7.004135 -7.163572) (xy 6.923416 -7.155622) (xy 6.843865 -7.139799)
			(xy 6.766249 -7.116254) (xy 6.691313 -7.085215) (xy 6.619781 -7.04698) (xy 6.552341 -7.001918) (xy 6.489642 -6.950463)
			(xy 6.432289 -6.89311) (xy 6.380834 -6.830411) (xy 6.335772 -6.762971) (xy 6.297537 -6.691439) (xy 6.266498 -6.616503)
			(xy 6.242953 -6.538887) (xy 6.22713 -6.459336) (xy 6.21918 -6.378617) (xy 5.3302 -6.378617) (xy 5.32225 -6.459336)
			(xy 5.306427 -6.538887) (xy 5.282882 -6.616503) (xy 5.251843 -6.691439) (xy 5.213608 -6.762971) (xy 5.168546 -6.830411)
			(xy 5.117091 -6.89311) (xy 5.059738 -6.950463) (xy 4.997039 -7.001918) (xy 4.929599 -7.04698) (xy 4.858067 -7.085215)
			(xy 4.783131 -7.116254) (xy 4.705515 -7.139799) (xy 4.625964 -7.155622) (xy 4.545245 -7.163572) (xy 4.464135 -7.163572)
			(xy 4.383416 -7.155622) (xy 4.303865 -7.139799) (xy 4.226249 -7.116254) (xy 4.151313 -7.085215) (xy 4.079781 -7.04698)
			(xy 4.012341 -7.001918) (xy 3.949642 -6.950463) (xy 3.892289 -6.89311) (xy 3.840834 -6.830411) (xy 3.795772 -6.762971)
			(xy 3.757537 -6.691439) (xy 3.726498 -6.616503) (xy 3.702953 -6.538887) (xy 3.68713 -6.459336) (xy 3.67918 -6.378617)
			(xy 0.509016 -6.378617) (xy 0.509016 -7.173484) (xy 29.519874 -7.173484) (xy 29.519874 -7.086584)
			(xy 29.527892 -7.000055) (xy 29.54386 -6.914635) (xy 29.567641 -6.831053) (xy 29.599033 -6.750021)
			(xy 29.637767 -6.672232) (xy 29.683514 -6.598348) (xy 29.735883 -6.529001) (xy 29.794427 -6.464781)
			(xy 29.858647 -6.406237) (xy 29.927994 -6.353868) (xy 30.001878 -6.308121) (xy 30.079667 -6.269387)
			(xy 30.160699 -6.237995) (xy 30.244281 -6.214214) (xy 30.329701 -6.198246) (xy 30.41623 -6.190228)
			(xy 30.45968 -6.189726) (xy 30.50313 -6.190228) (xy 30.589659 -6.198246) (xy 30.675079 -6.214214)
			(xy 30.758661 -6.237995) (xy 30.839693 -6.269387) (xy 30.917482 -6.308121) (xy 30.991366 -6.353868)
			(xy 31.060713 -6.406237) (xy 31.124933 -6.464781) (xy 31.183477 -6.529001) (xy 31.235846 -6.598348)
			(xy 31.281593 -6.672232) (xy 31.320327 -6.750021) (xy 31.351719 -6.831053) (xy 31.3755 -6.914635)
			(xy 31.391468 -7.000055) (xy 31.399486 -7.086584) (xy 31.399486 -7.173484) (xy 34.599874 -7.173484)
			(xy 34.599874 -7.086584) (xy 34.607892 -7.000055) (xy 34.62386 -6.914635) (xy 34.647641 -6.831053)
			(xy 34.679033 -6.750021) (xy 34.717767 -6.672232) (xy 34.763514 -6.598348) (xy 34.815883 -6.529001)
			(xy 34.874427 -6.464781) (xy 34.938647 -6.406237) (xy 35.007994 -6.353868) (xy 35.081878 -6.308121)
			(xy 35.159667 -6.269387) (xy 35.240699 -6.237995) (xy 35.324281 -6.214214) (xy 35.409701 -6.198246)
			(xy 35.49623 -6.190228) (xy 35.53968 -6.189726) (xy 35.58313 -6.190228) (xy 35.669659 -6.198246)
			(xy 35.755079 -6.214214) (xy 35.838661 -6.237995) (xy 35.919693 -6.269387) (xy 35.997482 -6.308121)
			(xy 36.071366 -6.353868) (xy 36.140713 -6.406237) (xy 36.204933 -6.464781) (xy 36.263477 -6.529001)
			(xy 36.315846 -6.598348) (xy 36.361593 -6.672232) (xy 36.400327 -6.750021) (xy 36.431719 -6.831053)
			(xy 36.445942 -6.881042) (xy 39.818314 -6.881042) (xy 39.824323 -6.765104) (xy 39.838316 -6.649857)
			(xy 39.860227 -6.535851) (xy 39.889952 -6.423627) (xy 39.927348 -6.313721) (xy 39.972237 -6.206658)
			(xy 40.024406 -6.102946) (xy 40.083606 -6.003081) (xy 40.149555 -5.907538) (xy 40.221938 -5.816772)
			(xy 40.300411 -5.731217) (xy 40.384599 -5.651279) (xy 40.474101 -5.57734) (xy 40.568492 -5.509752)
			(xy 40.66732 -5.448838) (xy 40.770116 -5.394886) (xy 40.876389 -5.348156) (xy 40.985633 -5.308868)
			(xy 41.097326 -5.277211) (xy 41.210938 -5.253335) (xy 41.325926 -5.237354) (xy 41.441743 -5.229345)
			(xy 41.49979 -5.228844) (xy 41.557837 -5.229345) (xy 41.673654 -5.237354) (xy 41.788642 -5.253335)
			(xy 41.902254 -5.277211) (xy 42.013947 -5.308868) (xy 42.123191 -5.348156) (xy 42.229464 -5.394886)
			(xy 42.33226 -5.448838) (xy 42.431088 -5.509752) (xy 42.474869 -5.541101) (xy 63.647829 -5.541101)
			(xy 63.653878 -5.465531) (xy 63.667925 -5.391033) (xy 63.689811 -5.31845) (xy 63.719288 -5.248604)
			(xy 63.756023 -5.182287) (xy 63.799598 -5.120251) (xy 63.84952 -5.063198) (xy 63.905224 -5.011774)
			(xy 63.966079 -4.966563) (xy 64.031394 -4.928076) (xy 64.10043 -4.89675) (xy 64.172405 -4.87294)
			(xy 64.246503 -4.856915) (xy 64.321884 -4.848856) (xy 64.35979 -4.848352) (xy 64.397696 -4.848856)
			(xy 64.473077 -4.856915) (xy 64.547175 -4.87294) (xy 64.61915 -4.89675) (xy 64.688186 -4.928076)
			(xy 64.753501 -4.966563) (xy 64.814356 -5.011774) (xy 64.87006 -5.063198) (xy 64.919982 -5.120251)
			(xy 64.963557 -5.182287) (xy 65.000292 -5.248604) (xy 65.029769 -5.31845) (xy 65.051655 -5.391033)
			(xy 65.065702 -5.465531) (xy 65.071751 -5.541101) (xy 66.187829 -5.541101) (xy 66.193878 -5.465531)
			(xy 66.207925 -5.391033) (xy 66.229811 -5.31845) (xy 66.259288 -5.248604) (xy 66.296023 -5.182287)
			(xy 66.339598 -5.120251) (xy 66.38952 -5.063198) (xy 66.445224 -5.011774) (xy 66.506079 -4.966563)
			(xy 66.571394 -4.928076) (xy 66.64043 -4.89675) (xy 66.712405 -4.87294) (xy 66.786503 -4.856915)
			(xy 66.861884 -4.848856) (xy 66.89979 -4.848352) (xy 66.937696 -4.848856) (xy 67.013077 -4.856915)
			(xy 67.087175 -4.87294) (xy 67.15915 -4.89675) (xy 67.228186 -4.928076) (xy 67.293501 -4.966563)
			(xy 67.354356 -5.011774) (xy 67.41006 -5.063198) (xy 67.459982 -5.120251) (xy 67.503557 -5.182287)
			(xy 67.540292 -5.248604) (xy 67.569769 -5.31845) (xy 67.591655 -5.391033) (xy 67.605702 -5.465531)
			(xy 67.611751 -5.541101) (xy 68.727829 -5.541101) (xy 68.733878 -5.465531) (xy 68.747925 -5.391033)
			(xy 68.769811 -5.31845) (xy 68.799288 -5.248604) (xy 68.836023 -5.182287) (xy 68.879598 -5.120251)
			(xy 68.92952 -5.063198) (xy 68.985224 -5.011774) (xy 69.046079 -4.966563) (xy 69.111394 -4.928076)
			(xy 69.18043 -4.89675) (xy 69.252405 -4.87294) (xy 69.326503 -4.856915) (xy 69.401884 -4.848856)
			(xy 69.43979 -4.848352) (xy 69.477696 -4.848856) (xy 69.553077 -4.856915) (xy 69.627175 -4.87294)
			(xy 69.69915 -4.89675) (xy 69.768186 -4.928076) (xy 69.833501 -4.966563) (xy 69.894356 -5.011774)
			(xy 69.95006 -5.063198) (xy 69.999982 -5.120251) (xy 70.043557 -5.182287) (xy 70.080292 -5.248604)
			(xy 70.109769 -5.31845) (xy 70.131655 -5.391033) (xy 70.145702 -5.465531) (xy 70.151751 -5.541101)
			(xy 71.267829 -5.541101) (xy 71.273878 -5.465531) (xy 71.287925 -5.391033) (xy 71.309811 -5.31845)
			(xy 71.339288 -5.248604) (xy 71.376023 -5.182287) (xy 71.419598 -5.120251) (xy 71.46952 -5.063198)
			(xy 71.525224 -5.011774) (xy 71.586079 -4.966563) (xy 71.651394 -4.928076) (xy 71.72043 -4.89675)
			(xy 71.792405 -4.87294) (xy 71.866503 -4.856915) (xy 71.941884 -4.848856) (xy 71.97979 -4.848352)
			(xy 72.017696 -4.848856) (xy 72.093077 -4.856915) (xy 72.167175 -4.87294) (xy 72.23915 -4.89675)
			(xy 72.308186 -4.928076) (xy 72.373501 -4.966563) (xy 72.434356 -5.011774) (xy 72.49006 -5.063198)
			(xy 72.539982 -5.120251) (xy 72.583557 -5.182287) (xy 72.620292 -5.248604) (xy 72.649769 -5.31845)
			(xy 72.671655 -5.391033) (xy 72.685702 -5.465531) (xy 72.691751 -5.541101) (xy 73.807829 -5.541101)
			(xy 73.813878 -5.465531) (xy 73.827925 -5.391033) (xy 73.849811 -5.31845) (xy 73.879288 -5.248604)
			(xy 73.916023 -5.182287) (xy 73.959598 -5.120251) (xy 74.00952 -5.063198) (xy 74.065224 -5.011774)
			(xy 74.126079 -4.966563) (xy 74.191394 -4.928076) (xy 74.26043 -4.89675) (xy 74.332405 -4.87294)
			(xy 74.406503 -4.856915) (xy 74.481884 -4.848856) (xy 74.51979 -4.848352) (xy 74.557696 -4.848856)
			(xy 74.633077 -4.856915) (xy 74.707175 -4.87294) (xy 74.77915 -4.89675) (xy 74.848186 -4.928076)
			(xy 74.913501 -4.966563) (xy 74.974356 -5.011774) (xy 75.03006 -5.063198) (xy 75.079982 -5.120251)
			(xy 75.123557 -5.182287) (xy 75.160292 -5.248604) (xy 75.189769 -5.31845) (xy 75.211655 -5.391033)
			(xy 75.225702 -5.465531) (xy 75.231751 -5.541101) (xy 76.347829 -5.541101) (xy 76.353878 -5.465531)
			(xy 76.367925 -5.391033) (xy 76.389811 -5.31845) (xy 76.419288 -5.248604) (xy 76.456023 -5.182287)
			(xy 76.499598 -5.120251) (xy 76.54952 -5.063198) (xy 76.605224 -5.011774) (xy 76.666079 -4.966563)
			(xy 76.731394 -4.928076) (xy 76.80043 -4.89675) (xy 76.872405 -4.87294) (xy 76.946503 -4.856915)
			(xy 77.021884 -4.848856) (xy 77.05979 -4.848352) (xy 77.097696 -4.848856) (xy 77.173077 -4.856915)
			(xy 77.247175 -4.87294) (xy 77.31915 -4.89675) (xy 77.388186 -4.928076) (xy 77.453501 -4.966563)
			(xy 77.514356 -5.011774) (xy 77.57006 -5.063198) (xy 77.619982 -5.120251) (xy 77.663557 -5.182287)
			(xy 77.700292 -5.248604) (xy 77.729769 -5.31845) (xy 77.751655 -5.391033) (xy 77.765702 -5.465531)
			(xy 77.771751 -5.541101) (xy 78.887829 -5.541101) (xy 78.893878 -5.465531) (xy 78.907925 -5.391033)
			(xy 78.929811 -5.31845) (xy 78.959288 -5.248604) (xy 78.996023 -5.182287) (xy 79.039598 -5.120251)
			(xy 79.08952 -5.063198) (xy 79.145224 -5.011774) (xy 79.206079 -4.966563) (xy 79.271394 -4.928076)
			(xy 79.34043 -4.89675) (xy 79.412405 -4.87294) (xy 79.486503 -4.856915) (xy 79.561884 -4.848856)
			(xy 79.59979 -4.848352) (xy 79.637696 -4.848856) (xy 79.713077 -4.856915) (xy 79.787175 -4.87294)
			(xy 79.85915 -4.89675) (xy 79.928186 -4.928076) (xy 79.993501 -4.966563) (xy 80.054356 -5.011774)
			(xy 80.11006 -5.063198) (xy 80.159982 -5.120251) (xy 80.203557 -5.182287) (xy 80.240292 -5.248604)
			(xy 80.269769 -5.31845) (xy 80.291655 -5.391033) (xy 80.305702 -5.465531) (xy 80.311751 -5.541101)
			(xy 81.427829 -5.541101) (xy 81.433878 -5.465531) (xy 81.447925 -5.391033) (xy 81.469811 -5.31845)
			(xy 81.499288 -5.248604) (xy 81.536023 -5.182287) (xy 81.579598 -5.120251) (xy 81.62952 -5.063198)
			(xy 81.685224 -5.011774) (xy 81.746079 -4.966563) (xy 81.811394 -4.928076) (xy 81.88043 -4.89675)
			(xy 81.952405 -4.87294) (xy 82.026503 -4.856915) (xy 82.101884 -4.848856) (xy 82.13979 -4.848352)
			(xy 82.177696 -4.848856) (xy 82.253077 -4.856915) (xy 82.327175 -4.87294) (xy 82.39915 -4.89675)
			(xy 82.468186 -4.928076) (xy 82.533501 -4.966563) (xy 82.594356 -5.011774) (xy 82.65006 -5.063198)
			(xy 82.699982 -5.120251) (xy 82.743557 -5.182287) (xy 82.780292 -5.248604) (xy 82.809769 -5.31845)
			(xy 82.831655 -5.391033) (xy 82.845702 -5.465531) (xy 82.851751 -5.541101) (xy 82.849732 -5.616885)
			(xy 82.83967 -5.692025) (xy 82.821678 -5.76567) (xy 82.79596 -5.836986) (xy 82.762808 -5.905163)
			(xy 82.722596 -5.969431) (xy 82.675781 -6.02906) (xy 82.622893 -6.083376) (xy 82.564531 -6.131762)
			(xy 82.501356 -6.17367) (xy 82.434085 -6.208626) (xy 82.36348 -6.236233) (xy 82.290588 -6.256111)
			(xy 84.927949 -6.256111) (xy 84.933998 -6.180541) (xy 84.948045 -6.106043) (xy 84.969931 -6.03346)
			(xy 84.999408 -5.963614) (xy 85.036143 -5.897297) (xy 85.079718 -5.835261) (xy 85.12964 -5.778208)
			(xy 85.185344 -5.726784) (xy 85.246199 -5.681573) (xy 85.311514 -5.643086) (xy 85.38055 -5.61176)
			(xy 85.452525 -5.58795) (xy 85.526623 -5.571925) (xy 85.602004 -5.563866) (xy 85.63991 -5.563362)
			(xy 85.677816 -5.563866) (xy 85.753197 -5.571925) (xy 85.827295 -5.58795) (xy 85.89927 -5.61176)
			(xy 85.968306 -5.643086) (xy 86.033621 -5.681573) (xy 86.094476 -5.726784) (xy 86.15018 -5.778208)
			(xy 86.200102 -5.835261) (xy 86.243677 -5.897297) (xy 86.280412 -5.963614) (xy 86.309889 -6.03346)
			(xy 86.331775 -6.106043) (xy 86.345822 -6.180541) (xy 86.351871 -6.256111) (xy 86.349852 -6.331895)
			(xy 86.33979 -6.407035) (xy 86.321798 -6.48068) (xy 86.29608 -6.551996) (xy 86.262928 -6.620173)
			(xy 86.222716 -6.684441) (xy 86.175901 -6.74407) (xy 86.123013 -6.798386) (xy 86.064651 -6.846772)
			(xy 86.001476 -6.88868) (xy 85.934205 -6.923636) (xy 85.8636 -6.951243) (xy 85.790459 -6.971189)
			(xy 85.715614 -6.983248) (xy 85.63991 -6.987283) (xy 85.564206 -6.983248) (xy 85.489361 -6.971189)
			(xy 85.41622 -6.951243) (xy 85.345615 -6.923636) (xy 85.278344 -6.88868) (xy 85.215169 -6.846772)
			(xy 85.156807 -6.798386) (xy 85.103919 -6.74407) (xy 85.057104 -6.684441) (xy 85.016892 -6.620173)
			(xy 84.98374 -6.551996) (xy 84.958022 -6.48068) (xy 84.94003 -6.407035) (xy 84.929968 -6.331895)
			(xy 84.927949 -6.256111) (xy 82.290588 -6.256111) (xy 82.290339 -6.256179) (xy 82.215494 -6.268238)
			(xy 82.13979 -6.272273) (xy 82.064086 -6.268238) (xy 81.989241 -6.256179) (xy 81.9161 -6.236233)
			(xy 81.845495 -6.208626) (xy 81.778224 -6.17367) (xy 81.715049 -6.131762) (xy 81.656687 -6.083376)
			(xy 81.603799 -6.02906) (xy 81.556984 -5.969431) (xy 81.516772 -5.905163) (xy 81.48362 -5.836986)
			(xy 81.457902 -5.76567) (xy 81.43991 -5.692025) (xy 81.429848 -5.616885) (xy 81.427829 -5.541101)
			(xy 80.311751 -5.541101) (xy 80.309732 -5.616885) (xy 80.29967 -5.692025) (xy 80.281678 -5.76567)
			(xy 80.25596 -5.836986) (xy 80.222808 -5.905163) (xy 80.182596 -5.969431) (xy 80.135781 -6.02906)
			(xy 80.082893 -6.083376) (xy 80.024531 -6.131762) (xy 79.961356 -6.17367) (xy 79.894085 -6.208626)
			(xy 79.82348 -6.236233) (xy 79.750339 -6.256179) (xy 79.675494 -6.268238) (xy 79.59979 -6.272273)
			(xy 79.524086 -6.268238) (xy 79.449241 -6.256179) (xy 79.3761 -6.236233) (xy 79.305495 -6.208626)
			(xy 79.238224 -6.17367) (xy 79.175049 -6.131762) (xy 79.116687 -6.083376) (xy 79.063799 -6.02906)
			(xy 79.016984 -5.969431) (xy 78.976772 -5.905163) (xy 78.94362 -5.836986) (xy 78.917902 -5.76567)
			(xy 78.89991 -5.692025) (xy 78.889848 -5.616885) (xy 78.887829 -5.541101) (xy 77.771751 -5.541101)
			(xy 77.769732 -5.616885) (xy 77.75967 -5.692025) (xy 77.741678 -5.76567) (xy 77.71596 -5.836986)
			(xy 77.682808 -5.905163) (xy 77.642596 -5.969431) (xy 77.595781 -6.02906) (xy 77.542893 -6.083376)
			(xy 77.484531 -6.131762) (xy 77.421356 -6.17367) (xy 77.354085 -6.208626) (xy 77.28348 -6.236233)
			(xy 77.210339 -6.256179) (xy 77.135494 -6.268238) (xy 77.05979 -6.272273) (xy 76.984086 -6.268238)
			(xy 76.909241 -6.256179) (xy 76.8361 -6.236233) (xy 76.765495 -6.208626) (xy 76.698224 -6.17367)
			(xy 76.635049 -6.131762) (xy 76.576687 -6.083376) (xy 76.523799 -6.02906) (xy 76.476984 -5.969431)
			(xy 76.436772 -5.905163) (xy 76.40362 -5.836986) (xy 76.377902 -5.76567) (xy 76.35991 -5.692025)
			(xy 76.349848 -5.616885) (xy 76.347829 -5.541101) (xy 75.231751 -5.541101) (xy 75.229732 -5.616885)
			(xy 75.21967 -5.692025) (xy 75.201678 -5.76567) (xy 75.17596 -5.836986) (xy 75.142808 -5.905163)
			(xy 75.102596 -5.969431) (xy 75.055781 -6.02906) (xy 75.002893 -6.083376) (xy 74.944531 -6.131762)
			(xy 74.881356 -6.17367) (xy 74.814085 -6.208626) (xy 74.74348 -6.236233) (xy 74.670339 -6.256179)
			(xy 74.595494 -6.268238) (xy 74.51979 -6.272273) (xy 74.444086 -6.268238) (xy 74.369241 -6.256179)
			(xy 74.2961 -6.236233) (xy 74.225495 -6.208626) (xy 74.158224 -6.17367) (xy 74.095049 -6.131762)
			(xy 74.036687 -6.083376) (xy 73.983799 -6.02906) (xy 73.936984 -5.969431) (xy 73.896772 -5.905163)
			(xy 73.86362 -5.836986) (xy 73.837902 -5.76567) (xy 73.81991 -5.692025) (xy 73.809848 -5.616885)
			(xy 73.807829 -5.541101) (xy 72.691751 -5.541101) (xy 72.689732 -5.616885) (xy 72.67967 -5.692025)
			(xy 72.661678 -5.76567) (xy 72.63596 -5.836986) (xy 72.602808 -5.905163) (xy 72.562596 -5.969431)
			(xy 72.515781 -6.02906) (xy 72.462893 -6.083376) (xy 72.404531 -6.131762) (xy 72.341356 -6.17367)
			(xy 72.274085 -6.208626) (xy 72.20348 -6.236233) (xy 72.130339 -6.256179) (xy 72.055494 -6.268238)
			(xy 71.97979 -6.272273) (xy 71.904086 -6.268238) (xy 71.829241 -6.256179) (xy 71.7561 -6.236233)
			(xy 71.685495 -6.208626) (xy 71.618224 -6.17367) (xy 71.555049 -6.131762) (xy 71.496687 -6.083376)
			(xy 71.443799 -6.02906) (xy 71.396984 -5.969431) (xy 71.356772 -5.905163) (xy 71.32362 -5.836986)
			(xy 71.297902 -5.76567) (xy 71.27991 -5.692025) (xy 71.269848 -5.616885) (xy 71.267829 -5.541101)
			(xy 70.151751 -5.541101) (xy 70.149732 -5.616885) (xy 70.13967 -5.692025) (xy 70.121678 -5.76567)
			(xy 70.09596 -5.836986) (xy 70.062808 -5.905163) (xy 70.022596 -5.969431) (xy 69.975781 -6.02906)
			(xy 69.922893 -6.083376) (xy 69.864531 -6.131762) (xy 69.801356 -6.17367) (xy 69.734085 -6.208626)
			(xy 69.66348 -6.236233) (xy 69.590339 -6.256179) (xy 69.515494 -6.268238) (xy 69.43979 -6.272273)
			(xy 69.364086 -6.268238) (xy 69.289241 -6.256179) (xy 69.2161 -6.236233) (xy 69.145495 -6.208626)
			(xy 69.078224 -6.17367) (xy 69.015049 -6.131762) (xy 68.956687 -6.083376) (xy 68.903799 -6.02906)
			(xy 68.856984 -5.969431) (xy 68.816772 -5.905163) (xy 68.78362 -5.836986) (xy 68.757902 -5.76567)
			(xy 68.73991 -5.692025) (xy 68.729848 -5.616885) (xy 68.727829 -5.541101) (xy 67.611751 -5.541101)
			(xy 67.609732 -5.616885) (xy 67.59967 -5.692025) (xy 67.581678 -5.76567) (xy 67.55596 -5.836986)
			(xy 67.522808 -5.905163) (xy 67.482596 -5.969431) (xy 67.435781 -6.02906) (xy 67.382893 -6.083376)
			(xy 67.324531 -6.131762) (xy 67.261356 -6.17367) (xy 67.194085 -6.208626) (xy 67.12348 -6.236233)
			(xy 67.050339 -6.256179) (xy 66.975494 -6.268238) (xy 66.89979 -6.272273) (xy 66.824086 -6.268238)
			(xy 66.749241 -6.256179) (xy 66.6761 -6.236233) (xy 66.605495 -6.208626) (xy 66.538224 -6.17367)
			(xy 66.475049 -6.131762) (xy 66.416687 -6.083376) (xy 66.363799 -6.02906) (xy 66.316984 -5.969431)
			(xy 66.276772 -5.905163) (xy 66.24362 -5.836986) (xy 66.217902 -5.76567) (xy 66.19991 -5.692025)
			(xy 66.189848 -5.616885) (xy 66.187829 -5.541101) (xy 65.071751 -5.541101) (xy 65.069732 -5.616885)
			(xy 65.05967 -5.692025) (xy 65.041678 -5.76567) (xy 65.01596 -5.836986) (xy 64.982808 -5.905163)
			(xy 64.942596 -5.969431) (xy 64.895781 -6.02906) (xy 64.842893 -6.083376) (xy 64.784531 -6.131762)
			(xy 64.721356 -6.17367) (xy 64.654085 -6.208626) (xy 64.58348 -6.236233) (xy 64.510339 -6.256179)
			(xy 64.435494 -6.268238) (xy 64.35979 -6.272273) (xy 64.284086 -6.268238) (xy 64.209241 -6.256179)
			(xy 64.1361 -6.236233) (xy 64.065495 -6.208626) (xy 63.998224 -6.17367) (xy 63.935049 -6.131762)
			(xy 63.876687 -6.083376) (xy 63.823799 -6.02906) (xy 63.776984 -5.969431) (xy 63.736772 -5.905163)
			(xy 63.70362 -5.836986) (xy 63.677902 -5.76567) (xy 63.65991 -5.692025) (xy 63.649848 -5.616885)
			(xy 63.647829 -5.541101) (xy 42.474869 -5.541101) (xy 42.525479 -5.57734) (xy 42.614981 -5.651279)
			(xy 42.699169 -5.731217) (xy 42.777642 -5.816772) (xy 42.850025 -5.907538) (xy 42.915974 -6.003081)
			(xy 42.975174 -6.102946) (xy 43.027343 -6.206658) (xy 43.072232 -6.313721) (xy 43.109628 -6.423627)
			(xy 43.139353 -6.535851) (xy 43.161264 -6.649857) (xy 43.175257 -6.765104) (xy 43.181266 -6.881042)
			(xy 43.179263 -6.997118) (xy 43.169255 -7.11278) (xy 43.151292 -7.227475) (xy 43.125459 -7.340658)
			(xy 43.091879 -7.451789) (xy 43.050711 -7.560338) (xy 43.002153 -7.665788) (xy 42.946436 -7.767637)
			(xy 42.883824 -7.8654) (xy 42.814617 -7.95861) (xy 42.739144 -8.046823) (xy 42.657765 -8.129619)
			(xy 42.570868 -8.206603) (xy 42.526017 -8.241121) (xy 63.647829 -8.241121) (xy 63.653878 -8.165551)
			(xy 63.667925 -8.091053) (xy 63.689811 -8.01847) (xy 63.719288 -7.948624) (xy 63.756023 -7.882307)
			(xy 63.799598 -7.820271) (xy 63.84952 -7.763218) (xy 63.905224 -7.711794) (xy 63.966079 -7.666583)
			(xy 64.031394 -7.628096) (xy 64.10043 -7.59677) (xy 64.172405 -7.57296) (xy 64.246503 -7.556935)
			(xy 64.321884 -7.548876) (xy 64.35979 -7.548372) (xy 64.397696 -7.548876) (xy 64.473077 -7.556935)
			(xy 64.547175 -7.57296) (xy 64.61915 -7.59677) (xy 64.688186 -7.628096) (xy 64.753501 -7.666583)
			(xy 64.814356 -7.711794) (xy 64.87006 -7.763218) (xy 64.919982 -7.820271) (xy 64.963557 -7.882307)
			(xy 65.000292 -7.948624) (xy 65.029769 -8.01847) (xy 65.051655 -8.091053) (xy 65.065702 -8.165551)
			(xy 65.071751 -8.241121) (xy 66.187829 -8.241121) (xy 66.193878 -8.165551) (xy 66.207925 -8.091053)
			(xy 66.229811 -8.01847) (xy 66.259288 -7.948624) (xy 66.296023 -7.882307) (xy 66.339598 -7.820271)
			(xy 66.38952 -7.763218) (xy 66.445224 -7.711794) (xy 66.506079 -7.666583) (xy 66.571394 -7.628096)
			(xy 66.64043 -7.59677) (xy 66.712405 -7.57296) (xy 66.786503 -7.556935) (xy 66.861884 -7.548876)
			(xy 66.89979 -7.548372) (xy 66.937696 -7.548876) (xy 67.013077 -7.556935) (xy 67.087175 -7.57296)
			(xy 67.15915 -7.59677) (xy 67.228186 -7.628096) (xy 67.293501 -7.666583) (xy 67.354356 -7.711794)
			(xy 67.41006 -7.763218) (xy 67.459982 -7.820271) (xy 67.503557 -7.882307) (xy 67.540292 -7.948624)
			(xy 67.569769 -8.01847) (xy 67.591655 -8.091053) (xy 67.605702 -8.165551) (xy 67.611751 -8.241121)
			(xy 68.727829 -8.241121) (xy 68.733878 -8.165551) (xy 68.747925 -8.091053) (xy 68.769811 -8.01847)
			(xy 68.799288 -7.948624) (xy 68.836023 -7.882307) (xy 68.879598 -7.820271) (xy 68.92952 -7.763218)
			(xy 68.985224 -7.711794) (xy 69.046079 -7.666583) (xy 69.111394 -7.628096) (xy 69.18043 -7.59677)
			(xy 69.252405 -7.57296) (xy 69.326503 -7.556935) (xy 69.401884 -7.548876) (xy 69.43979 -7.548372)
			(xy 69.477696 -7.548876) (xy 69.553077 -7.556935) (xy 69.627175 -7.57296) (xy 69.69915 -7.59677)
			(xy 69.768186 -7.628096) (xy 69.833501 -7.666583) (xy 69.894356 -7.711794) (xy 69.95006 -7.763218)
			(xy 69.999982 -7.820271) (xy 70.043557 -7.882307) (xy 70.080292 -7.948624) (xy 70.109769 -8.01847)
			(xy 70.131655 -8.091053) (xy 70.145702 -8.165551) (xy 70.151751 -8.241121) (xy 71.267829 -8.241121)
			(xy 71.273878 -8.165551) (xy 71.287925 -8.091053) (xy 71.309811 -8.01847) (xy 71.339288 -7.948624)
			(xy 71.376023 -7.882307) (xy 71.419598 -7.820271) (xy 71.46952 -7.763218) (xy 71.525224 -7.711794)
			(xy 71.586079 -7.666583) (xy 71.651394 -7.628096) (xy 71.72043 -7.59677) (xy 71.792405 -7.57296)
			(xy 71.866503 -7.556935) (xy 71.941884 -7.548876) (xy 71.97979 -7.548372) (xy 72.017696 -7.548876)
			(xy 72.093077 -7.556935) (xy 72.167175 -7.57296) (xy 72.23915 -7.59677) (xy 72.308186 -7.628096)
			(xy 72.373501 -7.666583) (xy 72.434356 -7.711794) (xy 72.49006 -7.763218) (xy 72.539982 -7.820271)
			(xy 72.583557 -7.882307) (xy 72.620292 -7.948624) (xy 72.649769 -8.01847) (xy 72.671655 -8.091053)
			(xy 72.685702 -8.165551) (xy 72.691751 -8.241121) (xy 73.807829 -8.241121) (xy 73.813878 -8.165551)
			(xy 73.827925 -8.091053) (xy 73.849811 -8.01847) (xy 73.879288 -7.948624) (xy 73.916023 -7.882307)
			(xy 73.959598 -7.820271) (xy 74.00952 -7.763218) (xy 74.065224 -7.711794) (xy 74.126079 -7.666583)
			(xy 74.191394 -7.628096) (xy 74.26043 -7.59677) (xy 74.332405 -7.57296) (xy 74.406503 -7.556935)
			(xy 74.481884 -7.548876) (xy 74.51979 -7.548372) (xy 74.557696 -7.548876) (xy 74.633077 -7.556935)
			(xy 74.707175 -7.57296) (xy 74.77915 -7.59677) (xy 74.848186 -7.628096) (xy 74.913501 -7.666583)
			(xy 74.974356 -7.711794) (xy 75.03006 -7.763218) (xy 75.079982 -7.820271) (xy 75.123557 -7.882307)
			(xy 75.160292 -7.948624) (xy 75.189769 -8.01847) (xy 75.211655 -8.091053) (xy 75.225702 -8.165551)
			(xy 75.231751 -8.241121) (xy 76.347829 -8.241121) (xy 76.353878 -8.165551) (xy 76.367925 -8.091053)
			(xy 76.389811 -8.01847) (xy 76.419288 -7.948624) (xy 76.456023 -7.882307) (xy 76.499598 -7.820271)
			(xy 76.54952 -7.763218) (xy 76.605224 -7.711794) (xy 76.666079 -7.666583) (xy 76.731394 -7.628096)
			(xy 76.80043 -7.59677) (xy 76.872405 -7.57296) (xy 76.946503 -7.556935) (xy 77.021884 -7.548876)
			(xy 77.05979 -7.548372) (xy 77.097696 -7.548876) (xy 77.173077 -7.556935) (xy 77.247175 -7.57296)
			(xy 77.31915 -7.59677) (xy 77.388186 -7.628096) (xy 77.453501 -7.666583) (xy 77.514356 -7.711794)
			(xy 77.57006 -7.763218) (xy 77.619982 -7.820271) (xy 77.663557 -7.882307) (xy 77.700292 -7.948624)
			(xy 77.729769 -8.01847) (xy 77.751655 -8.091053) (xy 77.765702 -8.165551) (xy 77.771751 -8.241121)
			(xy 78.887829 -8.241121) (xy 78.893878 -8.165551) (xy 78.907925 -8.091053) (xy 78.929811 -8.01847)
			(xy 78.959288 -7.948624) (xy 78.996023 -7.882307) (xy 79.039598 -7.820271) (xy 79.08952 -7.763218)
			(xy 79.145224 -7.711794) (xy 79.206079 -7.666583) (xy 79.271394 -7.628096) (xy 79.34043 -7.59677)
			(xy 79.412405 -7.57296) (xy 79.486503 -7.556935) (xy 79.561884 -7.548876) (xy 79.59979 -7.548372)
			(xy 79.637696 -7.548876) (xy 79.713077 -7.556935) (xy 79.787175 -7.57296) (xy 79.85915 -7.59677)
			(xy 79.928186 -7.628096) (xy 79.993501 -7.666583) (xy 80.054356 -7.711794) (xy 80.11006 -7.763218)
			(xy 80.159982 -7.820271) (xy 80.203557 -7.882307) (xy 80.240292 -7.948624) (xy 80.269769 -8.01847)
			(xy 80.291655 -8.091053) (xy 80.305702 -8.165551) (xy 80.311751 -8.241121) (xy 81.427829 -8.241121)
			(xy 81.433878 -8.165551) (xy 81.447925 -8.091053) (xy 81.469811 -8.01847) (xy 81.499288 -7.948624)
			(xy 81.536023 -7.882307) (xy 81.579598 -7.820271) (xy 81.62952 -7.763218) (xy 81.685224 -7.711794)
			(xy 81.746079 -7.666583) (xy 81.811394 -7.628096) (xy 81.88043 -7.59677) (xy 81.952405 -7.57296)
			(xy 82.026503 -7.556935) (xy 82.101884 -7.548876) (xy 82.13979 -7.548372) (xy 82.177696 -7.548876)
			(xy 82.253077 -7.556935) (xy 82.327175 -7.57296) (xy 82.39915 -7.59677) (xy 82.468186 -7.628096)
			(xy 82.533501 -7.666583) (xy 82.594356 -7.711794) (xy 82.65006 -7.763218) (xy 82.699982 -7.820271)
			(xy 82.743557 -7.882307) (xy 82.780292 -7.948624) (xy 82.809769 -8.01847) (xy 82.831655 -8.091053)
			(xy 82.845702 -8.165551) (xy 82.851751 -8.241121) (xy 82.849732 -8.316905) (xy 82.83967 -8.392045)
			(xy 82.821678 -8.46569) (xy 82.79596 -8.537006) (xy 82.762808 -8.605183) (xy 82.722596 -8.669451)
			(xy 82.675781 -8.72908) (xy 82.622893 -8.783396) (xy 82.564531 -8.831782) (xy 82.501356 -8.87369)
			(xy 82.434085 -8.908646) (xy 82.36348 -8.936253) (xy 82.290339 -8.956199) (xy 82.215494 -8.968258)
			(xy 82.13979 -8.972293) (xy 82.064086 -8.968258) (xy 81.989241 -8.956199) (xy 81.9161 -8.936253)
			(xy 81.845495 -8.908646) (xy 81.778224 -8.87369) (xy 81.715049 -8.831782) (xy 81.656687 -8.783396)
			(xy 81.603799 -8.72908) (xy 81.556984 -8.669451) (xy 81.516772 -8.605183) (xy 81.48362 -8.537006)
			(xy 81.457902 -8.46569) (xy 81.43991 -8.392045) (xy 81.429848 -8.316905) (xy 81.427829 -8.241121)
			(xy 80.311751 -8.241121) (xy 80.309732 -8.316905) (xy 80.29967 -8.392045) (xy 80.281678 -8.46569)
			(xy 80.25596 -8.537006) (xy 80.222808 -8.605183) (xy 80.182596 -8.669451) (xy 80.135781 -8.72908)
			(xy 80.082893 -8.783396) (xy 80.024531 -8.831782) (xy 79.961356 -8.87369) (xy 79.894085 -8.908646)
			(xy 79.82348 -8.936253) (xy 79.750339 -8.956199) (xy 79.675494 -8.968258) (xy 79.59979 -8.972293)
			(xy 79.524086 -8.968258) (xy 79.449241 -8.956199) (xy 79.3761 -8.936253) (xy 79.305495 -8.908646)
			(xy 79.238224 -8.87369) (xy 79.175049 -8.831782) (xy 79.116687 -8.783396) (xy 79.063799 -8.72908)
			(xy 79.016984 -8.669451) (xy 78.976772 -8.605183) (xy 78.94362 -8.537006) (xy 78.917902 -8.46569)
			(xy 78.89991 -8.392045) (xy 78.889848 -8.316905) (xy 78.887829 -8.241121) (xy 77.771751 -8.241121)
			(xy 77.769732 -8.316905) (xy 77.75967 -8.392045) (xy 77.741678 -8.46569) (xy 77.71596 -8.537006)
			(xy 77.682808 -8.605183) (xy 77.642596 -8.669451) (xy 77.595781 -8.72908) (xy 77.542893 -8.783396)
			(xy 77.484531 -8.831782) (xy 77.421356 -8.87369) (xy 77.354085 -8.908646) (xy 77.28348 -8.936253)
			(xy 77.210339 -8.956199) (xy 77.135494 -8.968258) (xy 77.05979 -8.972293) (xy 76.984086 -8.968258)
			(xy 76.909241 -8.956199) (xy 76.8361 -8.936253) (xy 76.765495 -8.908646) (xy 76.698224 -8.87369)
			(xy 76.635049 -8.831782) (xy 76.576687 -8.783396) (xy 76.523799 -8.72908) (xy 76.476984 -8.669451)
			(xy 76.436772 -8.605183) (xy 76.40362 -8.537006) (xy 76.377902 -8.46569) (xy 76.35991 -8.392045)
			(xy 76.349848 -8.316905) (xy 76.347829 -8.241121) (xy 75.231751 -8.241121) (xy 75.229732 -8.316905)
			(xy 75.21967 -8.392045) (xy 75.201678 -8.46569) (xy 75.17596 -8.537006) (xy 75.142808 -8.605183)
			(xy 75.102596 -8.669451) (xy 75.055781 -8.72908) (xy 75.002893 -8.783396) (xy 74.944531 -8.831782)
			(xy 74.881356 -8.87369) (xy 74.814085 -8.908646) (xy 74.74348 -8.936253) (xy 74.670339 -8.956199)
			(xy 74.595494 -8.968258) (xy 74.51979 -8.972293) (xy 74.444086 -8.968258) (xy 74.369241 -8.956199)
			(xy 74.2961 -8.936253) (xy 74.225495 -8.908646) (xy 74.158224 -8.87369) (xy 74.095049 -8.831782)
			(xy 74.036687 -8.783396) (xy 73.983799 -8.72908) (xy 73.936984 -8.669451) (xy 73.896772 -8.605183)
			(xy 73.86362 -8.537006) (xy 73.837902 -8.46569) (xy 73.81991 -8.392045) (xy 73.809848 -8.316905)
			(xy 73.807829 -8.241121) (xy 72.691751 -8.241121) (xy 72.689732 -8.316905) (xy 72.67967 -8.392045)
			(xy 72.661678 -8.46569) (xy 72.63596 -8.537006) (xy 72.602808 -8.605183) (xy 72.562596 -8.669451)
			(xy 72.515781 -8.72908) (xy 72.462893 -8.783396) (xy 72.404531 -8.831782) (xy 72.341356 -8.87369)
			(xy 72.274085 -8.908646) (xy 72.20348 -8.936253) (xy 72.130339 -8.956199) (xy 72.055494 -8.968258)
			(xy 71.97979 -8.972293) (xy 71.904086 -8.968258) (xy 71.829241 -8.956199) (xy 71.7561 -8.936253)
			(xy 71.685495 -8.908646) (xy 71.618224 -8.87369) (xy 71.555049 -8.831782) (xy 71.496687 -8.783396)
			(xy 71.443799 -8.72908) (xy 71.396984 -8.669451) (xy 71.356772 -8.605183) (xy 71.32362 -8.537006)
			(xy 71.297902 -8.46569) (xy 71.27991 -8.392045) (xy 71.269848 -8.316905) (xy 71.267829 -8.241121)
			(xy 70.151751 -8.241121) (xy 70.149732 -8.316905) (xy 70.13967 -8.392045) (xy 70.121678 -8.46569)
			(xy 70.09596 -8.537006) (xy 70.062808 -8.605183) (xy 70.022596 -8.669451) (xy 69.975781 -8.72908)
			(xy 69.922893 -8.783396) (xy 69.864531 -8.831782) (xy 69.801356 -8.87369) (xy 69.734085 -8.908646)
			(xy 69.66348 -8.936253) (xy 69.590339 -8.956199) (xy 69.515494 -8.968258) (xy 69.43979 -8.972293)
			(xy 69.364086 -8.968258) (xy 69.289241 -8.956199) (xy 69.2161 -8.936253) (xy 69.145495 -8.908646)
			(xy 69.078224 -8.87369) (xy 69.015049 -8.831782) (xy 68.956687 -8.783396) (xy 68.903799 -8.72908)
			(xy 68.856984 -8.669451) (xy 68.816772 -8.605183) (xy 68.78362 -8.537006) (xy 68.757902 -8.46569)
			(xy 68.73991 -8.392045) (xy 68.729848 -8.316905) (xy 68.727829 -8.241121) (xy 67.611751 -8.241121)
			(xy 67.609732 -8.316905) (xy 67.59967 -8.392045) (xy 67.581678 -8.46569) (xy 67.55596 -8.537006)
			(xy 67.522808 -8.605183) (xy 67.482596 -8.669451) (xy 67.435781 -8.72908) (xy 67.382893 -8.783396)
			(xy 67.324531 -8.831782) (xy 67.261356 -8.87369) (xy 67.194085 -8.908646) (xy 67.12348 -8.936253)
			(xy 67.050339 -8.956199) (xy 66.975494 -8.968258) (xy 66.89979 -8.972293) (xy 66.824086 -8.968258)
			(xy 66.749241 -8.956199) (xy 66.6761 -8.936253) (xy 66.605495 -8.908646) (xy 66.538224 -8.87369)
			(xy 66.475049 -8.831782) (xy 66.416687 -8.783396) (xy 66.363799 -8.72908) (xy 66.316984 -8.669451)
			(xy 66.276772 -8.605183) (xy 66.24362 -8.537006) (xy 66.217902 -8.46569) (xy 66.19991 -8.392045)
			(xy 66.189848 -8.316905) (xy 66.187829 -8.241121) (xy 65.071751 -8.241121) (xy 65.069732 -8.316905)
			(xy 65.05967 -8.392045) (xy 65.041678 -8.46569) (xy 65.01596 -8.537006) (xy 64.982808 -8.605183)
			(xy 64.942596 -8.669451) (xy 64.895781 -8.72908) (xy 64.842893 -8.783396) (xy 64.784531 -8.831782)
			(xy 64.721356 -8.87369) (xy 64.654085 -8.908646) (xy 64.58348 -8.936253) (xy 64.510339 -8.956199)
			(xy 64.435494 -8.968258) (xy 64.35979 -8.972293) (xy 64.284086 -8.968258) (xy 64.209241 -8.956199)
			(xy 64.1361 -8.936253) (xy 64.065495 -8.908646) (xy 63.998224 -8.87369) (xy 63.935049 -8.831782)
			(xy 63.876687 -8.783396) (xy 63.823799 -8.72908) (xy 63.776984 -8.669451) (xy 63.736772 -8.605183)
			(xy 63.70362 -8.537006) (xy 63.677902 -8.46569) (xy 63.65991 -8.392045) (xy 63.649848 -8.316905)
			(xy 63.647829 -8.241121) (xy 42.526017 -8.241121) (xy 42.478867 -8.277408) (xy 42.3822 -8.341698)
			(xy 42.281328 -8.399165) (xy 42.176731 -8.449536) (xy 42.068908 -8.492571) (xy 41.958374 -8.528065)
			(xy 41.845654 -8.555848) (xy 41.731286 -8.575788) (xy 41.615814 -8.58779) (xy 41.49979 -8.591797)
			(xy 41.383766 -8.58779) (xy 41.268294 -8.575788) (xy 41.153926 -8.555848) (xy 41.041206 -8.528065)
			(xy 40.930672 -8.492571) (xy 40.822849 -8.449536) (xy 40.718252 -8.399165) (xy 40.61738 -8.341698)
			(xy 40.520713 -8.277408) (xy 40.428712 -8.206603) (xy 40.341815 -8.129619) (xy 40.260436 -8.046823)
			(xy 40.184963 -7.95861) (xy 40.115756 -7.8654) (xy 40.053144 -7.767637) (xy 39.997427 -7.665788)
			(xy 39.948869 -7.560338) (xy 39.907701 -7.451789) (xy 39.874121 -7.340658) (xy 39.848288 -7.227475)
			(xy 39.830325 -7.11278) (xy 39.820317 -6.997118) (xy 39.818314 -6.881042) (xy 36.445942 -6.881042)
			(xy 36.4555 -6.914635) (xy 36.471468 -7.000055) (xy 36.479486 -7.086584) (xy 36.479486 -7.173484)
			(xy 36.471468 -7.260013) (xy 36.4555 -7.345433) (xy 36.431719 -7.429015) (xy 36.400327 -7.510047)
			(xy 36.361593 -7.587836) (xy 36.315846 -7.66172) (xy 36.263477 -7.731067) (xy 36.204933 -7.795287)
			(xy 36.140713 -7.853831) (xy 36.071366 -7.9062) (xy 35.997482 -7.951947) (xy 35.919693 -7.990681)
			(xy 35.838661 -8.022073) (xy 35.755079 -8.045854) (xy 35.669659 -8.061822) (xy 35.58313 -8.06984)
			(xy 35.49623 -8.06984) (xy 35.409701 -8.061822) (xy 35.324281 -8.045854) (xy 35.240699 -8.022073)
			(xy 35.159667 -7.990681) (xy 35.081878 -7.951947) (xy 35.007994 -7.9062) (xy 34.938647 -7.853831)
			(xy 34.874427 -7.795287) (xy 34.815883 -7.731067) (xy 34.763514 -7.66172) (xy 34.717767 -7.587836)
			(xy 34.679033 -7.510047) (xy 34.647641 -7.429015) (xy 34.62386 -7.345433) (xy 34.607892 -7.260013)
			(xy 34.599874 -7.173484) (xy 31.399486 -7.173484) (xy 31.391468 -7.260013) (xy 31.3755 -7.345433)
			(xy 31.351719 -7.429015) (xy 31.320327 -7.510047) (xy 31.281593 -7.587836) (xy 31.235846 -7.66172)
			(xy 31.183477 -7.731067) (xy 31.124933 -7.795287) (xy 31.060713 -7.853831) (xy 30.991366 -7.9062)
			(xy 30.917482 -7.951947) (xy 30.839693 -7.990681) (xy 30.758661 -8.022073) (xy 30.675079 -8.045854)
			(xy 30.589659 -8.061822) (xy 30.50313 -8.06984) (xy 30.41623 -8.06984) (xy 30.329701 -8.061822) (xy 30.244281 -8.045854)
			(xy 30.160699 -8.022073) (xy 30.079667 -7.990681) (xy 30.001878 -7.951947) (xy 29.927994 -7.9062)
			(xy 29.858647 -7.853831) (xy 29.794427 -7.795287) (xy 29.735883 -7.731067) (xy 29.683514 -7.66172)
			(xy 29.637767 -7.587836) (xy 29.599033 -7.510047) (xy 29.567641 -7.429015) (xy 29.54386 -7.345433)
			(xy 29.527892 -7.260013) (xy 29.519874 -7.173484) (xy 0.509016 -7.173484) (xy 0.509016 -8.918617)
			(xy 4.94918 -8.918617) (xy 4.94918 -8.837507) (xy 4.95713 -8.756788) (xy 4.972953 -8.677237) (xy 4.996498 -8.599621)
			(xy 5.027537 -8.524685) (xy 5.065772 -8.453153) (xy 5.110834 -8.385713) (xy 5.162289 -8.323014) (xy 5.219642 -8.265661)
			(xy 5.282341 -8.214206) (xy 5.349781 -8.169144) (xy 5.421313 -8.130909) (xy 5.496249 -8.09987) (xy 5.573865 -8.076325)
			(xy 5.653416 -8.060502) (xy 5.734135 -8.052552) (xy 5.77469 -8.052054) (xy 5.815245 -8.052552) (xy 5.895964 -8.060502)
			(xy 5.975515 -8.076325) (xy 6.053131 -8.09987) (xy 6.128067 -8.130909) (xy 6.199599 -8.169144) (xy 6.267039 -8.214206)
			(xy 6.329738 -8.265661) (xy 6.387091 -8.323014) (xy 6.438546 -8.385713) (xy 6.483608 -8.453153) (xy 6.521843 -8.524685)
			(xy 6.552882 -8.599621) (xy 6.576427 -8.677237) (xy 6.59225 -8.756788) (xy 6.6002 -8.837507) (xy 6.6002 -8.918617)
			(xy 10.02918 -8.918617) (xy 10.02918 -8.837507) (xy 10.03713 -8.756788) (xy 10.052953 -8.677237)
			(xy 10.076498 -8.599621) (xy 10.107537 -8.524685) (xy 10.145772 -8.453153) (xy 10.190834 -8.385713)
			(xy 10.242289 -8.323014) (xy 10.299642 -8.265661) (xy 10.362341 -8.214206) (xy 10.429781 -8.169144)
			(xy 10.501313 -8.130909) (xy 10.576249 -8.09987) (xy 10.653865 -8.076325) (xy 10.733416 -8.060502)
			(xy 10.814135 -8.052552) (xy 10.85469 -8.052054) (xy 10.895245 -8.052552) (xy 10.975964 -8.060502)
			(xy 11.055515 -8.076325) (xy 11.133131 -8.09987) (xy 11.208067 -8.130909) (xy 11.279599 -8.169144)
			(xy 11.347039 -8.214206) (xy 11.409738 -8.265661) (xy 11.467091 -8.323014) (xy 11.518546 -8.385713)
			(xy 11.563608 -8.453153) (xy 11.601843 -8.524685) (xy 11.632882 -8.599621) (xy 11.656427 -8.677237)
			(xy 11.67225 -8.756788) (xy 11.6802 -8.837507) (xy 11.6802 -8.918617) (xy 12.56918 -8.918617) (xy 12.56918 -8.837507)
			(xy 12.57713 -8.756788) (xy 12.592953 -8.677237) (xy 12.616498 -8.599621) (xy 12.647537 -8.524685)
			(xy 12.685772 -8.453153) (xy 12.730834 -8.385713) (xy 12.782289 -8.323014) (xy 12.839642 -8.265661)
			(xy 12.902341 -8.214206) (xy 12.969781 -8.169144) (xy 13.041313 -8.130909) (xy 13.116249 -8.09987)
			(xy 13.193865 -8.076325) (xy 13.273416 -8.060502) (xy 13.354135 -8.052552) (xy 13.39469 -8.052054)
			(xy 13.435245 -8.052552) (xy 13.515964 -8.060502) (xy 13.595515 -8.076325) (xy 13.673131 -8.09987)
			(xy 13.748067 -8.130909) (xy 13.819599 -8.169144) (xy 13.887039 -8.214206) (xy 13.949738 -8.265661)
			(xy 14.007091 -8.323014) (xy 14.058546 -8.385713) (xy 14.103608 -8.453153) (xy 14.141843 -8.524685)
			(xy 14.172882 -8.599621) (xy 14.196427 -8.677237) (xy 14.21225 -8.756788) (xy 14.216166 -8.796546)
			(xy 26.805635 -8.796546) (xy 26.811735 -8.741109) (xy 26.825841 -8.687152) (xy 26.847653 -8.635823)
			(xy 26.876707 -8.588217) (xy 26.912382 -8.545349) (xy 26.953919 -8.508132) (xy 27.000432 -8.477359)
			(xy 27.050929 -8.453687) (xy 27.104336 -8.437619) (xy 27.159512 -8.429499) (xy 27.187398 -8.42899)
			(xy 27.215284 -8.429499) (xy 27.27046 -8.437619) (xy 27.323867 -8.453687) (xy 27.374364 -8.477359)
			(xy 27.420877 -8.508132) (xy 27.462414 -8.545349) (xy 27.498089 -8.588217) (xy 27.527143 -8.635823)
			(xy 27.548955 -8.687152) (xy 27.563061 -8.741109) (xy 27.569161 -8.796546) (xy 27.567124 -8.85228)
			(xy 27.556994 -8.907123) (xy 27.538987 -8.959907) (xy 27.513486 -9.009507) (xy 27.481035 -9.054865)
			(xy 27.442326 -9.095014) (xy 27.398183 -9.1291) (xy 27.349548 -9.156396) (xy 27.297457 -9.176319)
			(xy 27.24302 -9.188445) (xy 27.187398 -9.192516) (xy 27.131776 -9.188445) (xy 27.077339 -9.176319)
			(xy 27.025248 -9.156396) (xy 26.976613 -9.1291) (xy 26.93247 -9.095014) (xy 26.893761 -9.054865)
			(xy 26.86131 -9.009507) (xy 26.835809 -8.959907) (xy 26.817802 -8.907123) (xy 26.807672 -8.85228)
			(xy 26.805635 -8.796546) (xy 14.216166 -8.796546) (xy 14.2202 -8.837507) (xy 14.2202 -8.918617) (xy 14.21225 -8.999336)
			(xy 14.196427 -9.078887) (xy 14.172882 -9.156503) (xy 14.141843 -9.231439) (xy 14.103608 -9.302971)
			(xy 14.058546 -9.370411) (xy 14.007091 -9.43311) (xy 13.949738 -9.490463) (xy 13.887039 -9.541918)
			(xy 13.819599 -9.58698) (xy 13.748067 -9.625215) (xy 13.673131 -9.656254) (xy 13.595515 -9.679799)
			(xy 13.515964 -9.695622) (xy 13.435245 -9.703572) (xy 13.354135 -9.703572) (xy 13.273416 -9.695622)
			(xy 13.193865 -9.679799) (xy 13.116249 -9.656254) (xy 13.041313 -9.625215) (xy 12.969781 -9.58698)
			(xy 12.902341 -9.541918) (xy 12.839642 -9.490463) (xy 12.782289 -9.43311) (xy 12.730834 -9.370411)
			(xy 12.685772 -9.302971) (xy 12.647537 -9.231439) (xy 12.616498 -9.156503) (xy 12.592953 -9.078887)
			(xy 12.57713 -8.999336) (xy 12.56918 -8.918617) (xy 11.6802 -8.918617) (xy 11.67225 -8.999336) (xy 11.656427 -9.078887)
			(xy 11.632882 -9.156503) (xy 11.601843 -9.231439) (xy 11.563608 -9.302971) (xy 11.518546 -9.370411)
			(xy 11.467091 -9.43311) (xy 11.409738 -9.490463) (xy 11.347039 -9.541918) (xy 11.279599 -9.58698)
			(xy 11.208067 -9.625215) (xy 11.133131 -9.656254) (xy 11.055515 -9.679799) (xy 10.975964 -9.695622)
			(xy 10.895245 -9.703572) (xy 10.814135 -9.703572) (xy 10.733416 -9.695622) (xy 10.653865 -9.679799)
			(xy 10.576249 -9.656254) (xy 10.501313 -9.625215) (xy 10.429781 -9.58698) (xy 10.362341 -9.541918)
			(xy 10.299642 -9.490463) (xy 10.242289 -9.43311) (xy 10.190834 -9.370411) (xy 10.145772 -9.302971)
			(xy 10.107537 -9.231439) (xy 10.076498 -9.156503) (xy 10.052953 -9.078887) (xy 10.03713 -8.999336)
			(xy 10.02918 -8.918617) (xy 6.6002 -8.918617) (xy 6.59225 -8.999336) (xy 6.576427 -9.078887) (xy 6.552882 -9.156503)
			(xy 6.521843 -9.231439) (xy 6.483608 -9.302971) (xy 6.438546 -9.370411) (xy 6.387091 -9.43311) (xy 6.329738 -9.490463)
			(xy 6.267039 -9.541918) (xy 6.199599 -9.58698) (xy 6.128067 -9.625215) (xy 6.053131 -9.656254) (xy 5.975515 -9.679799)
			(xy 5.895964 -9.695622) (xy 5.815245 -9.703572) (xy 5.734135 -9.703572) (xy 5.653416 -9.695622) (xy 5.573865 -9.679799)
			(xy 5.496249 -9.656254) (xy 5.421313 -9.625215) (xy 5.349781 -9.58698) (xy 5.282341 -9.541918) (xy 5.219642 -9.490463)
			(xy 5.162289 -9.43311) (xy 5.110834 -9.370411) (xy 5.065772 -9.302971) (xy 5.027537 -9.231439) (xy 4.996498 -9.156503)
			(xy 4.972953 -9.078887) (xy 4.95713 -8.999336) (xy 4.94918 -8.918617) (xy 0.509016 -8.918617) (xy 0.509016 -9.713484)
			(xy 29.519874 -9.713484) (xy 29.519874 -9.626584) (xy 29.527892 -9.540055) (xy 29.54386 -9.454635)
			(xy 29.567641 -9.371053) (xy 29.599033 -9.290021) (xy 29.637767 -9.212232) (xy 29.683514 -9.138348)
			(xy 29.735883 -9.069001) (xy 29.794427 -9.004781) (xy 29.858647 -8.946237) (xy 29.927994 -8.893868)
			(xy 30.001878 -8.848121) (xy 30.079667 -8.809387) (xy 30.160699 -8.777995) (xy 30.244281 -8.754214)
			(xy 30.329701 -8.738246) (xy 30.41623 -8.730228) (xy 30.45968 -8.729726) (xy 30.50313 -8.730228)
			(xy 30.589659 -8.738246) (xy 30.675079 -8.754214) (xy 30.758661 -8.777995) (xy 30.839693 -8.809387)
			(xy 30.917482 -8.848121) (xy 30.991366 -8.893868) (xy 31.060713 -8.946237) (xy 31.124933 -9.004781)
			(xy 31.183477 -9.069001) (xy 31.235846 -9.138348) (xy 31.281593 -9.212232) (xy 31.320327 -9.290021)
			(xy 31.351719 -9.371053) (xy 31.3755 -9.454635) (xy 31.391468 -9.540055) (xy 31.399486 -9.626584)
			(xy 31.399486 -9.713484) (xy 34.599874 -9.713484) (xy 34.599874 -9.626584) (xy 34.607892 -9.540055)
			(xy 34.62386 -9.454635) (xy 34.647641 -9.371053) (xy 34.679033 -9.290021) (xy 34.717767 -9.212232)
			(xy 34.763514 -9.138348) (xy 34.815883 -9.069001) (xy 34.874427 -9.004781) (xy 34.938647 -8.946237)
			(xy 35.007994 -8.893868) (xy 35.081878 -8.848121) (xy 35.159667 -8.809387) (xy 35.240699 -8.777995)
			(xy 35.324281 -8.754214) (xy 35.409701 -8.738246) (xy 35.49623 -8.730228) (xy 35.53968 -8.729726)
			(xy 35.58313 -8.730228) (xy 35.669659 -8.738246) (xy 35.755079 -8.754214) (xy 35.838661 -8.777995)
			(xy 35.919693 -8.809387) (xy 35.997482 -8.848121) (xy 36.071366 -8.893868) (xy 36.140713 -8.946237)
			(xy 36.204933 -9.004781) (xy 36.263477 -9.069001) (xy 36.315846 -9.138348) (xy 36.361593 -9.212232)
			(xy 36.400327 -9.290021) (xy 36.431719 -9.371053) (xy 36.4555 -9.454635) (xy 36.471468 -9.540055)
			(xy 36.479486 -9.626584) (xy 36.479486 -9.713484) (xy 36.471468 -9.800013) (xy 36.4555 -9.885433)
			(xy 36.431719 -9.969015) (xy 36.400327 -10.050047) (xy 36.361593 -10.127836) (xy 36.315846 -10.20172)
			(xy 36.263477 -10.271067) (xy 36.204933 -10.335287) (xy 36.140713 -10.393831) (xy 36.071366 -10.4462)
			(xy 35.997482 -10.491947) (xy 35.919693 -10.530681) (xy 35.838661 -10.562073) (xy 35.755079 -10.585854)
			(xy 35.669659 -10.601822) (xy 35.58313 -10.60984) (xy 35.49623 -10.60984) (xy 35.409701 -10.601822)
			(xy 35.324281 -10.585854) (xy 35.240699 -10.562073) (xy 35.159667 -10.530681) (xy 35.081878 -10.491947)
			(xy 35.007994 -10.4462) (xy 34.938647 -10.393831) (xy 34.874427 -10.335287) (xy 34.815883 -10.271067)
			(xy 34.763514 -10.20172) (xy 34.717767 -10.127836) (xy 34.679033 -10.050047) (xy 34.647641 -9.969015)
			(xy 34.62386 -9.885433) (xy 34.607892 -9.800013) (xy 34.599874 -9.713484) (xy 31.399486 -9.713484)
			(xy 31.391468 -9.800013) (xy 31.3755 -9.885433) (xy 31.351719 -9.969015) (xy 31.320327 -10.050047)
			(xy 31.281593 -10.127836) (xy 31.235846 -10.20172) (xy 31.183477 -10.271067) (xy 31.124933 -10.335287)
			(xy 31.060713 -10.393831) (xy 30.991366 -10.4462) (xy 30.917482 -10.491947) (xy 30.839693 -10.530681)
			(xy 30.758661 -10.562073) (xy 30.675079 -10.585854) (xy 30.589659 -10.601822) (xy 30.50313 -10.60984)
			(xy 30.41623 -10.60984) (xy 30.329701 -10.601822) (xy 30.244281 -10.585854) (xy 30.160699 -10.562073)
			(xy 30.079667 -10.530681) (xy 30.001878 -10.491947) (xy 29.927994 -10.4462) (xy 29.858647 -10.393831)
			(xy 29.794427 -10.335287) (xy 29.735883 -10.271067) (xy 29.683514 -10.20172) (xy 29.637767 -10.127836)
			(xy 29.599033 -10.050047) (xy 29.567641 -9.969015) (xy 29.54386 -9.885433) (xy 29.527892 -9.800013)
			(xy 29.519874 -9.713484) (xy 0.509016 -9.713484) (xy 0.509016 -10.60401) (xy 25.381457 -10.60401)
			(xy 25.387557 -10.548573) (xy 25.401663 -10.494616) (xy 25.423475 -10.443287) (xy 25.452529 -10.395681)
			(xy 25.488204 -10.352813) (xy 25.529741 -10.315596) (xy 25.576254 -10.284823) (xy 25.626751 -10.261151)
			(xy 25.680158 -10.245083) (xy 25.735334 -10.236963) (xy 25.76322 -10.236454) (xy 25.791106 -10.236963)
			(xy 25.846282 -10.245083) (xy 25.899689 -10.261151) (xy 25.950186 -10.284823) (xy 25.996699 -10.315596)
			(xy 26.038236 -10.352813) (xy 26.073911 -10.395681) (xy 26.102965 -10.443287) (xy 26.124777 -10.494616)
			(xy 26.138883 -10.548573) (xy 26.144983 -10.60401) (xy 26.142946 -10.659744) (xy 26.132816 -10.714587)
			(xy 26.114809 -10.767371) (xy 26.089308 -10.816971) (xy 26.056857 -10.862329) (xy 26.018148 -10.902478)
			(xy 25.974005 -10.936564) (xy 25.92537 -10.96386) (xy 25.873279 -10.983783) (xy 25.818842 -10.995909)
			(xy 25.76322 -10.99998) (xy 25.707598 -10.995909) (xy 25.653161 -10.983783) (xy 25.60107 -10.96386)
			(xy 25.552435 -10.936564) (xy 25.508292 -10.902478) (xy 25.469583 -10.862329) (xy 25.437132 -10.816971)
			(xy 25.411631 -10.767371) (xy 25.393624 -10.714587) (xy 25.383494 -10.659744) (xy 25.381457 -10.60401)
			(xy 0.509016 -10.60401) (xy 0.509016 -12.253484) (xy 29.519874 -12.253484) (xy 29.519874 -12.166584)
			(xy 29.527892 -12.080055) (xy 29.54386 -11.994635) (xy 29.567641 -11.911053) (xy 29.599033 -11.830021)
			(xy 29.637767 -11.752232) (xy 29.683514 -11.678348) (xy 29.735883 -11.609001) (xy 29.794427 -11.544781)
			(xy 29.858647 -11.486237) (xy 29.927994 -11.433868) (xy 30.001878 -11.388121) (xy 30.079667 -11.349387)
			(xy 30.160699 -11.317995) (xy 30.244281 -11.294214) (xy 30.329701 -11.278246) (xy 30.41623 -11.270228)
			(xy 30.45968 -11.269726) (xy 30.50313 -11.270228) (xy 30.589659 -11.278246) (xy 30.675079 -11.294214)
			(xy 30.758661 -11.317995) (xy 30.839693 -11.349387) (xy 30.917482 -11.388121) (xy 30.991366 -11.433868)
			(xy 31.060713 -11.486237) (xy 31.124933 -11.544781) (xy 31.183477 -11.609001) (xy 31.235846 -11.678348)
			(xy 31.281593 -11.752232) (xy 31.320327 -11.830021) (xy 31.351719 -11.911053) (xy 31.3755 -11.994635)
			(xy 31.391468 -12.080055) (xy 31.399486 -12.166584) (xy 31.399486 -12.253484) (xy 34.599874 -12.253484)
			(xy 34.599874 -12.166584) (xy 34.607892 -12.080055) (xy 34.62386 -11.994635) (xy 34.647641 -11.911053)
			(xy 34.679033 -11.830021) (xy 34.717767 -11.752232) (xy 34.763514 -11.678348) (xy 34.815883 -11.609001)
			(xy 34.874427 -11.544781) (xy 34.938647 -11.486237) (xy 35.007994 -11.433868) (xy 35.081878 -11.388121)
			(xy 35.159667 -11.349387) (xy 35.240699 -11.317995) (xy 35.324281 -11.294214) (xy 35.409701 -11.278246)
			(xy 35.49623 -11.270228) (xy 35.53968 -11.269726) (xy 35.58313 -11.270228) (xy 35.669659 -11.278246)
			(xy 35.755079 -11.294214) (xy 35.838661 -11.317995) (xy 35.919693 -11.349387) (xy 35.997482 -11.388121)
			(xy 36.071366 -11.433868) (xy 36.140713 -11.486237) (xy 36.204933 -11.544781) (xy 36.263477 -11.609001)
			(xy 36.264948 -11.610949) (xy 64.532756 -11.610949) (xy 64.532756 -11.539627) (xy 64.540742 -11.468753)
			(xy 64.556612 -11.399218) (xy 64.580169 -11.331898) (xy 64.611114 -11.267639) (xy 64.64906 -11.207248)
			(xy 64.693529 -11.151486) (xy 64.743962 -11.101053) (xy 64.799724 -11.056584) (xy 64.860115 -11.018638)
			(xy 64.924374 -10.987693) (xy 64.991694 -10.964136) (xy 65.061229 -10.948266) (xy 65.132103 -10.94028)
			(xy 65.167764 -10.93978) (xy 65.203425 -10.94028) (xy 65.274299 -10.948266) (xy 65.343834 -10.964136)
			(xy 65.411154 -10.987693) (xy 65.475413 -11.018638) (xy 65.535804 -11.056584) (xy 65.591566 -11.101053)
			(xy 65.641999 -11.151486) (xy 65.686468 -11.207248) (xy 65.724414 -11.267639) (xy 65.755359 -11.331898)
			(xy 65.778916 -11.399218) (xy 65.794786 -11.468753) (xy 65.802772 -11.539627) (xy 65.802772 -11.610949)
			(xy 66.447408 -11.610949) (xy 66.447408 -11.539627) (xy 66.455394 -11.468753) (xy 66.471264 -11.399218)
			(xy 66.494821 -11.331898) (xy 66.525766 -11.267639) (xy 66.563712 -11.207248) (xy 66.608181 -11.151486)
			(xy 66.658614 -11.101053) (xy 66.714376 -11.056584) (xy 66.774767 -11.018638) (xy 66.839026 -10.987693)
			(xy 66.906346 -10.964136) (xy 66.975881 -10.948266) (xy 67.046755 -10.94028) (xy 67.082416 -10.93978)
			(xy 67.118077 -10.94028) (xy 67.188951 -10.948266) (xy 67.258486 -10.964136) (xy 67.325806 -10.987693)
			(xy 67.390065 -11.018638) (xy 67.450456 -11.056584) (xy 67.506218 -11.101053) (xy 67.556651 -11.151486)
			(xy 67.60112 -11.207248) (xy 67.639066 -11.267639) (xy 67.670011 -11.331898) (xy 67.693568 -11.399218)
			(xy 67.709438 -11.468753) (xy 67.717424 -11.539627) (xy 67.717424 -11.610949) (xy 68.34428 -11.610949)
			(xy 68.34428 -11.539627) (xy 68.352266 -11.468753) (xy 68.368136 -11.399218) (xy 68.391693 -11.331898)
			(xy 68.422638 -11.267639) (xy 68.460584 -11.207248) (xy 68.505053 -11.151486) (xy 68.555486 -11.101053)
			(xy 68.611248 -11.056584) (xy 68.671639 -11.018638) (xy 68.735898 -10.987693) (xy 68.803218 -10.964136)
			(xy 68.872753 -10.948266) (xy 68.943627 -10.94028) (xy 68.979288 -10.93978) (xy 69.014949 -10.94028)
			(xy 69.085823 -10.948266) (xy 69.155358 -10.964136) (xy 69.222678 -10.987693) (xy 69.286937 -11.018638)
			(xy 69.347328 -11.056584) (xy 69.40309 -11.101053) (xy 69.453523 -11.151486) (xy 69.497992 -11.207248)
			(xy 69.535938 -11.267639) (xy 69.566883 -11.331898) (xy 69.59044 -11.399218) (xy 69.60631 -11.468753)
			(xy 69.614296 -11.539627) (xy 69.614296 -11.610949) (xy 70.422508 -11.610949) (xy 70.422508 -11.539627)
			(xy 70.430494 -11.468753) (xy 70.446364 -11.399218) (xy 70.469921 -11.331898) (xy 70.500866 -11.267639)
			(xy 70.538812 -11.207248) (xy 70.583281 -11.151486) (xy 70.633714 -11.101053) (xy 70.689476 -11.056584)
			(xy 70.749867 -11.018638) (xy 70.814126 -10.987693) (xy 70.881446 -10.964136) (xy 70.950981 -10.948266)
			(xy 71.021855 -10.94028) (xy 71.057516 -10.93978) (xy 71.093177 -10.94028) (xy 71.164051 -10.948266)
			(xy 71.233586 -10.964136) (xy 71.300906 -10.987693) (xy 71.365165 -11.018638) (xy 71.425556 -11.056584)
			(xy 71.481318 -11.101053) (xy 71.531751 -11.151486) (xy 71.57622 -11.207248) (xy 71.614166 -11.267639)
			(xy 71.645111 -11.331898) (xy 71.668668 -11.399218) (xy 71.684538 -11.468753) (xy 71.692524 -11.539627)
			(xy 71.692524 -11.610949) (xy 72.5429 -11.610949) (xy 72.5429 -11.539627) (xy 72.550886 -11.468753)
			(xy 72.566756 -11.399218) (xy 72.590313 -11.331898) (xy 72.621258 -11.267639) (xy 72.659204 -11.207248)
			(xy 72.703673 -11.151486) (xy 72.754106 -11.101053) (xy 72.809868 -11.056584) (xy 72.870259 -11.018638)
			(xy 72.934518 -10.987693) (xy 73.001838 -10.964136) (xy 73.071373 -10.948266) (xy 73.142247 -10.94028)
			(xy 73.177908 -10.93978) (xy 73.213569 -10.94028) (xy 73.284443 -10.948266) (xy 73.353978 -10.964136)
			(xy 73.421298 -10.987693) (xy 73.485557 -11.018638) (xy 73.545948 -11.056584) (xy 73.60171 -11.101053)
			(xy 73.652143 -11.151486) (xy 73.696612 -11.207248) (xy 73.734558 -11.267639) (xy 73.765503 -11.331898)
			(xy 73.78906 -11.399218) (xy 73.80493 -11.468753) (xy 73.812916 -11.539627) (xy 73.812916 -11.610949)
			(xy 73.80493 -11.681823) (xy 73.78906 -11.751358) (xy 73.765503 -11.818678) (xy 73.734558 -11.882937)
			(xy 73.696612 -11.943328) (xy 73.652143 -11.99909) (xy 73.60171 -12.049523) (xy 73.545948 -12.093992)
			(xy 73.485557 -12.131938) (xy 73.421298 -12.162883) (xy 73.353978 -12.18644) (xy 73.284443 -12.20231)
			(xy 73.213569 -12.210296) (xy 73.142247 -12.210296) (xy 73.071373 -12.20231) (xy 73.001838 -12.18644)
			(xy 72.934518 -12.162883) (xy 72.870259 -12.131938) (xy 72.809868 -12.093992) (xy 72.754106 -12.049523)
			(xy 72.703673 -11.99909) (xy 72.659204 -11.943328) (xy 72.621258 -11.882937) (xy 72.590313 -11.818678)
			(xy 72.566756 -11.751358) (xy 72.550886 -11.681823) (xy 72.5429 -11.610949) (xy 71.692524 -11.610949)
			(xy 71.684538 -11.681823) (xy 71.668668 -11.751358) (xy 71.645111 -11.818678) (xy 71.614166 -11.882937)
			(xy 71.57622 -11.943328) (xy 71.531751 -11.99909) (xy 71.481318 -12.049523) (xy 71.425556 -12.093992)
			(xy 71.365165 -12.131938) (xy 71.300906 -12.162883) (xy 71.233586 -12.18644) (xy 71.164051 -12.20231)
			(xy 71.093177 -12.210296) (xy 71.021855 -12.210296) (xy 70.950981 -12.20231) (xy 70.881446 -12.18644)
			(xy 70.814126 -12.162883) (xy 70.749867 -12.131938) (xy 70.689476 -12.093992) (xy 70.633714 -12.049523)
			(xy 70.583281 -11.99909) (xy 70.538812 -11.943328) (xy 70.500866 -11.882937) (xy 70.469921 -11.818678)
			(xy 70.446364 -11.751358) (xy 70.430494 -11.681823) (xy 70.422508 -11.610949) (xy 69.614296 -11.610949)
			(xy 69.60631 -11.681823) (xy 69.59044 -11.751358) (xy 69.566883 -11.818678) (xy 69.535938 -11.882937)
			(xy 69.497992 -11.943328) (xy 69.453523 -11.99909) (xy 69.40309 -12.049523) (xy 69.347328 -12.093992)
			(xy 69.286937 -12.131938) (xy 69.222678 -12.162883) (xy 69.155358 -12.18644) (xy 69.085823 -12.20231)
			(xy 69.014949 -12.210296) (xy 68.943627 -12.210296) (xy 68.872753 -12.20231) (xy 68.803218 -12.18644)
			(xy 68.735898 -12.162883) (xy 68.671639 -12.131938) (xy 68.611248 -12.093992) (xy 68.555486 -12.049523)
			(xy 68.505053 -11.99909) (xy 68.460584 -11.943328) (xy 68.422638 -11.882937) (xy 68.391693 -11.818678)
			(xy 68.368136 -11.751358) (xy 68.352266 -11.681823) (xy 68.34428 -11.610949) (xy 67.717424 -11.610949)
			(xy 67.709438 -11.681823) (xy 67.693568 -11.751358) (xy 67.670011 -11.818678) (xy 67.639066 -11.882937)
			(xy 67.60112 -11.943328) (xy 67.556651 -11.99909) (xy 67.506218 -12.049523) (xy 67.450456 -12.093992)
			(xy 67.390065 -12.131938) (xy 67.325806 -12.162883) (xy 67.258486 -12.18644) (xy 67.188951 -12.20231)
			(xy 67.118077 -12.210296) (xy 67.046755 -12.210296) (xy 66.975881 -12.20231) (xy 66.906346 -12.18644)
			(xy 66.839026 -12.162883) (xy 66.774767 -12.131938) (xy 66.714376 -12.093992) (xy 66.658614 -12.049523)
			(xy 66.608181 -11.99909) (xy 66.563712 -11.943328) (xy 66.525766 -11.882937) (xy 66.494821 -11.818678)
			(xy 66.471264 -11.751358) (xy 66.455394 -11.681823) (xy 66.447408 -11.610949) (xy 65.802772 -11.610949)
			(xy 65.794786 -11.681823) (xy 65.778916 -11.751358) (xy 65.755359 -11.818678) (xy 65.724414 -11.882937)
			(xy 65.686468 -11.943328) (xy 65.641999 -11.99909) (xy 65.591566 -12.049523) (xy 65.535804 -12.093992)
			(xy 65.475413 -12.131938) (xy 65.411154 -12.162883) (xy 65.343834 -12.18644) (xy 65.274299 -12.20231)
			(xy 65.203425 -12.210296) (xy 65.132103 -12.210296) (xy 65.061229 -12.20231) (xy 64.991694 -12.18644)
			(xy 64.924374 -12.162883) (xy 64.860115 -12.131938) (xy 64.799724 -12.093992) (xy 64.743962 -12.049523)
			(xy 64.693529 -11.99909) (xy 64.64906 -11.943328) (xy 64.611114 -11.882937) (xy 64.580169 -11.818678)
			(xy 64.556612 -11.751358) (xy 64.540742 -11.681823) (xy 64.532756 -11.610949) (xy 36.264948 -11.610949)
			(xy 36.315846 -11.678348) (xy 36.361593 -11.752232) (xy 36.400327 -11.830021) (xy 36.431719 -11.911053)
			(xy 36.4555 -11.994635) (xy 36.471468 -12.080055) (xy 36.479486 -12.166584) (xy 36.479486 -12.253484)
			(xy 36.471468 -12.340013) (xy 36.4555 -12.425433) (xy 36.431719 -12.509015) (xy 36.400327 -12.590047)
			(xy 36.361593 -12.667836) (xy 36.315846 -12.74172) (xy 36.263477 -12.811067) (xy 36.204933 -12.875287)
			(xy 36.140713 -12.933831) (xy 36.071366 -12.9862) (xy 35.997482 -13.031947) (xy 35.964737 -13.048252)
			(xy 39.637969 -13.048252) (xy 39.644069 -12.992815) (xy 39.658175 -12.938858) (xy 39.679987 -12.887529)
			(xy 39.709041 -12.839923) (xy 39.744716 -12.797055) (xy 39.786253 -12.759838) (xy 39.832766 -12.729065)
			(xy 39.883263 -12.705393) (xy 39.93667 -12.689325) (xy 39.991846 -12.681205) (xy 40.019732 -12.680696)
			(xy 40.047618 -12.681205) (xy 40.102794 -12.689325) (xy 40.156201 -12.705393) (xy 40.206698 -12.729065)
			(xy 40.253211 -12.759838) (xy 40.294748 -12.797055) (xy 40.330423 -12.839923) (xy 40.359477 -12.887529)
			(xy 40.381289 -12.938858) (xy 40.395395 -12.992815) (xy 40.40102 -13.043934) (xy 83.794599 -13.043934)
			(xy 83.800699 -12.988497) (xy 83.814805 -12.93454) (xy 83.836617 -12.883211) (xy 83.865671 -12.835605)
			(xy 83.901346 -12.792737) (xy 83.942883 -12.75552) (xy 83.989396 -12.724747) (xy 84.039893 -12.701075)
			(xy 84.0933 -12.685007) (xy 84.148476 -12.676887) (xy 84.176362 -12.676378) (xy 84.204248 -12.676887)
			(xy 84.259424 -12.685007) (xy 84.312831 -12.701075) (xy 84.363328 -12.724747) (xy 84.409841 -12.75552)
			(xy 84.451378 -12.792737) (xy 84.487053 -12.835605) (xy 84.516107 -12.883211) (xy 84.537919 -12.93454)
			(xy 84.552025 -12.988497) (xy 84.558125 -13.043934) (xy 84.556547 -13.087114) (xy 86.072979 -13.087114)
			(xy 86.079079 -13.031677) (xy 86.093185 -12.97772) (xy 86.114997 -12.926391) (xy 86.144051 -12.878785)
			(xy 86.179726 -12.835917) (xy 86.221263 -12.7987) (xy 86.267776 -12.767927) (xy 86.318273 -12.744255)
			(xy 86.37168 -12.728187) (xy 86.426856 -12.720067) (xy 86.454742 -12.719558) (xy 86.482628 -12.720067)
			(xy 86.537804 -12.728187) (xy 86.591211 -12.744255) (xy 86.641708 -12.767927) (xy 86.688221 -12.7987)
			(xy 86.729758 -12.835917) (xy 86.765433 -12.878785) (xy 86.781585 -12.90525) (xy 88.083643 -12.90525)
			(xy 88.089743 -12.849813) (xy 88.103849 -12.795856) (xy 88.125661 -12.744527) (xy 88.154715 -12.696921)
			(xy 88.19039 -12.654053) (xy 88.231927 -12.616836) (xy 88.27844 -12.586063) (xy 88.328937 -12.562391)
			(xy 88.382344 -12.546323) (xy 88.43752 -12.538203) (xy 88.465406 -12.537694) (xy 88.493292 -12.538203)
			(xy 88.548468 -12.546323) (xy 88.601875 -12.562391) (xy 88.652372 -12.586063) (xy 88.698885 -12.616836)
			(xy 88.740422 -12.654053) (xy 88.776097 -12.696921) (xy 88.805151 -12.744527) (xy 88.826963 -12.795856)
			(xy 88.841069 -12.849813) (xy 88.847169 -12.90525) (xy 88.845132 -12.960984) (xy 88.835002 -13.015827)
			(xy 88.816995 -13.068611) (xy 88.791494 -13.118211) (xy 88.759043 -13.163569) (xy 88.720334 -13.203718)
			(xy 88.676191 -13.237804) (xy 88.627556 -13.2651) (xy 88.575465 -13.285023) (xy 88.521028 -13.297149)
			(xy 88.465406 -13.30122) (xy 88.409784 -13.297149) (xy 88.355347 -13.285023) (xy 88.303256 -13.2651)
			(xy 88.254621 -13.237804) (xy 88.210478 -13.203718) (xy 88.171769 -13.163569) (xy 88.139318 -13.118211)
			(xy 88.113817 -13.068611) (xy 88.09581 -13.015827) (xy 88.08568 -12.960984) (xy 88.083643 -12.90525)
			(xy 86.781585 -12.90525) (xy 86.794487 -12.926391) (xy 86.816299 -12.97772) (xy 86.830405 -13.031677)
			(xy 86.836505 -13.087114) (xy 86.834468 -13.142848) (xy 86.824338 -13.197691) (xy 86.806331 -13.250475)
			(xy 86.78083 -13.300075) (xy 86.748379 -13.345433) (xy 86.70967 -13.385582) (xy 86.665527 -13.419668)
			(xy 86.616892 -13.446964) (xy 86.564801 -13.466887) (xy 86.510364 -13.479013) (xy 86.454742 -13.483084)
			(xy 86.39912 -13.479013) (xy 86.344683 -13.466887) (xy 86.292592 -13.446964) (xy 86.243957 -13.419668)
			(xy 86.199814 -13.385582) (xy 86.161105 -13.345433) (xy 86.128654 -13.300075) (xy 86.103153 -13.250475)
			(xy 86.085146 -13.197691) (xy 86.075016 -13.142848) (xy 86.072979 -13.087114) (xy 84.556547 -13.087114)
			(xy 84.556088 -13.099668) (xy 84.545958 -13.154511) (xy 84.527951 -13.207295) (xy 84.50245 -13.256895)
			(xy 84.469999 -13.302253) (xy 84.43129 -13.342402) (xy 84.387147 -13.376488) (xy 84.338512 -13.403784)
			(xy 84.286421 -13.423707) (xy 84.231984 -13.435833) (xy 84.176362 -13.439904) (xy 84.12074 -13.435833)
			(xy 84.066303 -13.423707) (xy 84.014212 -13.403784) (xy 83.965577 -13.376488) (xy 83.921434 -13.342402)
			(xy 83.882725 -13.302253) (xy 83.850274 -13.256895) (xy 83.824773 -13.207295) (xy 83.806766 -13.154511)
			(xy 83.796636 -13.099668) (xy 83.794599 -13.043934) (xy 40.40102 -13.043934) (xy 40.401495 -13.048252)
			(xy 40.399458 -13.103986) (xy 40.389328 -13.158829) (xy 40.371321 -13.211613) (xy 40.34582 -13.261213)
			(xy 40.313369 -13.306571) (xy 40.27466 -13.34672) (xy 40.230517 -13.380806) (xy 40.181882 -13.408102)
			(xy 40.129791 -13.428025) (xy 40.075354 -13.440151) (xy 40.019732 -13.444222) (xy 39.96411 -13.440151)
			(xy 39.909673 -13.428025) (xy 39.857582 -13.408102) (xy 39.808947 -13.380806) (xy 39.764804 -13.34672)
			(xy 39.726095 -13.306571) (xy 39.693644 -13.261213) (xy 39.668143 -13.211613) (xy 39.650136 -13.158829)
			(xy 39.640006 -13.103986) (xy 39.637969 -13.048252) (xy 35.964737 -13.048252) (xy 35.919693 -13.070681)
			(xy 35.838661 -13.102073) (xy 35.755079 -13.125854) (xy 35.669659 -13.141822) (xy 35.58313 -13.14984)
			(xy 35.49623 -13.14984) (xy 35.409701 -13.141822) (xy 35.324281 -13.125854) (xy 35.240699 -13.102073)
			(xy 35.159667 -13.070681) (xy 35.081878 -13.031947) (xy 35.007994 -12.9862) (xy 34.938647 -12.933831)
			(xy 34.874427 -12.875287) (xy 34.815883 -12.811067) (xy 34.763514 -12.74172) (xy 34.717767 -12.667836)
			(xy 34.679033 -12.590047) (xy 34.647641 -12.509015) (xy 34.62386 -12.425433) (xy 34.607892 -12.340013)
			(xy 34.599874 -12.253484) (xy 31.399486 -12.253484) (xy 31.391468 -12.340013) (xy 31.3755 -12.425433)
			(xy 31.351719 -12.509015) (xy 31.320327 -12.590047) (xy 31.281593 -12.667836) (xy 31.235846 -12.74172)
			(xy 31.183477 -12.811067) (xy 31.124933 -12.875287) (xy 31.060713 -12.933831) (xy 30.991366 -12.9862)
			(xy 30.917482 -13.031947) (xy 30.839693 -13.070681) (xy 30.758661 -13.102073) (xy 30.675079 -13.125854)
			(xy 30.589659 -13.141822) (xy 30.50313 -13.14984) (xy 30.41623 -13.14984) (xy 30.329701 -13.141822)
			(xy 30.244281 -13.125854) (xy 30.160699 -13.102073) (xy 30.079667 -13.070681) (xy 30.001878 -13.031947)
			(xy 29.927994 -12.9862) (xy 29.858647 -12.933831) (xy 29.794427 -12.875287) (xy 29.735883 -12.811067)
			(xy 29.683514 -12.74172) (xy 29.637767 -12.667836) (xy 29.599033 -12.590047) (xy 29.567641 -12.509015)
			(xy 29.54386 -12.425433) (xy 29.527892 -12.340013) (xy 29.519874 -12.253484) (xy 0.509016 -12.253484)
			(xy 0.509016 -12.66014) (xy 26.899107 -12.66014) (xy 26.905207 -12.604703) (xy 26.919313 -12.550746)
			(xy 26.941125 -12.499417) (xy 26.970179 -12.451811) (xy 27.005854 -12.408943) (xy 27.047391 -12.371726)
			(xy 27.093904 -12.340953) (xy 27.144401 -12.317281) (xy 27.197808 -12.301213) (xy 27.252984 -12.293093)
			(xy 27.28087 -12.292584) (xy 27.308756 -12.293093) (xy 27.363932 -12.301213) (xy 27.417339 -12.317281)
			(xy 27.467836 -12.340953) (xy 27.514349 -12.371726) (xy 27.555886 -12.408943) (xy 27.591561 -12.451811)
			(xy 27.620615 -12.499417) (xy 27.642427 -12.550746) (xy 27.656533 -12.604703) (xy 27.662633 -12.66014)
			(xy 27.660596 -12.715874) (xy 27.650466 -12.770717) (xy 27.632459 -12.823501) (xy 27.606958 -12.873101)
			(xy 27.574507 -12.918459) (xy 27.535798 -12.958608) (xy 27.491655 -12.992694) (xy 27.44302 -13.01999)
			(xy 27.390929 -13.039913) (xy 27.336492 -13.052039) (xy 27.28087 -13.05611) (xy 27.225248 -13.052039)
			(xy 27.170811 -13.039913) (xy 27.11872 -13.01999) (xy 27.070085 -12.992694) (xy 27.025942 -12.958608)
			(xy 26.987233 -12.918459) (xy 26.954782 -12.873101) (xy 26.929281 -12.823501) (xy 26.911274 -12.770717)
			(xy 26.901144 -12.715874) (xy 26.899107 -12.66014) (xy 0.509016 -12.66014) (xy 0.509016 -15.260473)
			(xy 1.150876 -15.260473) (xy 1.152892 -15.13086) (xy 1.162962 -15.001624) (xy 1.181047 -14.873263)
			(xy 1.207077 -14.746275) (xy 1.240952 -14.621151) (xy 1.28254 -14.498375) (xy 1.331681 -14.378422)
			(xy 1.388184 -14.261757) (xy 1.451831 -14.148829) (xy 1.522375 -14.040077) (xy 1.599544 -13.935921)
			(xy 1.683039 -13.836764) (xy 1.772537 -13.74299) (xy 1.867692 -13.654961) (xy 1.968135 -13.573018)
			(xy 2.073478 -13.497479) (xy 2.183314 -13.428634) (xy 2.297218 -13.366751) (xy 2.414748 -13.31207)
			(xy 2.535451 -13.2648) (xy 2.658859 -13.225127) (xy 2.784495 -13.193202) (xy 2.911872 -13.16915)
			(xy 3.040498 -13.153063) (xy 3.169876 -13.145004) (xy 3.23469 -13.1445) (xy 3.299504 -13.145004)
			(xy 3.428882 -13.153063) (xy 3.557508 -13.16915) (xy 3.684885 -13.193202) (xy 3.810521 -13.225127)
			(xy 3.933929 -13.2648) (xy 4.054632 -13.31207) (xy 4.172162 -13.366751) (xy 4.286066 -13.428634)
			(xy 4.395902 -13.497479) (xy 4.501245 -13.573018) (xy 4.601688 -13.654961) (xy 4.696843 -13.74299)
			(xy 4.786341 -13.836764) (xy 4.869836 -13.935921) (xy 4.947005 -14.040077) (xy 5.017549 -14.148829)
			(xy 5.081196 -14.261757) (xy 5.137699 -14.378422) (xy 5.18684 -14.498375) (xy 5.228428 -14.621151)
			(xy 5.262303 -14.746275) (xy 5.288333 -14.873263) (xy 5.306418 -15.001624) (xy 5.316488 -15.13086)
			(xy 5.318504 -15.260473) (xy 12.580876 -15.260473) (xy 12.582892 -15.13086) (xy 12.592962 -15.001624)
			(xy 12.611047 -14.873263) (xy 12.637077 -14.746275) (xy 12.670952 -14.621151) (xy 12.71254 -14.498375)
			(xy 12.761681 -14.378422) (xy 12.818184 -14.261757) (xy 12.881831 -14.148829) (xy 12.952375 -14.040077)
			(xy 13.029544 -13.935921) (xy 13.113039 -13.836764) (xy 13.202537 -13.74299) (xy 13.297692 -13.654961)
			(xy 13.398135 -13.573018) (xy 13.503478 -13.497479) (xy 13.613314 -13.428634) (xy 13.727218 -13.366751)
			(xy 13.844748 -13.31207) (xy 13.965451 -13.2648) (xy 14.088859 -13.225127) (xy 14.214495 -13.193202)
			(xy 14.341872 -13.16915) (xy 14.470498 -13.153063) (xy 14.599876 -13.145004) (xy 14.66469 -13.1445)
			(xy 14.729504 -13.145004) (xy 14.858882 -13.153063) (xy 14.987508 -13.16915) (xy 15.114885 -13.193202)
			(xy 15.240521 -13.225127) (xy 15.363929 -13.2648) (xy 15.484632 -13.31207) (xy 15.602162 -13.366751)
			(xy 15.716066 -13.428634) (xy 15.825902 -13.497479) (xy 15.931245 -13.573018) (xy 16.031688 -13.654961)
			(xy 16.126843 -13.74299) (xy 16.216341 -13.836764) (xy 16.299836 -13.935921) (xy 16.377005 -14.040077)
			(xy 16.447549 -14.148829) (xy 16.511196 -14.261757) (xy 16.567699 -14.378422) (xy 16.61684 -14.498375)
			(xy 16.658428 -14.621151) (xy 16.692303 -14.746275) (xy 16.699533 -14.781548) (xy 27.317953 -14.781548)
			(xy 27.324053 -14.726111) (xy 27.338159 -14.672154) (xy 27.359971 -14.620825) (xy 27.389025 -14.573219)
			(xy 27.4247 -14.530351) (xy 27.466237 -14.493134) (xy 27.51275 -14.462361) (xy 27.563247 -14.438689)
			(xy 27.616654 -14.422621) (xy 27.67183 -14.414501) (xy 27.699716 -14.413992) (xy 27.727602 -14.414501)
			(xy 27.782778 -14.422621) (xy 27.836185 -14.438689) (xy 27.886682 -14.462361) (xy 27.933195 -14.493134)
			(xy 27.974732 -14.530351) (xy 28.010407 -14.573219) (xy 28.039461 -14.620825) (xy 28.061273 -14.672154)
			(xy 28.075379 -14.726111) (xy 28.081479 -14.781548) (xy 28.081043 -14.793484) (xy 29.519874 -14.793484)
			(xy 29.519874 -14.706584) (xy 29.527892 -14.620055) (xy 29.54386 -14.534635) (xy 29.567641 -14.451053)
			(xy 29.599033 -14.370021) (xy 29.637767 -14.292232) (xy 29.683514 -14.218348) (xy 29.735883 -14.149001)
			(xy 29.794427 -14.084781) (xy 29.858647 -14.026237) (xy 29.927994 -13.973868) (xy 30.001878 -13.928121)
			(xy 30.079667 -13.889387) (xy 30.160699 -13.857995) (xy 30.244281 -13.834214) (xy 30.329701 -13.818246)
			(xy 30.41623 -13.810228) (xy 30.45968 -13.809726) (xy 30.50313 -13.810228) (xy 30.589659 -13.818246)
			(xy 30.675079 -13.834214) (xy 30.758661 -13.857995) (xy 30.839693 -13.889387) (xy 30.917482 -13.928121)
			(xy 30.991366 -13.973868) (xy 31.060713 -14.026237) (xy 31.124933 -14.084781) (xy 31.183477 -14.149001)
			(xy 31.235846 -14.218348) (xy 31.281593 -14.292232) (xy 31.320327 -14.370021) (xy 31.351719 -14.451053)
			(xy 31.3755 -14.534635) (xy 31.391468 -14.620055) (xy 31.399486 -14.706584) (xy 31.399486 -14.793484)
			(xy 34.599874 -14.793484) (xy 34.599874 -14.706584) (xy 34.607892 -14.620055) (xy 34.62386 -14.534635)
			(xy 34.647641 -14.451053) (xy 34.679033 -14.370021) (xy 34.717767 -14.292232) (xy 34.763514 -14.218348)
			(xy 34.815883 -14.149001) (xy 34.874427 -14.084781) (xy 34.938647 -14.026237) (xy 35.007994 -13.973868)
			(xy 35.081878 -13.928121) (xy 35.159667 -13.889387) (xy 35.240699 -13.857995) (xy 35.324281 -13.834214)
			(xy 35.409701 -13.818246) (xy 35.49623 -13.810228) (xy 35.53968 -13.809726) (xy 35.58313 -13.810228)
			(xy 35.669659 -13.818246) (xy 35.755079 -13.834214) (xy 35.838661 -13.857995) (xy 35.919693 -13.889387)
			(xy 35.997482 -13.928121) (xy 36.071366 -13.973868) (xy 36.094631 -13.991437) (xy 64.532756 -13.991437)
			(xy 64.532756 -13.920115) (xy 64.540742 -13.849241) (xy 64.556612 -13.779706) (xy 64.580169 -13.712386)
			(xy 64.611114 -13.648127) (xy 64.64906 -13.587736) (xy 64.693529 -13.531974) (xy 64.743962 -13.481541)
			(xy 64.799724 -13.437072) (xy 64.860115 -13.399126) (xy 64.924374 -13.368181) (xy 64.991694 -13.344624)
			(xy 65.061229 -13.328754) (xy 65.132103 -13.320768) (xy 65.167764 -13.320268) (xy 65.203425 -13.320768)
			(xy 65.274299 -13.328754) (xy 65.343834 -13.344624) (xy 65.411154 -13.368181) (xy 65.475413 -13.399126)
			(xy 65.535804 -13.437072) (xy 65.591566 -13.481541) (xy 65.641999 -13.531974) (xy 65.686468 -13.587736)
			(xy 65.724414 -13.648127) (xy 65.755359 -13.712386) (xy 65.778916 -13.779706) (xy 65.794786 -13.849241)
			(xy 65.802772 -13.920115) (xy 65.802772 -13.991437) (xy 66.447408 -13.991437) (xy 66.447408 -13.920115)
			(xy 66.455394 -13.849241) (xy 66.471264 -13.779706) (xy 66.494821 -13.712386) (xy 66.525766 -13.648127)
			(xy 66.563712 -13.587736) (xy 66.608181 -13.531974) (xy 66.658614 -13.481541) (xy 66.714376 -13.437072)
			(xy 66.774767 -13.399126) (xy 66.839026 -13.368181) (xy 66.906346 -13.344624) (xy 66.975881 -13.328754)
			(xy 67.046755 -13.320768) (xy 67.082416 -13.320268) (xy 67.118077 -13.320768) (xy 67.188951 -13.328754)
			(xy 67.258486 -13.344624) (xy 67.325806 -13.368181) (xy 67.390065 -13.399126) (xy 67.450456 -13.437072)
			(xy 67.506218 -13.481541) (xy 67.556651 -13.531974) (xy 67.60112 -13.587736) (xy 67.639066 -13.648127)
			(xy 67.670011 -13.712386) (xy 67.693568 -13.779706) (xy 67.709438 -13.849241) (xy 67.717424 -13.920115)
			(xy 67.717424 -13.991437) (xy 68.34428 -13.991437) (xy 68.34428 -13.920115) (xy 68.352266 -13.849241)
			(xy 68.368136 -13.779706) (xy 68.391693 -13.712386) (xy 68.422638 -13.648127) (xy 68.460584 -13.587736)
			(xy 68.505053 -13.531974) (xy 68.555486 -13.481541) (xy 68.611248 -13.437072) (xy 68.671639 -13.399126)
			(xy 68.735898 -13.368181) (xy 68.803218 -13.344624) (xy 68.872753 -13.328754) (xy 68.943627 -13.320768)
			(xy 68.979288 -13.320268) (xy 69.014949 -13.320768) (xy 69.085823 -13.328754) (xy 69.155358 -13.344624)
			(xy 69.222678 -13.368181) (xy 69.286937 -13.399126) (xy 69.347328 -13.437072) (xy 69.40309 -13.481541)
			(xy 69.453523 -13.531974) (xy 69.497992 -13.587736) (xy 69.535938 -13.648127) (xy 69.566883 -13.712386)
			(xy 69.59044 -13.779706) (xy 69.60631 -13.849241) (xy 69.614296 -13.920115) (xy 69.614296 -13.991437)
			(xy 70.422508 -13.991437) (xy 70.422508 -13.920115) (xy 70.430494 -13.849241) (xy 70.446364 -13.779706)
			(xy 70.469921 -13.712386) (xy 70.500866 -13.648127) (xy 70.538812 -13.587736) (xy 70.583281 -13.531974)
			(xy 70.633714 -13.481541) (xy 70.689476 -13.437072) (xy 70.749867 -13.399126) (xy 70.814126 -13.368181)
			(xy 70.881446 -13.344624) (xy 70.950981 -13.328754) (xy 71.021855 -13.320768) (xy 71.057516 -13.320268)
			(xy 71.093177 -13.320768) (xy 71.164051 -13.328754) (xy 71.233586 -13.344624) (xy 71.300906 -13.368181)
			(xy 71.365165 -13.399126) (xy 71.425556 -13.437072) (xy 71.481318 -13.481541) (xy 71.531751 -13.531974)
			(xy 71.57622 -13.587736) (xy 71.614166 -13.648127) (xy 71.645111 -13.712386) (xy 71.668668 -13.779706)
			(xy 71.684538 -13.849241) (xy 71.692524 -13.920115) (xy 71.692524 -13.991437) (xy 72.5429 -13.991437)
			(xy 72.5429 -13.920115) (xy 72.550886 -13.849241) (xy 72.566756 -13.779706) (xy 72.590313 -13.712386)
			(xy 72.621258 -13.648127) (xy 72.659204 -13.587736) (xy 72.703673 -13.531974) (xy 72.754106 -13.481541)
			(xy 72.809868 -13.437072) (xy 72.870259 -13.399126) (xy 72.934518 -13.368181) (xy 73.001838 -13.344624)
			(xy 73.071373 -13.328754) (xy 73.142247 -13.320768) (xy 73.177908 -13.320268) (xy 73.213569 -13.320768)
			(xy 73.284443 -13.328754) (xy 73.353978 -13.344624) (xy 73.421298 -13.368181) (xy 73.485557 -13.399126)
			(xy 73.545948 -13.437072) (xy 73.60171 -13.481541) (xy 73.652143 -13.531974) (xy 73.696612 -13.587736)
			(xy 73.734558 -13.648127) (xy 73.765503 -13.712386) (xy 73.78906 -13.779706) (xy 73.80493 -13.849241)
			(xy 73.812916 -13.920115) (xy 73.812916 -13.991437) (xy 73.80493 -14.062311) (xy 73.78906 -14.131846)
			(xy 73.765503 -14.199166) (xy 73.757694 -14.215382) (xy 84.426043 -14.215382) (xy 84.432143 -14.159945)
			(xy 84.446249 -14.105988) (xy 84.468061 -14.054659) (xy 84.497115 -14.007053) (xy 84.53279 -13.964185)
			(xy 84.574327 -13.926968) (xy 84.62084 -13.896195) (xy 84.671337 -13.872523) (xy 84.724744 -13.856455)
			(xy 84.77992 -13.848335) (xy 84.807806 -13.847826) (xy 84.835692 -13.848335) (xy 84.890868 -13.856455)
			(xy 84.944275 -13.872523) (xy 84.994772 -13.896195) (xy 85.041285 -13.926968) (xy 85.082822 -13.964185)
			(xy 85.118497 -14.007053) (xy 85.147551 -14.054659) (xy 85.169363 -14.105988) (xy 85.183469 -14.159945)
			(xy 85.189569 -14.215382) (xy 85.188 -14.258308) (xy 87.270843 -14.258308) (xy 87.276943 -14.202871)
			(xy 87.291049 -14.148914) (xy 87.312861 -14.097585) (xy 87.341915 -14.049979) (xy 87.37759 -14.007111)
			(xy 87.419127 -13.969894) (xy 87.46564 -13.939121) (xy 87.516137 -13.915449) (xy 87.569544 -13.899381)
			(xy 87.62472 -13.891261) (xy 87.652606 -13.890752) (xy 87.680492 -13.891261) (xy 87.735668 -13.899381)
			(xy 87.789075 -13.915449) (xy 87.839572 -13.939121) (xy 87.886085 -13.969894) (xy 87.927622 -14.007111)
			(xy 87.963297 -14.049979) (xy 87.992351 -14.097585) (xy 88.014163 -14.148914) (xy 88.028269 -14.202871)
			(xy 88.034369 -14.258308) (xy 88.032332 -14.314042) (xy 88.022202 -14.368885) (xy 88.004195 -14.421669)
			(xy 87.978694 -14.471269) (xy 87.946243 -14.516627) (xy 87.907534 -14.556776) (xy 87.863391 -14.590862)
			(xy 87.814756 -14.618158) (xy 87.762665 -14.638081) (xy 87.708228 -14.650207) (xy 87.652606 -14.654278)
			(xy 87.596984 -14.650207) (xy 87.542547 -14.638081) (xy 87.490456 -14.618158) (xy 87.441821 -14.590862)
			(xy 87.397678 -14.556776) (xy 87.358969 -14.516627) (xy 87.326518 -14.471269) (xy 87.301017 -14.421669)
			(xy 87.28301 -14.368885) (xy 87.27288 -14.314042) (xy 87.270843 -14.258308) (xy 85.188 -14.258308)
			(xy 85.187532 -14.271116) (xy 85.177402 -14.325959) (xy 85.159395 -14.378743) (xy 85.133894 -14.428343)
			(xy 85.101443 -14.473701) (xy 85.062734 -14.51385) (xy 85.018591 -14.547936) (xy 84.969956 -14.575232)
			(xy 84.917865 -14.595155) (xy 84.863428 -14.607281) (xy 84.807806 -14.611352) (xy 84.752184 -14.607281)
			(xy 84.697747 -14.595155) (xy 84.645656 -14.575232) (xy 84.597021 -14.547936) (xy 84.552878 -14.51385)
			(xy 84.514169 -14.473701) (xy 84.481718 -14.428343) (xy 84.456217 -14.378743) (xy 84.43821 -14.325959)
			(xy 84.42808 -14.271116) (xy 84.426043 -14.215382) (xy 73.757694 -14.215382) (xy 73.734558 -14.263425)
			(xy 73.696612 -14.323816) (xy 73.652143 -14.379578) (xy 73.60171 -14.430011) (xy 73.545948 -14.47448)
			(xy 73.485557 -14.512426) (xy 73.421298 -14.543371) (xy 73.353978 -14.566928) (xy 73.284443 -14.582798)
			(xy 73.213569 -14.590784) (xy 73.142247 -14.590784) (xy 73.071373 -14.582798) (xy 73.001838 -14.566928)
			(xy 72.934518 -14.543371) (xy 72.870259 -14.512426) (xy 72.809868 -14.47448) (xy 72.754106 -14.430011)
			(xy 72.703673 -14.379578) (xy 72.659204 -14.323816) (xy 72.621258 -14.263425) (xy 72.590313 -14.199166)
			(xy 72.566756 -14.131846) (xy 72.550886 -14.062311) (xy 72.5429 -13.991437) (xy 71.692524 -13.991437)
			(xy 71.684538 -14.062311) (xy 71.668668 -14.131846) (xy 71.645111 -14.199166) (xy 71.614166 -14.263425)
			(xy 71.57622 -14.323816) (xy 71.531751 -14.379578) (xy 71.481318 -14.430011) (xy 71.425556 -14.47448)
			(xy 71.365165 -14.512426) (xy 71.300906 -14.543371) (xy 71.233586 -14.566928) (xy 71.164051 -14.582798)
			(xy 71.093177 -14.590784) (xy 71.021855 -14.590784) (xy 70.950981 -14.582798) (xy 70.881446 -14.566928)
			(xy 70.814126 -14.543371) (xy 70.749867 -14.512426) (xy 70.689476 -14.47448) (xy 70.633714 -14.430011)
			(xy 70.583281 -14.379578) (xy 70.538812 -14.323816) (xy 70.500866 -14.263425) (xy 70.469921 -14.199166)
			(xy 70.446364 -14.131846) (xy 70.430494 -14.062311) (xy 70.422508 -13.991437) (xy 69.614296 -13.991437)
			(xy 69.60631 -14.062311) (xy 69.59044 -14.131846) (xy 69.566883 -14.199166) (xy 69.535938 -14.263425)
			(xy 69.497992 -14.323816) (xy 69.453523 -14.379578) (xy 69.40309 -14.430011) (xy 69.347328 -14.47448)
			(xy 69.286937 -14.512426) (xy 69.222678 -14.543371) (xy 69.155358 -14.566928) (xy 69.085823 -14.582798)
			(xy 69.014949 -14.590784) (xy 68.943627 -14.590784) (xy 68.872753 -14.582798) (xy 68.803218 -14.566928)
			(xy 68.735898 -14.543371) (xy 68.671639 -14.512426) (xy 68.611248 -14.47448) (xy 68.555486 -14.430011)
			(xy 68.505053 -14.379578) (xy 68.460584 -14.323816) (xy 68.422638 -14.263425) (xy 68.391693 -14.199166)
			(xy 68.368136 -14.131846) (xy 68.352266 -14.062311) (xy 68.34428 -13.991437) (xy 67.717424 -13.991437)
			(xy 67.709438 -14.062311) (xy 67.693568 -14.131846) (xy 67.670011 -14.199166) (xy 67.639066 -14.263425)
			(xy 67.60112 -14.323816) (xy 67.556651 -14.379578) (xy 67.506218 -14.430011) (xy 67.450456 -14.47448)
			(xy 67.390065 -14.512426) (xy 67.325806 -14.543371) (xy 67.258486 -14.566928) (xy 67.188951 -14.582798)
			(xy 67.118077 -14.590784) (xy 67.046755 -14.590784) (xy 66.975881 -14.582798) (xy 66.906346 -14.566928)
			(xy 66.839026 -14.543371) (xy 66.774767 -14.512426) (xy 66.714376 -14.47448) (xy 66.658614 -14.430011)
			(xy 66.608181 -14.379578) (xy 66.563712 -14.323816) (xy 66.525766 -14.263425) (xy 66.494821 -14.199166)
			(xy 66.471264 -14.131846) (xy 66.455394 -14.062311) (xy 66.447408 -13.991437) (xy 65.802772 -13.991437)
			(xy 65.794786 -14.062311) (xy 65.778916 -14.131846) (xy 65.755359 -14.199166) (xy 65.724414 -14.263425)
			(xy 65.686468 -14.323816) (xy 65.641999 -14.379578) (xy 65.591566 -14.430011) (xy 65.535804 -14.47448)
			(xy 65.475413 -14.512426) (xy 65.411154 -14.543371) (xy 65.343834 -14.566928) (xy 65.274299 -14.582798)
			(xy 65.203425 -14.590784) (xy 65.132103 -14.590784) (xy 65.061229 -14.582798) (xy 64.991694 -14.566928)
			(xy 64.924374 -14.543371) (xy 64.860115 -14.512426) (xy 64.799724 -14.47448) (xy 64.743962 -14.430011)
			(xy 64.693529 -14.379578) (xy 64.64906 -14.323816) (xy 64.611114 -14.263425) (xy 64.580169 -14.199166)
			(xy 64.556612 -14.131846) (xy 64.540742 -14.062311) (xy 64.532756 -13.991437) (xy 36.094631 -13.991437)
			(xy 36.140713 -14.026237) (xy 36.204933 -14.084781) (xy 36.263477 -14.149001) (xy 36.315846 -14.218348)
			(xy 36.361593 -14.292232) (xy 36.400327 -14.370021) (xy 36.431719 -14.451053) (xy 36.4555 -14.534635)
			(xy 36.471468 -14.620055) (xy 36.479486 -14.706584) (xy 36.479486 -14.793484) (xy 36.471468 -14.880013)
			(xy 36.4555 -14.965433) (xy 36.431719 -15.049015) (xy 36.400327 -15.130047) (xy 36.361593 -15.207836)
			(xy 36.315846 -15.28172) (xy 36.263477 -15.351067) (xy 36.204933 -15.415287) (xy 36.140713 -15.473831)
			(xy 36.071366 -15.5262) (xy 35.997482 -15.571947) (xy 35.919693 -15.610681) (xy 35.890388 -15.622034)
			(xy 85.527895 -15.622034) (xy 85.533995 -15.566597) (xy 85.548101 -15.51264) (xy 85.569913 -15.461311)
			(xy 85.598967 -15.413705) (xy 85.634642 -15.370837) (xy 85.676179 -15.33362) (xy 85.722692 -15.302847)
			(xy 85.773189 -15.279175) (xy 85.826596 -15.263107) (xy 85.881772 -15.254987) (xy 85.909658 -15.254478)
			(xy 85.937544 -15.254987) (xy 85.99272 -15.263107) (xy 86.046127 -15.279175) (xy 86.096624 -15.302847)
			(xy 86.143137 -15.33362) (xy 86.184674 -15.370837) (xy 86.220349 -15.413705) (xy 86.249403 -15.461311)
			(xy 86.271215 -15.51264) (xy 86.285321 -15.566597) (xy 86.291421 -15.622034) (xy 86.289384 -15.677768)
			(xy 86.279254 -15.732611) (xy 86.261247 -15.785395) (xy 86.235746 -15.834995) (xy 86.203295 -15.880353)
			(xy 86.164586 -15.920502) (xy 86.120443 -15.954588) (xy 86.071808 -15.981884) (xy 86.019717 -16.001807)
			(xy 85.96528 -16.013933) (xy 85.909658 -16.018004) (xy 85.854036 -16.013933) (xy 85.799599 -16.001807)
			(xy 85.747508 -15.981884) (xy 85.698873 -15.954588) (xy 85.65473 -15.920502) (xy 85.616021 -15.880353)
			(xy 85.58357 -15.834995) (xy 85.558069 -15.785395) (xy 85.540062 -15.732611) (xy 85.529932 -15.677768)
			(xy 85.527895 -15.622034) (xy 35.890388 -15.622034) (xy 35.838661 -15.642073) (xy 35.755079 -15.665854)
			(xy 35.669659 -15.681822) (xy 35.58313 -15.68984) (xy 35.49623 -15.68984) (xy 35.409701 -15.681822)
			(xy 35.324281 -15.665854) (xy 35.240699 -15.642073) (xy 35.159667 -15.610681) (xy 35.081878 -15.571947)
			(xy 35.007994 -15.5262) (xy 34.938647 -15.473831) (xy 34.874427 -15.415287) (xy 34.815883 -15.351067)
			(xy 34.763514 -15.28172) (xy 34.717767 -15.207836) (xy 34.679033 -15.130047) (xy 34.647641 -15.049015)
			(xy 34.62386 -14.965433) (xy 34.607892 -14.880013) (xy 34.599874 -14.793484) (xy 31.399486 -14.793484)
			(xy 31.391468 -14.880013) (xy 31.3755 -14.965433) (xy 31.351719 -15.049015) (xy 31.320327 -15.130047)
			(xy 31.281593 -15.207836) (xy 31.235846 -15.28172) (xy 31.183477 -15.351067) (xy 31.124933 -15.415287)
			(xy 31.060713 -15.473831) (xy 30.991366 -15.5262) (xy 30.917482 -15.571947) (xy 30.839693 -15.610681)
			(xy 30.758661 -15.642073) (xy 30.675079 -15.665854) (xy 30.589659 -15.681822) (xy 30.50313 -15.68984)
			(xy 30.41623 -15.68984) (xy 30.329701 -15.681822) (xy 30.244281 -15.665854) (xy 30.160699 -15.642073)
			(xy 30.079667 -15.610681) (xy 30.001878 -15.571947) (xy 29.927994 -15.5262) (xy 29.858647 -15.473831)
			(xy 29.794427 -15.415287) (xy 29.735883 -15.351067) (xy 29.683514 -15.28172) (xy 29.637767 -15.207836)
			(xy 29.599033 -15.130047) (xy 29.567641 -15.049015) (xy 29.54386 -14.965433) (xy 29.527892 -14.880013)
			(xy 29.519874 -14.793484) (xy 28.081043 -14.793484) (xy 28.079442 -14.837282) (xy 28.069312 -14.892125)
			(xy 28.051305 -14.944909) (xy 28.025804 -14.994509) (xy 27.993353 -15.039867) (xy 27.954644 -15.080016)
			(xy 27.910501 -15.114102) (xy 27.861866 -15.141398) (xy 27.809775 -15.161321) (xy 27.755338 -15.173447)
			(xy 27.699716 -15.177518) (xy 27.644094 -15.173447) (xy 27.589657 -15.161321) (xy 27.537566 -15.141398)
			(xy 27.488931 -15.114102) (xy 27.444788 -15.080016) (xy 27.406079 -15.039867) (xy 27.373628 -14.994509)
			(xy 27.348127 -14.944909) (xy 27.33012 -14.892125) (xy 27.31999 -14.837282) (xy 27.317953 -14.781548)
			(xy 16.699533 -14.781548) (xy 16.718333 -14.873263) (xy 16.736418 -15.001624) (xy 16.746488 -15.13086)
			(xy 16.748504 -15.260473) (xy 16.742458 -15.38996) (xy 16.728374 -15.518821) (xy 16.706305 -15.646557)
			(xy 16.676338 -15.772674) (xy 16.665442 -15.80847) (xy 26.123137 -15.80847) (xy 26.129237 -15.753033)
			(xy 26.143343 -15.699076) (xy 26.165155 -15.647747) (xy 26.194209 -15.600141) (xy 26.229884 -15.557273)
			(xy 26.271421 -15.520056) (xy 26.317934 -15.489283) (xy 26.368431 -15.465611) (xy 26.421838 -15.449543)
			(xy 26.477014 -15.441423) (xy 26.5049 -15.440914) (xy 26.532786 -15.441423) (xy 26.587962 -15.449543)
			(xy 26.641369 -15.465611) (xy 26.691866 -15.489283) (xy 26.738379 -15.520056) (xy 26.779916 -15.557273)
			(xy 26.815591 -15.600141) (xy 26.844645 -15.647747) (xy 26.866457 -15.699076) (xy 26.880563 -15.753033)
			(xy 26.886663 -15.80847) (xy 26.884626 -15.864204) (xy 26.874496 -15.919047) (xy 26.856489 -15.971831)
			(xy 26.830988 -16.021431) (xy 26.798537 -16.066789) (xy 26.759828 -16.106938) (xy 26.715685 -16.141024)
			(xy 26.66705 -16.16832) (xy 26.614959 -16.188243) (xy 26.560522 -16.200369) (xy 26.5049 -16.20444)
			(xy 26.449278 -16.200369) (xy 26.394841 -16.188243) (xy 26.34275 -16.16832) (xy 26.294115 -16.141024)
			(xy 26.249972 -16.106938) (xy 26.211263 -16.066789) (xy 26.178812 -16.021431) (xy 26.153311 -15.971831)
			(xy 26.135304 -15.919047) (xy 26.125174 -15.864204) (xy 26.123137 -15.80847) (xy 16.665442 -15.80847)
			(xy 16.638589 -15.896684) (xy 16.593202 -16.018107) (xy 16.540355 -16.136474) (xy 16.480251 -16.251326)
			(xy 16.413123 -16.362219) (xy 16.339231 -16.468725) (xy 16.25886 -16.570431) (xy 16.172322 -16.666943)
			(xy 16.07995 -16.757888) (xy 15.982104 -16.842915) (xy 15.879161 -16.921695) (xy 15.771519 -16.993922)
			(xy 15.659595 -17.059317) (xy 15.543822 -17.117628) (xy 15.424648 -17.168628) (xy 15.302534 -17.21212)
			(xy 15.177951 -17.247937) (xy 15.051384 -17.275939) (xy 14.92332 -17.296018) (xy 14.794256 -17.308097)
			(xy 14.66469 -17.312128) (xy 14.535124 -17.308097) (xy 14.40606 -17.296018) (xy 14.277996 -17.275939)
			(xy 14.151429 -17.247937) (xy 14.026846 -17.21212) (xy 13.904732 -17.168628) (xy 13.785558 -17.117628)
			(xy 13.669785 -17.059317) (xy 13.557861 -16.993922) (xy 13.450219 -16.921695) (xy 13.347276 -16.842915)
			(xy 13.24943 -16.757888) (xy 13.157058 -16.666943) (xy 13.07052 -16.570431) (xy 12.990149 -16.468725)
			(xy 12.916257 -16.362219) (xy 12.849129 -16.251326) (xy 12.789025 -16.136474) (xy 12.736178 -16.018107)
			(xy 12.690791 -15.896684) (xy 12.653042 -15.772674) (xy 12.623075 -15.646557) (xy 12.601006 -15.518821)
			(xy 12.586922 -15.38996) (xy 12.580876 -15.260473) (xy 5.318504 -15.260473) (xy 5.312458 -15.38996)
			(xy 5.298374 -15.518821) (xy 5.276305 -15.646557) (xy 5.246338 -15.772674) (xy 5.208589 -15.896684)
			(xy 5.163202 -16.018107) (xy 5.110355 -16.136474) (xy 5.050251 -16.251326) (xy 4.983123 -16.362219)
			(xy 4.909231 -16.468725) (xy 4.82886 -16.570431) (xy 4.742322 -16.666943) (xy 4.64995 -16.757888)
			(xy 4.552104 -16.842915) (xy 4.449161 -16.921695) (xy 4.341519 -16.993922) (xy 4.229595 -17.059317)
			(xy 4.113822 -17.117628) (xy 3.994648 -17.168628) (xy 3.872534 -17.21212) (xy 3.747951 -17.247937)
			(xy 3.621384 -17.275939) (xy 3.49332 -17.296018) (xy 3.364256 -17.308097) (xy 3.23469 -17.312128)
			(xy 3.105124 -17.308097) (xy 2.97606 -17.296018) (xy 2.847996 -17.275939) (xy 2.721429 -17.247937)
			(xy 2.596846 -17.21212) (xy 2.474732 -17.168628) (xy 2.355558 -17.117628) (xy 2.239785 -17.059317)
			(xy 2.127861 -16.993922) (xy 2.020219 -16.921695) (xy 1.917276 -16.842915) (xy 1.81943 -16.757888)
			(xy 1.727058 -16.666943) (xy 1.64052 -16.570431) (xy 1.560149 -16.468725) (xy 1.486257 -16.362219)
			(xy 1.419129 -16.251326) (xy 1.359025 -16.136474) (xy 1.306178 -16.018107) (xy 1.260791 -15.896684)
			(xy 1.223042 -15.772674) (xy 1.193075 -15.646557) (xy 1.171006 -15.518821) (xy 1.156922 -15.38996)
			(xy 1.150876 -15.260473) (xy 0.509016 -15.260473) (xy 0.509016 -18.381634) (xy 26.762163 -18.381634)
			(xy 26.762163 -18.318366) (xy 26.770421 -18.25564) (xy 26.786796 -18.194528) (xy 26.811008 -18.136077)
			(xy 26.842641 -18.081285) (xy 26.881156 -18.031092) (xy 26.925893 -17.986355) (xy 26.976087 -17.94784)
			(xy 27.030878 -17.916207) (xy 27.08933 -17.891995) (xy 27.150442 -17.875621) (xy 27.213168 -17.867363)
			(xy 27.244802 -17.866868) (xy 28.989782 -17.866868) (xy 29.20746 -18.084546) (xy 29.219533 -18.096013)
			(xy 29.248336 -18.112702) (xy 29.280478 -18.121366) (xy 29.297122 -18.121884) (xy 29.41447 -18.121884)
			(xy 29.436456 -18.121402) (xy 29.479771 -18.113837) (xy 29.521137 -18.098928) (xy 29.559319 -18.07712)
			(xy 29.593176 -18.049064) (xy 29.621698 -18.015597) (xy 29.644032 -17.977721) (xy 29.659512 -17.936564)
			(xy 29.667675 -17.893358) (xy 29.668277 -17.849391) (xy 29.661301 -17.805976) (xy 29.646956 -17.764411)
			(xy 29.63672 -17.744948) (xy 29.616168 -17.706738) (xy 29.581366 -17.627257) (xy 29.554035 -17.544908)
			(xy 29.534406 -17.460391) (xy 29.522646 -17.374425) (xy 29.518856 -17.287741) (xy 29.523069 -17.201077)
			(xy 29.535247 -17.115169) (xy 29.555288 -17.030749) (xy 29.58302 -16.948534) (xy 29.618209 -16.869223)
			(xy 29.660555 -16.793492) (xy 29.709698 -16.721984) (xy 29.765219 -16.655307) (xy 29.826647 -16.594028)
			(xy 29.893459 -16.53867) (xy 29.965087 -16.489702) (xy 30.040921 -16.44754) (xy 30.120317 -16.412545)
			(xy 30.2026 -16.385012) (xy 30.287069 -16.365177) (xy 30.373006 -16.353209) (xy 30.45968 -16.349208)
			(xy 30.546354 -16.353209) (xy 30.632291 -16.365177) (xy 30.71676 -16.385012) (xy 30.799043 -16.412545)
			(xy 30.878439 -16.44754) (xy 30.954273 -16.489702) (xy 31.025901 -16.53867) (xy 31.092713 -16.594028)
			(xy 31.154141 -16.655307) (xy 31.209662 -16.721984) (xy 31.258805 -16.793492) (xy 31.301151 -16.869223)
			(xy 31.33634 -16.948534) (xy 31.364072 -17.030749) (xy 31.384113 -17.115169) (xy 31.396291 -17.201077)
			(xy 31.400504 -17.287741) (xy 31.398504 -17.333484) (xy 34.599874 -17.333484) (xy 34.599874 -17.246584)
			(xy 34.607892 -17.160055) (xy 34.62386 -17.074635) (xy 34.647641 -16.991053) (xy 34.679033 -16.910021)
			(xy 34.717767 -16.832232) (xy 34.763514 -16.758348) (xy 34.815883 -16.689001) (xy 34.874427 -16.624781)
			(xy 34.938647 -16.566237) (xy 35.007994 -16.513868) (xy 35.081878 -16.468121) (xy 35.159667 -16.429387)
			(xy 35.240699 -16.397995) (xy 35.324281 -16.374214) (xy 35.409701 -16.358246) (xy 35.49623 -16.350228)
			(xy 35.53968 -16.349726) (xy 35.58313 -16.350228) (xy 35.669659 -16.358246) (xy 35.755079 -16.374214)
			(xy 35.838661 -16.397995) (xy 35.919693 -16.429387) (xy 35.997482 -16.468121) (xy 36.071366 -16.513868)
			(xy 36.140713 -16.566237) (xy 36.204933 -16.624781) (xy 36.236772 -16.659707) (xy 64.532756 -16.659707)
			(xy 64.532756 -16.588385) (xy 64.540742 -16.517511) (xy 64.556612 -16.447976) (xy 64.580169 -16.380656)
			(xy 64.611114 -16.316397) (xy 64.64906 -16.256006) (xy 64.693529 -16.200244) (xy 64.743962 -16.149811)
			(xy 64.799724 -16.105342) (xy 64.860115 -16.067396) (xy 64.924374 -16.036451) (xy 64.991694 -16.012894)
			(xy 65.061229 -15.997024) (xy 65.132103 -15.989038) (xy 65.167764 -15.988538) (xy 65.203425 -15.989038)
			(xy 65.274299 -15.997024) (xy 65.343834 -16.012894) (xy 65.411154 -16.036451) (xy 65.475413 -16.067396)
			(xy 65.535804 -16.105342) (xy 65.591566 -16.149811) (xy 65.641999 -16.200244) (xy 65.686468 -16.256006)
			(xy 65.724414 -16.316397) (xy 65.755359 -16.380656) (xy 65.778916 -16.447976) (xy 65.794786 -16.517511)
			(xy 65.802772 -16.588385) (xy 65.802772 -16.659707) (xy 66.447408 -16.659707) (xy 66.447408 -16.588385)
			(xy 66.455394 -16.517511) (xy 66.471264 -16.447976) (xy 66.494821 -16.380656) (xy 66.525766 -16.316397)
			(xy 66.563712 -16.256006) (xy 66.608181 -16.200244) (xy 66.658614 -16.149811) (xy 66.714376 -16.105342)
			(xy 66.774767 -16.067396) (xy 66.839026 -16.036451) (xy 66.906346 -16.012894) (xy 66.975881 -15.997024)
			(xy 67.046755 -15.989038) (xy 67.082416 -15.988538) (xy 67.118077 -15.989038) (xy 67.188951 -15.997024)
			(xy 67.258486 -16.012894) (xy 67.325806 -16.036451) (xy 67.390065 -16.067396) (xy 67.450456 -16.105342)
			(xy 67.506218 -16.149811) (xy 67.556651 -16.200244) (xy 67.60112 -16.256006) (xy 67.639066 -16.316397)
			(xy 67.670011 -16.380656) (xy 67.693568 -16.447976) (xy 67.709438 -16.517511) (xy 67.717424 -16.588385)
			(xy 67.717424 -16.659707) (xy 68.34428 -16.659707) (xy 68.34428 -16.588385) (xy 68.352266 -16.517511)
			(xy 68.368136 -16.447976) (xy 68.391693 -16.380656) (xy 68.422638 -16.316397) (xy 68.460584 -16.256006)
			(xy 68.505053 -16.200244) (xy 68.555486 -16.149811) (xy 68.611248 -16.105342) (xy 68.671639 -16.067396)
			(xy 68.735898 -16.036451) (xy 68.803218 -16.012894) (xy 68.872753 -15.997024) (xy 68.943627 -15.989038)
			(xy 68.979288 -15.988538) (xy 69.014949 -15.989038) (xy 69.085823 -15.997024) (xy 69.155358 -16.012894)
			(xy 69.222678 -16.036451) (xy 69.286937 -16.067396) (xy 69.347328 -16.105342) (xy 69.40309 -16.149811)
			(xy 69.453523 -16.200244) (xy 69.497992 -16.256006) (xy 69.535938 -16.316397) (xy 69.566883 -16.380656)
			(xy 69.59044 -16.447976) (xy 69.60631 -16.517511) (xy 69.614296 -16.588385) (xy 69.614296 -16.659707)
			(xy 70.422508 -16.659707) (xy 70.422508 -16.588385) (xy 70.430494 -16.517511) (xy 70.446364 -16.447976)
			(xy 70.469921 -16.380656) (xy 70.500866 -16.316397) (xy 70.538812 -16.256006) (xy 70.583281 -16.200244)
			(xy 70.633714 -16.149811) (xy 70.689476 -16.105342) (xy 70.749867 -16.067396) (xy 70.814126 -16.036451)
			(xy 70.881446 -16.012894) (xy 70.950981 -15.997024) (xy 71.021855 -15.989038) (xy 71.057516 -15.988538)
			(xy 71.093177 -15.989038) (xy 71.164051 -15.997024) (xy 71.233586 -16.012894) (xy 71.300906 -16.036451)
			(xy 71.365165 -16.067396) (xy 71.425556 -16.105342) (xy 71.481318 -16.149811) (xy 71.531751 -16.200244)
			(xy 71.57622 -16.256006) (xy 71.614166 -16.316397) (xy 71.645111 -16.380656) (xy 71.668668 -16.447976)
			(xy 71.684538 -16.517511) (xy 71.692524 -16.588385) (xy 71.692524 -16.659707) (xy 72.5429 -16.659707)
			(xy 72.5429 -16.588385) (xy 72.550886 -16.517511) (xy 72.566756 -16.447976) (xy 72.590313 -16.380656)
			(xy 72.621258 -16.316397) (xy 72.659204 -16.256006) (xy 72.703673 -16.200244) (xy 72.754106 -16.149811)
			(xy 72.809868 -16.105342) (xy 72.870259 -16.067396) (xy 72.934518 -16.036451) (xy 73.001838 -16.012894)
			(xy 73.071373 -15.997024) (xy 73.142247 -15.989038) (xy 73.177908 -15.988538) (xy 73.213569 -15.989038)
			(xy 73.284443 -15.997024) (xy 73.353978 -16.012894) (xy 73.421298 -16.036451) (xy 73.485557 -16.067396)
			(xy 73.545948 -16.105342) (xy 73.60171 -16.149811) (xy 73.652143 -16.200244) (xy 73.696612 -16.256006)
			(xy 73.734558 -16.316397) (xy 73.765503 -16.380656) (xy 73.78906 -16.447976) (xy 73.80493 -16.517511)
			(xy 73.812916 -16.588385) (xy 73.812916 -16.659707) (xy 73.80493 -16.730581) (xy 73.78906 -16.800116)
			(xy 73.765503 -16.867436) (xy 73.734558 -16.931695) (xy 73.696612 -16.992086) (xy 73.652143 -17.047848)
			(xy 73.60171 -17.098281) (xy 73.545948 -17.14275) (xy 73.485557 -17.180696) (xy 73.421298 -17.211641)
			(xy 73.353978 -17.235198) (xy 73.284443 -17.251068) (xy 73.213569 -17.259054) (xy 73.142247 -17.259054)
			(xy 73.071373 -17.251068) (xy 73.001838 -17.235198) (xy 72.934518 -17.211641) (xy 72.870259 -17.180696)
			(xy 72.809868 -17.14275) (xy 72.754106 -17.098281) (xy 72.703673 -17.047848) (xy 72.659204 -16.992086)
			(xy 72.621258 -16.931695) (xy 72.590313 -16.867436) (xy 72.566756 -16.800116) (xy 72.550886 -16.730581)
			(xy 72.5429 -16.659707) (xy 71.692524 -16.659707) (xy 71.684538 -16.730581) (xy 71.668668 -16.800116)
			(xy 71.645111 -16.867436) (xy 71.614166 -16.931695) (xy 71.57622 -16.992086) (xy 71.531751 -17.047848)
			(xy 71.481318 -17.098281) (xy 71.425556 -17.14275) (xy 71.365165 -17.180696) (xy 71.300906 -17.211641)
			(xy 71.233586 -17.235198) (xy 71.164051 -17.251068) (xy 71.093177 -17.259054) (xy 71.021855 -17.259054)
			(xy 70.950981 -17.251068) (xy 70.881446 -17.235198) (xy 70.814126 -17.211641) (xy 70.749867 -17.180696)
			(xy 70.689476 -17.14275) (xy 70.633714 -17.098281) (xy 70.583281 -17.047848) (xy 70.538812 -16.992086)
			(xy 70.500866 -16.931695) (xy 70.469921 -16.867436) (xy 70.446364 -16.800116) (xy 70.430494 -16.730581)
			(xy 70.422508 -16.659707) (xy 69.614296 -16.659707) (xy 69.60631 -16.730581) (xy 69.59044 -16.800116)
			(xy 69.566883 -16.867436) (xy 69.535938 -16.931695) (xy 69.497992 -16.992086) (xy 69.453523 -17.047848)
			(xy 69.40309 -17.098281) (xy 69.347328 -17.14275) (xy 69.286937 -17.180696) (xy 69.222678 -17.211641)
			(xy 69.155358 -17.235198) (xy 69.085823 -17.251068) (xy 69.014949 -17.259054) (xy 68.943627 -17.259054)
			(xy 68.872753 -17.251068) (xy 68.803218 -17.235198) (xy 68.735898 -17.211641) (xy 68.671639 -17.180696)
			(xy 68.611248 -17.14275) (xy 68.555486 -17.098281) (xy 68.505053 -17.047848) (xy 68.460584 -16.992086)
			(xy 68.422638 -16.931695) (xy 68.391693 -16.867436) (xy 68.368136 -16.800116) (xy 68.352266 -16.730581)
			(xy 68.34428 -16.659707) (xy 67.717424 -16.659707) (xy 67.709438 -16.730581) (xy 67.693568 -16.800116)
			(xy 67.670011 -16.867436) (xy 67.639066 -16.931695) (xy 67.60112 -16.992086) (xy 67.556651 -17.047848)
			(xy 67.506218 -17.098281) (xy 67.450456 -17.14275) (xy 67.390065 -17.180696) (xy 67.325806 -17.211641)
			(xy 67.258486 -17.235198) (xy 67.188951 -17.251068) (xy 67.118077 -17.259054) (xy 67.046755 -17.259054)
			(xy 66.975881 -17.251068) (xy 66.906346 -17.235198) (xy 66.839026 -17.211641) (xy 66.774767 -17.180696)
			(xy 66.714376 -17.14275) (xy 66.658614 -17.098281) (xy 66.608181 -17.047848) (xy 66.563712 -16.992086)
			(xy 66.525766 -16.931695) (xy 66.494821 -16.867436) (xy 66.471264 -16.800116) (xy 66.455394 -16.730581)
			(xy 66.447408 -16.659707) (xy 65.802772 -16.659707) (xy 65.794786 -16.730581) (xy 65.778916 -16.800116)
			(xy 65.755359 -16.867436) (xy 65.724414 -16.931695) (xy 65.686468 -16.992086) (xy 65.641999 -17.047848)
			(xy 65.591566 -17.098281) (xy 65.535804 -17.14275) (xy 65.475413 -17.180696) (xy 65.411154 -17.211641)
			(xy 65.343834 -17.235198) (xy 65.274299 -17.251068) (xy 65.203425 -17.259054) (xy 65.132103 -17.259054)
			(xy 65.061229 -17.251068) (xy 64.991694 -17.235198) (xy 64.924374 -17.211641) (xy 64.860115 -17.180696)
			(xy 64.799724 -17.14275) (xy 64.743962 -17.098281) (xy 64.693529 -17.047848) (xy 64.64906 -16.992086)
			(xy 64.611114 -16.931695) (xy 64.580169 -16.867436) (xy 64.556612 -16.800116) (xy 64.540742 -16.730581)
			(xy 64.532756 -16.659707) (xy 36.236772 -16.659707) (xy 36.263477 -16.689001) (xy 36.315846 -16.758348)
			(xy 36.361593 -16.832232) (xy 36.400327 -16.910021) (xy 36.431719 -16.991053) (xy 36.4555 -17.074635)
			(xy 36.471468 -17.160055) (xy 36.479486 -17.246584) (xy 36.479486 -17.333484) (xy 36.471468 -17.420013)
			(xy 36.4555 -17.505433) (xy 36.431719 -17.589015) (xy 36.400327 -17.670047) (xy 36.361593 -17.747836)
			(xy 36.315846 -17.82172) (xy 36.263477 -17.891067) (xy 36.204933 -17.955287) (xy 36.140713 -18.013831)
			(xy 36.071366 -18.0662) (xy 35.997482 -18.111947) (xy 35.919693 -18.150681) (xy 35.838661 -18.182073)
			(xy 35.755079 -18.205854) (xy 35.669659 -18.221822) (xy 35.58313 -18.22984) (xy 35.49623 -18.22984)
			(xy 35.409701 -18.221822) (xy 35.324281 -18.205854) (xy 35.240699 -18.182073) (xy 35.159667 -18.150681)
			(xy 35.081878 -18.111947) (xy 35.007994 -18.0662) (xy 34.938647 -18.013831) (xy 34.874427 -17.955287)
			(xy 34.815883 -17.891067) (xy 34.763514 -17.82172) (xy 34.717767 -17.747836) (xy 34.679033 -17.670047)
			(xy 34.647641 -17.589015) (xy 34.62386 -17.505433) (xy 34.607892 -17.420013) (xy 34.599874 -17.333484)
			(xy 31.398504 -17.333484) (xy 31.396714 -17.374425) (xy 31.384954 -17.460391) (xy 31.365325 -17.544908)
			(xy 31.337994 -17.627257) (xy 31.303192 -17.706738) (xy 31.28264 -17.744948) (xy 31.272421 -17.76442)
			(xy 31.258079 -17.805984) (xy 31.251105 -17.849396) (xy 31.251708 -17.893361) (xy 31.259871 -17.936566)
			(xy 31.275349 -17.977721) (xy 31.29768 -18.015597) (xy 31.326198 -18.049064) (xy 31.360052 -18.077121)
			(xy 31.39823 -18.098932) (xy 31.439593 -18.113846) (xy 31.482905 -18.121417) (xy 31.50489 -18.121884)
			(xy 32.670496 -18.121884) (xy 33.157837 -18.609225) (xy 50.874158 -18.609225) (xy 50.874158 -18.528115)
			(xy 50.882108 -18.447396) (xy 50.897931 -18.367845) (xy 50.921476 -18.290229) (xy 50.952515 -18.215293)
			(xy 50.99075 -18.143761) (xy 51.035812 -18.076321) (xy 51.087267 -18.013622) (xy 51.14462 -17.956269)
			(xy 51.207319 -17.904814) (xy 51.274759 -17.859752) (xy 51.346291 -17.821517) (xy 51.421227 -17.790478)
			(xy 51.498843 -17.766933) (xy 51.578394 -17.75111) (xy 51.659113 -17.74316) (xy 51.699668 -17.742662)
			(xy 51.740223 -17.74316) (xy 51.820942 -17.75111) (xy 51.900493 -17.766933) (xy 51.978109 -17.790478)
			(xy 52.053045 -17.821517) (xy 52.124577 -17.859752) (xy 52.192017 -17.904814) (xy 52.254716 -17.956269)
			(xy 52.312069 -18.013622) (xy 52.363524 -18.076321) (xy 52.408586 -18.143761) (xy 52.446821 -18.215293)
			(xy 52.47786 -18.290229) (xy 52.501405 -18.367845) (xy 52.517228 -18.447396) (xy 52.525178 -18.528115)
			(xy 52.525178 -18.609225) (xy 52.517228 -18.689944) (xy 52.501405 -18.769495) (xy 52.47786 -18.847111)
			(xy 52.446821 -18.922047) (xy 52.408586 -18.993579) (xy 52.363524 -19.061019) (xy 52.312069 -19.123718)
			(xy 52.254716 -19.181071) (xy 52.192017 -19.232526) (xy 52.124577 -19.277588) (xy 52.053045 -19.315823)
			(xy 51.978109 -19.346862) (xy 51.900493 -19.370407) (xy 51.820942 -19.38623) (xy 51.740223 -19.39418)
			(xy 51.659113 -19.39418) (xy 51.578394 -19.38623) (xy 51.498843 -19.370407) (xy 51.421227 -19.346862)
			(xy 51.346291 -19.315823) (xy 51.274759 -19.277588) (xy 51.207319 -19.232526) (xy 51.14462 -19.181071)
			(xy 51.087267 -19.123718) (xy 51.035812 -19.061019) (xy 50.99075 -18.993579) (xy 50.952515 -18.922047)
			(xy 50.921476 -18.847111) (xy 50.897931 -18.769495) (xy 50.882108 -18.689944) (xy 50.874158 -18.609225)
			(xy 33.157837 -18.609225) (xy 34.215832 -19.66722) (xy 34.231662 -19.682317) (xy 34.267419 -19.707505)
			(xy 34.306962 -19.726195) (xy 34.349122 -19.737836) (xy 34.392653 -19.742083) (xy 34.436268 -19.738811)
			(xy 34.478678 -19.728117) (xy 34.518629 -19.710316) (xy 34.554941 -19.685936) (xy 34.58654 -19.655695)
			(xy 34.612493 -19.62049) (xy 34.632031 -19.581359) (xy 34.638742 -19.56054) (xy 34.651797 -19.518639)
			(xy 34.684675 -19.43726) (xy 34.724993 -19.359299) (xy 34.7724 -19.285434) (xy 34.826484 -19.216308)
			(xy 34.886773 -19.152521) (xy 34.952744 -19.094631) (xy 35.023821 -19.043139) (xy 35.099388 -18.998494)
			(xy 35.178786 -18.961084) (xy 35.261324 -18.931236) (xy 35.346284 -18.909208) (xy 35.432928 -18.895193)
			(xy 35.5205 -18.889312) (xy 35.608239 -18.891617) (xy 35.695382 -18.902087) (xy 35.78117 -18.920631)
			(xy 35.864857 -18.947089) (xy 35.945714 -18.981229) (xy 36.023038 -19.022755) (xy 36.096157 -19.071306)
			(xy 36.164434 -19.126458) (xy 36.227274 -19.187732) (xy 36.284132 -19.254596) (xy 36.334512 -19.326466)
			(xy 36.377976 -19.402718) (xy 36.414145 -19.482688) (xy 36.442706 -19.565681) (xy 36.463409 -19.650973)
			(xy 36.476075 -19.737824) (xy 36.480593 -19.825477) (xy 36.476923 -19.91317) (xy 36.465099 -20.000139)
			(xy 36.445222 -20.085628) (xy 36.417466 -20.168894) (xy 36.400232 -20.209256) (xy 36.391426 -20.230459)
			(xy 36.380742 -20.275106) (xy 36.378248 -20.320946) (xy 36.384027 -20.366488) (xy 36.397889 -20.410253)
			(xy 36.419384 -20.450817) (xy 36.447814 -20.486862) (xy 36.482255 -20.517215) (xy 36.521586 -20.540892)
			(xy 36.564529 -20.55712) (xy 36.609688 -20.565374) (xy 36.632642 -20.565872) (xy 39.1033 -20.565872)
			(xy 39.119932 -20.565284) (xy 39.152049 -20.55661) (xy 39.180832 -20.539929) (xy 39.192962 -20.528534)
			(xy 39.437564 -20.283932) (xy 50.988722 -20.283932) (xy 60.564268 -29.859732) (xy 60.576403 -29.871099)
			(xy 60.605201 -29.887694) (xy 60.637311 -29.896279) (xy 60.65393 -29.896816) (xy 64.029336 -29.896816)
			(xy 64.045951 -29.896246) (xy 64.078052 -29.88766) (xy 64.106848 -29.871078) (xy 64.118998 -29.859732)
			(xy 64.96812 -29.010356) (xy 64.990853 -28.988354) (xy 65.041045 -28.949841) (xy 65.095834 -28.918208)
			(xy 65.154284 -28.893997) (xy 65.215393 -28.877623) (xy 65.278117 -28.869365) (xy 65.341383 -28.869365)
			(xy 65.404107 -28.877623) (xy 65.465216 -28.893997) (xy 65.523666 -28.918208) (xy 65.578455 -28.949841)
			(xy 65.628647 -28.988354) (xy 65.673382 -29.033089) (xy 65.711895 -29.083281) (xy 65.743528 -29.13807)
			(xy 65.767739 -29.19652) (xy 65.784113 -29.257629) (xy 65.792371 -29.320353) (xy 65.792371 -29.383619)
			(xy 65.784113 -29.446343) (xy 65.767739 -29.507452) (xy 65.743528 -29.565902) (xy 65.711895 -29.620691)
			(xy 65.673382 -29.670883) (xy 65.65138 -29.693616) (xy 64.445134 -30.899608) (xy 64.43365 -30.91172)
			(xy 64.416943 -30.940604) (xy 64.408295 -30.972833) (xy 64.4083 -31.006201) (xy 64.416956 -31.038427)
			(xy 64.43367 -31.067307) (xy 64.445134 -31.07944) (xy 65.606168 -32.240474) (xy 65.614377 -32.248956)
			(xy 72.868285 -32.248956) (xy 72.874295 -32.046255) (xy 72.888307 -31.84395) (xy 72.910302 -31.642356)
			(xy 72.940243 -31.441789) (xy 72.978084 -31.242561) (xy 73.023767 -31.044983) (xy 73.07722 -30.849365)
			(xy 73.138359 -30.656011) (xy 73.20709 -30.465223) (xy 73.283304 -30.2773) (xy 73.366883 -30.092534)
			(xy 73.457696 -29.911215) (xy 73.555601 -29.733625) (xy 73.660446 -29.560041) (xy 73.772067 -29.390735)
			(xy 73.890289 -29.22597) (xy 74.014929 -29.066005) (xy 74.14579 -28.911089) (xy 74.28267 -28.761464)
			(xy 74.425354 -28.617364) (xy 74.57362 -28.479012) (xy 74.727236 -28.346627) (xy 74.885961 -28.220413)
			(xy 75.04955 -28.100569) (xy 75.217745 -27.987281) (xy 75.390284 -27.880726) (xy 75.566899 -27.781071)
			(xy 75.747312 -27.688471) (xy 75.931243 -27.603071) (xy 76.118404 -27.525004) (xy 76.308504 -27.454392)
			(xy 76.501244 -27.391346) (xy 76.696325 -27.335963) (xy 76.893442 -27.288331) (xy 77.092286 -27.248523)
			(xy 77.292548 -27.216601) (xy 77.493914 -27.192617) (xy 77.696071 -27.176606) (xy 77.898703 -27.168595)
			(xy 78.000098 -27.168094) (xy 78.101493 -27.168595) (xy 78.304125 -27.176606) (xy 78.506282 -27.192617)
			(xy 78.707648 -27.216601) (xy 78.90791 -27.248523) (xy 79.106754 -27.288331) (xy 79.303871 -27.335963)
			(xy 79.498952 -27.391346) (xy 79.691692 -27.454392) (xy 79.881792 -27.525004) (xy 80.068953 -27.603071)
			(xy 80.252884 -27.688471) (xy 80.433297 -27.781071) (xy 80.609912 -27.880726) (xy 80.782451 -27.987281)
			(xy 80.950646 -28.100569) (xy 81.114235 -28.220413) (xy 81.27296 -28.346627) (xy 81.426576 -28.479012)
			(xy 81.574842 -28.617364) (xy 81.717526 -28.761464) (xy 81.854406 -28.911089) (xy 81.985267 -29.066005)
			(xy 82.109907 -29.22597) (xy 82.228129 -29.390735) (xy 82.33975 -29.560041) (xy 82.444595 -29.733625)
			(xy 82.5425 -29.911215) (xy 82.633313 -30.092534) (xy 82.716892 -30.2773) (xy 82.793106 -30.465223)
			(xy 82.861837 -30.656011) (xy 82.922976 -30.849365) (xy 82.976429 -31.044983) (xy 83.022112 -31.242561)
			(xy 83.059953 -31.441789) (xy 83.089894 -31.642356) (xy 83.111889 -31.84395) (xy 83.125901 -32.046255)
			(xy 83.131911 -32.248956) (xy 83.129907 -32.451736) (xy 83.119894 -32.654279) (xy 83.101887 -32.856268)
			(xy 83.075915 -33.057387) (xy 83.042017 -33.257324) (xy 83.000246 -33.455766) (xy 82.950669 -33.652402)
			(xy 82.893361 -33.846926) (xy 82.828414 -34.039034) (xy 82.755927 -34.228427) (xy 82.676015 -34.414808)
			(xy 82.588803 -34.597886) (xy 82.494425 -34.777376) (xy 82.39303 -34.952997) (xy 82.284776 -35.124476)
			(xy 82.169832 -35.291543) (xy 82.048377 -35.45394) (xy 81.920602 -35.611411) (xy 81.786705 -35.763711)
			(xy 81.646896 -35.910603) (xy 81.501392 -36.051856) (xy 81.350422 -36.187251) (xy 81.194221 -36.316576)
			(xy 81.033032 -36.439629) (xy 80.867108 -36.556218) (xy 80.696708 -36.666161) (xy 80.522097 -36.769286)
			(xy 80.343548 -36.865432) (xy 80.16134 -36.95445) (xy 79.975758 -37.036199) (xy 79.787091 -37.110553)
			(xy 79.595633 -37.177395) (xy 79.401685 -37.236621) (xy 79.205548 -37.288139) (xy 79.007529 -37.331868)
			(xy 78.807937 -37.367739) (xy 78.607083 -37.395698) (xy 78.405282 -37.415699) (xy 78.202848 -37.427712)
			(xy 78.000098 -37.431719) (xy 77.797348 -37.427712) (xy 77.594914 -37.415699) (xy 77.393113 -37.395698)
			(xy 77.192259 -37.367739) (xy 76.992667 -37.331868) (xy 76.794648 -37.288139) (xy 76.598511 -37.236621)
			(xy 76.404563 -37.177395) (xy 76.213105 -37.110553) (xy 76.024438 -37.036199) (xy 75.838856 -36.95445)
			(xy 75.656648 -36.865432) (xy 75.478099 -36.769286) (xy 75.303488 -36.666161) (xy 75.133088 -36.556218)
			(xy 74.967164 -36.439629) (xy 74.805975 -36.316576) (xy 74.649774 -36.187251) (xy 74.498804 -36.051856)
			(xy 74.3533 -35.910603) (xy 74.213491 -35.763711) (xy 74.079594 -35.611411) (xy 73.951819 -35.45394)
			(xy 73.830364 -35.291543) (xy 73.71542 -35.124476) (xy 73.607166 -34.952997) (xy 73.505771 -34.777376)
			(xy 73.411393 -34.597886) (xy 73.324181 -34.414808) (xy 73.244269 -34.228427) (xy 73.171782 -34.039034)
			(xy 73.106835 -33.846926) (xy 73.049527 -33.652402) (xy 72.99995 -33.455766) (xy 72.958179 -33.257324)
			(xy 72.924281 -33.057387) (xy 72.898309 -32.856268) (xy 72.880302 -32.654279) (xy 72.870289 -32.451736)
			(xy 72.868285 -32.248956) (xy 65.614377 -32.248956) (xy 65.62817 -32.263207) (xy 65.666683 -32.313399)
			(xy 65.698316 -32.368188) (xy 65.722527 -32.426638) (xy 65.738901 -32.487747) (xy 65.747159 -32.550471)
			(xy 65.747159 -32.613737) (xy 65.738901 -32.676461) (xy 65.722527 -32.73757) (xy 65.698316 -32.79602)
			(xy 65.666683 -32.850809) (xy 65.62817 -32.901001) (xy 65.583435 -32.945736) (xy 65.533243 -32.984249)
			(xy 65.478454 -33.015882) (xy 65.420004 -33.040093) (xy 65.358895 -33.056467) (xy 65.296171 -33.064725)
			(xy 65.232905 -33.064725) (xy 65.170181 -33.056467) (xy 65.109072 -33.040093) (xy 65.050622 -33.015882)
			(xy 64.995833 -32.984249) (xy 64.945641 -32.945736) (xy 64.922908 -32.923734) (xy 63.68923 -31.690056)
			(xy 59.858148 -31.690056) (xy 50.282602 -22.114256) (xy 50.270466 -22.102889) (xy 50.24167 -22.08629)
			(xy 50.209559 -22.077706) (xy 50.19294 -22.077172) (xy 41.613836 -22.077172) (xy 41.590582 -22.077692)
			(xy 41.544851 -22.086164) (xy 41.501425 -22.102815) (xy 41.461753 -22.127088) (xy 41.427159 -22.158174)
			(xy 41.398798 -22.195034) (xy 41.377615 -22.236439) (xy 41.364319 -22.281006) (xy 41.359352 -22.327249)
			(xy 41.360598 -22.350476) (xy 41.362221 -22.378223) (xy 41.358349 -22.433668) (xy 41.346476 -22.487965)
			(xy 41.326851 -22.539966) (xy 41.29989 -22.588569) (xy 41.266164 -22.632747) (xy 41.226386 -22.671566)
			(xy 41.181398 -22.704203) (xy 41.13215 -22.729969) (xy 41.079686 -22.748318) (xy 41.052496 -22.754082)
			(xy 41.029443 -22.759068) (xy 40.985596 -22.776435) (xy 40.945704 -22.80159) (xy 40.911134 -22.83367)
			(xy 40.883073 -22.871574) (xy 40.862481 -22.914002) (xy 40.850067 -22.9595) (xy 40.846255 -23.006507)
			(xy 40.851176 -23.05341) (xy 40.857424 -23.076154) (xy 40.864896 -23.102972) (xy 40.872914 -23.15806)
			(xy 40.872842 -23.213729) (xy 40.864681 -23.268797) (xy 40.848605 -23.322094) (xy 40.824956 -23.37249)
			(xy 40.794234 -23.418914) (xy 40.757093 -23.460382) (xy 40.71432 -23.496012) (xy 40.666824 -23.525049)
			(xy 40.615613 -23.546877) (xy 40.561774 -23.561031) (xy 40.506449 -23.567212) (xy 40.450813 -23.565289)
			(xy 40.396047 -23.555301) (xy 40.343314 -23.537461) (xy 40.293733 -23.512149) (xy 40.248356 -23.4799)
			(xy 40.208147 -23.4414) (xy 40.173959 -23.397466) (xy 40.146517 -23.349031) (xy 40.126405 -23.297122)
			(xy 40.114049 -23.242841) (xy 40.109712 -23.187342) (xy 40.113485 -23.131801) (xy 40.125288 -23.077398)
			(xy 40.144872 -23.025287) (xy 40.17182 -22.976575) (xy 40.20556 -22.932296) (xy 40.245376 -22.893389)
			(xy 40.290422 -22.860681) (xy 40.339744 -22.834866) (xy 40.392293 -22.816491) (xy 40.419528 -22.810724)
			(xy 40.442583 -22.805747) (xy 40.486428 -22.788376) (xy 40.526319 -22.763219) (xy 40.560887 -22.731138)
			(xy 40.588948 -22.693233) (xy 40.609539 -22.650804) (xy 40.621954 -22.605306) (xy 40.625767 -22.5583)
			(xy 40.620847 -22.511396) (xy 40.6146 -22.488652) (xy 40.606405 -22.459142) (xy 40.598486 -22.398414)
			(xy 40.600365 -22.3372) (xy 40.611995 -22.277073) (xy 40.621966 -22.248114) (xy 40.629586 -22.226778)
			(xy 40.629586 -22.204172) (xy 40.629081 -22.187521) (xy 40.620455 -22.155356) (xy 40.603799 -22.126519)
			(xy 40.580248 -22.102975) (xy 40.551405 -22.086328) (xy 40.519237 -22.077713) (xy 40.502586 -22.077172)
			(xy 40.360854 -22.077172) (xy 40.32912 -22.076662) (xy 40.266202 -22.068333) (xy 40.204915 -22.051838)
			(xy 40.146316 -22.027462) (xy 40.091413 -21.995623) (xy 40.04115 -21.95687) (xy 39.996394 -21.91187)
			(xy 39.957915 -21.861397) (xy 39.926376 -21.806321) (xy 39.902319 -21.74759) (xy 39.886158 -21.686214)
			(xy 39.878172 -21.623252) (xy 39.878498 -21.559785) (xy 39.882318 -21.528278) (xy 39.886382 -21.49856)
			(xy 39.867332 -21.441918) (xy 39.846504 -21.42109) (xy 39.834372 -21.409629) (xy 39.805493 -21.39292)
			(xy 39.77327 -21.384269) (xy 39.739906 -21.384269) (xy 39.707683 -21.39292) (xy 39.678804 -21.409629)
			(xy 39.666672 -21.42109) (xy 39.556182 -21.53158) (xy 36.581334 -21.53158) (xy 36.559274 -21.532048)
			(xy 36.515816 -21.539662) (xy 36.474325 -21.554667) (xy 36.43605 -21.576612) (xy 36.402139 -21.604837)
			(xy 36.373613 -21.638495) (xy 36.351328 -21.676573) (xy 36.335955 -21.717928) (xy 36.327954 -21.761317)
			(xy 36.327567 -21.805436) (xy 36.334805 -21.848958) (xy 36.349451 -21.890577) (xy 36.359846 -21.91004)
			(xy 36.380422 -21.94772) (xy 36.41542 -22.026122) (xy 36.443124 -22.107387) (xy 36.463304 -22.19084)
			(xy 36.475793 -22.275786) (xy 36.480485 -22.361516) (xy 36.477341 -22.447317) (xy 36.466389 -22.532474)
			(xy 36.447719 -22.616277) (xy 36.421486 -22.69803) (xy 36.38791 -22.777051) (xy 36.347269 -22.852681)
			(xy 36.299903 -22.924292) (xy 36.246205 -22.991286) (xy 36.186624 -23.053106) (xy 36.121654 -23.109236)
			(xy 36.051838 -23.15921) (xy 35.977757 -23.202611) (xy 35.900027 -23.239077) (xy 35.819297 -23.268305)
			(xy 35.736238 -23.290051) (xy 35.651543 -23.304135) (xy 35.565916 -23.310439) (xy 35.480071 -23.30891)
			(xy 35.394724 -23.299561) (xy 35.310583 -23.28247) (xy 35.228352 -23.25778) (xy 35.148713 -23.225695)
			(xy 35.072332 -23.186484) (xy 34.999843 -23.140473) (xy 34.931851 -23.088045) (xy 34.868921 -23.029637)
			(xy 34.811579 -22.965734) (xy 34.760301 -22.896871) (xy 34.715515 -22.823619) (xy 34.677593 -22.746589)
			(xy 34.646852 -22.666422) (xy 34.623547 -22.583787) (xy 34.607873 -22.499372) (xy 34.59996 -22.413879)
			(xy 34.599874 -22.328021) (xy 34.607616 -22.242512) (xy 34.623122 -22.158065) (xy 34.646261 -22.075384)
			(xy 34.676842 -21.995156) (xy 34.714609 -21.918051) (xy 34.759249 -21.844709) (xy 34.810389 -21.775743)
			(xy 34.83864 -21.743416) (xy 34.870898 -21.707094) (xy 34.870898 -21.65858) (xy 34.870374 -21.641931)
			(xy 34.861752 -21.609767) (xy 34.845099 -21.580932) (xy 34.821551 -21.557388) (xy 34.792712 -21.54074)
			(xy 34.760547 -21.532123) (xy 34.743898 -21.53158) (xy 34.71418 -21.53158) (xy 32.270192 -19.087592)
			(xy 31.549594 -19.087592) (xy 31.526571 -19.088072) (xy 31.481274 -19.09635) (xy 31.43821 -19.112653)
			(xy 31.398787 -19.136446) (xy 31.364296 -19.166953) (xy 31.335864 -19.203173) (xy 31.314423 -19.243923)
			(xy 31.300672 -19.287868) (xy 31.295064 -19.333572) (xy 31.29778 -19.379539) (xy 31.308733 -19.424264)
			(xy 31.317692 -19.445478) (xy 31.335063 -19.485438) (xy 31.363191 -19.567911) (xy 31.383569 -19.652633)
			(xy 31.39602 -19.738878) (xy 31.400437 -19.825904) (xy 31.396784 -19.912966) (xy 31.385091 -19.999316)
			(xy 31.365458 -20.084214) (xy 31.338054 -20.166931) (xy 31.303115 -20.246758) (xy 31.260939 -20.32301)
			(xy 31.211889 -20.395032) (xy 31.156386 -20.462207) (xy 31.094905 -20.523958) (xy 31.027975 -20.579756)
			(xy 30.956168 -20.629121) (xy 30.880103 -20.671631) (xy 30.80043 -20.706921) (xy 30.717834 -20.734687)
			(xy 30.633023 -20.754693) (xy 30.546725 -20.766765) (xy 30.45968 -20.7708) (xy 30.372635 -20.766765)
			(xy 30.286337 -20.754693) (xy 30.201526 -20.734687) (xy 30.11893 -20.706921) (xy 30.039257 -20.671631)
			(xy 29.963192 -20.629121) (xy 29.891385 -20.579756) (xy 29.824455 -20.523958) (xy 29.762974 -20.462207)
			(xy 29.707471 -20.395032) (xy 29.658421 -20.32301) (xy 29.616245 -20.246758) (xy 29.581306 -20.166931)
			(xy 29.553902 -20.084214) (xy 29.534269 -19.999316) (xy 29.522576 -19.912966) (xy 29.518923 -19.825904)
			(xy 29.52334 -19.738878) (xy 29.535791 -19.652633) (xy 29.556169 -19.567911) (xy 29.584297 -19.485438)
			(xy 29.601668 -19.445478) (xy 29.610599 -19.424258) (xy 29.621525 -19.379539) (xy 29.624223 -19.333585)
			(xy 29.618603 -19.287895) (xy 29.60485 -19.243963) (xy 29.583412 -19.203226) (xy 29.55499 -19.167013)
			(xy 29.520513 -19.136509) (xy 29.481108 -19.112711) (xy 29.438063 -19.096395) (xy 29.392783 -19.088096)
			(xy 29.369766 -19.087592) (xy 28.84424 -19.087592) (xy 28.589478 -18.833084) (xy 27.244802 -18.833084)
			(xy 27.213168 -18.832637) (xy 27.150442 -18.824379) (xy 27.08933 -18.808005) (xy 27.030878 -18.783793)
			(xy 26.976087 -18.75216) (xy 26.925893 -18.713645) (xy 26.881156 -18.668908) (xy 26.842641 -18.618715)
			(xy 26.811008 -18.563923) (xy 26.786796 -18.505472) (xy 26.770421 -18.44436) (xy 26.762163 -18.381634)
			(xy 0.509016 -18.381634) (xy 0.509016 -21.618974) (xy 26.850339 -21.618974) (xy 26.856439 -21.563537)
			(xy 26.870545 -21.50958) (xy 26.892357 -21.458251) (xy 26.921411 -21.410645) (xy 26.957086 -21.367777)
			(xy 26.998623 -21.33056) (xy 27.045136 -21.299787) (xy 27.095633 -21.276115) (xy 27.14904 -21.260047)
			(xy 27.204216 -21.251927) (xy 27.232102 -21.251418) (xy 27.259988 -21.251927) (xy 27.315164 -21.260047)
			(xy 27.368571 -21.276115) (xy 27.419068 -21.299787) (xy 27.465581 -21.33056) (xy 27.507118 -21.367777)
			(xy 27.542793 -21.410645) (xy 27.571847 -21.458251) (xy 27.593659 -21.50958) (xy 27.607765 -21.563537)
			(xy 27.613865 -21.618974) (xy 27.611828 -21.674708) (xy 27.601698 -21.729551) (xy 27.583691 -21.782335)
			(xy 27.55819 -21.831935) (xy 27.525739 -21.877293) (xy 27.48703 -21.917442) (xy 27.442887 -21.951528)
			(xy 27.394252 -21.978824) (xy 27.342161 -21.998747) (xy 27.287724 -22.010873) (xy 27.232102 -22.014944)
			(xy 27.17648 -22.010873) (xy 27.122043 -21.998747) (xy 27.069952 -21.978824) (xy 27.021317 -21.951528)
			(xy 26.977174 -21.917442) (xy 26.938465 -21.877293) (xy 26.906014 -21.831935) (xy 26.880513 -21.782335)
			(xy 26.862506 -21.729551) (xy 26.852376 -21.674708) (xy 26.850339 -21.618974) (xy 0.509016 -21.618974)
			(xy 0.509016 -22.413484) (xy 29.519874 -22.413484) (xy 29.519874 -22.326584) (xy 29.527892 -22.240055)
			(xy 29.54386 -22.154635) (xy 29.567641 -22.071053) (xy 29.599033 -21.990021) (xy 29.637767 -21.912232)
			(xy 29.683514 -21.838348) (xy 29.735883 -21.769001) (xy 29.794427 -21.704781) (xy 29.858647 -21.646237)
			(xy 29.927994 -21.593868) (xy 30.001878 -21.548121) (xy 30.079667 -21.509387) (xy 30.160699 -21.477995)
			(xy 30.244281 -21.454214) (xy 30.329701 -21.438246) (xy 30.41623 -21.430228) (xy 30.45968 -21.429726)
			(xy 30.50313 -21.430228) (xy 30.589659 -21.438246) (xy 30.675079 -21.454214) (xy 30.758661 -21.477995)
			(xy 30.839693 -21.509387) (xy 30.917482 -21.548121) (xy 30.991366 -21.593868) (xy 31.060713 -21.646237)
			(xy 31.124933 -21.704781) (xy 31.183477 -21.769001) (xy 31.235846 -21.838348) (xy 31.281593 -21.912232)
			(xy 31.320327 -21.990021) (xy 31.351719 -22.071053) (xy 31.3755 -22.154635) (xy 31.391468 -22.240055)
			(xy 31.399486 -22.326584) (xy 31.399486 -22.413484) (xy 31.391468 -22.500013) (xy 31.3755 -22.585433)
			(xy 31.351719 -22.669015) (xy 31.320327 -22.750047) (xy 31.281593 -22.827836) (xy 31.235846 -22.90172)
			(xy 31.183477 -22.971067) (xy 31.124933 -23.035287) (xy 31.060713 -23.093831) (xy 30.991366 -23.1462)
			(xy 30.917482 -23.191947) (xy 30.839693 -23.230681) (xy 30.758661 -23.262073) (xy 30.675079 -23.285854)
			(xy 30.589659 -23.301822) (xy 30.50313 -23.30984) (xy 30.41623 -23.30984) (xy 30.329701 -23.301822)
			(xy 30.244281 -23.285854) (xy 30.160699 -23.262073) (xy 30.079667 -23.230681) (xy 30.001878 -23.191947)
			(xy 29.927994 -23.1462) (xy 29.858647 -23.093831) (xy 29.794427 -23.035287) (xy 29.735883 -22.971067)
			(xy 29.683514 -22.90172) (xy 29.637767 -22.827836) (xy 29.599033 -22.750047) (xy 29.567641 -22.669015)
			(xy 29.54386 -22.585433) (xy 29.527892 -22.500013) (xy 29.519874 -22.413484) (xy 0.509016 -22.413484)
			(xy 0.509016 -29.19984) (xy 11.345164 -29.19984) (xy 11.345675 -29.09666) (xy 11.353776 -28.890459)
			(xy 11.369967 -28.684735) (xy 11.394222 -28.479805) (xy 11.426504 -28.275986) (xy 11.466763 -28.073591)
			(xy 11.514936 -27.872932) (xy 11.570951 -27.67432) (xy 11.63472 -27.47806) (xy 11.706144 -27.284454)
			(xy 11.785115 -27.093802) (xy 11.87151 -26.906398) (xy 11.965195 -26.722529) (xy 12.066027 -26.542481)
			(xy 12.17385 -26.36653) (xy 12.288497 -26.194948) (xy 12.409793 -26.027999) (xy 12.537549 -25.865941)
			(xy 12.671569 -25.709023) (xy 12.811647 -25.557488) (xy 12.957565 -25.411569) (xy 13.1091 -25.271492)
			(xy 13.266018 -25.137472) (xy 13.428076 -25.009715) (xy 13.595024 -24.88842) (xy 13.766607 -24.773772)
			(xy 13.942558 -24.665949) (xy 14.122606 -24.565117) (xy 14.306474 -24.471431) (xy 14.493879 -24.385037)
			(xy 14.68453 -24.306066) (xy 14.878136 -24.234641) (xy 15.074396 -24.170872) (xy 15.273008 -24.114857)
			(xy 15.473667 -24.066684) (xy 15.676062 -24.026425) (xy 15.879881 -23.994143) (xy 16.084811 -23.969887)
			(xy 16.290535 -23.953696) (xy 16.496736 -23.945595) (xy 16.599916 -23.945088) (xy 16.703096 -23.945592)
			(xy 16.909298 -23.953693) (xy 17.115022 -23.969884) (xy 17.319952 -23.994139) (xy 17.523772 -24.026421)
			(xy 17.726167 -24.06668) (xy 17.926826 -24.114853) (xy 18.125439 -24.170868) (xy 18.321699 -24.234637)
			(xy 18.515305 -24.306061) (xy 18.705957 -24.385032) (xy 18.893362 -24.471427) (xy 19.07723 -24.565112)
			(xy 19.257279 -24.665944) (xy 19.43323 -24.773767) (xy 19.604813 -24.888415) (xy 19.771762 -25.00971)
			(xy 19.933821 -25.137467) (xy 20.090738 -25.271487) (xy 20.242274 -25.411565) (xy 20.388192 -25.557484)
			(xy 20.52827 -25.709019) (xy 20.662291 -25.865936) (xy 20.790047 -26.027995) (xy 20.911343 -26.194944)
			(xy 21.025991 -26.366526) (xy 21.133814 -26.542477) (xy 21.234646 -26.722526) (xy 21.328332 -26.906395)
			(xy 21.414726 -27.093799) (xy 21.493697 -27.284452) (xy 21.565122 -27.478057) (xy 21.628891 -27.674318)
			(xy 21.684906 -27.87293) (xy 21.73308 -28.073589) (xy 21.773338 -28.275984) (xy 21.80562 -28.479804)
			(xy 21.829875 -28.684734) (xy 21.846066 -28.890458) (xy 21.854168 -29.09666) (xy 21.854668 -29.19984)
			(xy 21.854162 -29.303009) (xy 21.846061 -29.509187) (xy 21.829873 -29.714889) (xy 21.805622 -29.919796)
			(xy 21.773346 -30.123594) (xy 21.733094 -30.325967) (xy 21.684928 -30.526604) (xy 21.628923 -30.725196)
			(xy 21.565165 -30.921436) (xy 21.493753 -31.115022) (xy 21.414795 -31.305655) (xy 21.328415 -31.493041)
			(xy 21.234745 -31.676892) (xy 21.13393 -31.856924) (xy 21.026125 -32.032859) (xy 20.911496 -32.204427)
			(xy 20.79022 -32.371362) (xy 20.662484 -32.533408) (xy 20.528486 -32.690314) (xy 20.388431 -32.841839)
			(xy 20.242535 -32.987748) (xy 20.091024 -33.127818) (xy 19.93413 -33.261832) (xy 19.772097 -33.389583)
			(xy 19.605174 -33.510875) (xy 19.433617 -33.625521) (xy 19.257692 -33.733343) (xy 19.07767 -33.834176)
			(xy 18.893828 -33.927863) (xy 18.70645 -34.014262) (xy 18.515825 -34.093237) (xy 18.322246 -34.164669)
			(xy 18.126012 -34.228446) (xy 17.927426 -34.28447) (xy 17.726794 -34.332655) (xy 17.524424 -34.372927)
			(xy 17.32063 -34.405223) (xy 17.115725 -34.429494) (xy 16.910024 -34.445701) (xy 16.703847 -34.453822)
			(xy 16.600678 -34.454338) (xy 16.599154 -34.454338) (xy 16.495985 -34.45382) (xy 16.289808 -34.4457)
			(xy 16.084108 -34.429492) (xy 15.879202 -34.405221) (xy 15.675408 -34.372925) (xy 15.473039 -34.332654)
			(xy 15.272406 -34.284469) (xy 15.07382 -34.228444) (xy 14.877586 -34.164668) (xy 14.684007 -34.093236)
			(xy 14.493382 -34.01426) (xy 14.306004 -33.927862) (xy 14.122162 -33.834174) (xy 13.94214 -33.733342)
			(xy 13.766215 -33.62552) (xy 13.594659 -33.510874) (xy 13.427735 -33.389583) (xy 13.265702 -33.261831)
			(xy 13.108808 -33.127817) (xy 12.957297 -32.987748) (xy 12.811402 -32.841838) (xy 12.671346 -32.690313)
			(xy 12.537348 -32.533407) (xy 12.409612 -32.371362) (xy 12.288336 -32.204426) (xy 12.173707 -32.032859)
			(xy 12.065902 -31.856923) (xy 11.965087 -31.676892) (xy 11.871417 -31.493041) (xy 11.785037 -31.305654)
			(xy 11.706079 -31.115021) (xy 11.634667 -30.921436) (xy 11.570909 -30.725196) (xy 11.514904 -30.526604)
			(xy 11.466738 -30.325967) (xy 11.426486 -30.123594) (xy 11.39421 -29.919796) (xy 11.369959 -29.714889)
			(xy 11.353771 -29.509187) (xy 11.34567 -29.303009) (xy 11.345164 -29.19984) (xy 0.509016 -29.19984)
			(xy 0.509016 -38.661255) (xy 51.008016 -38.661255) (xy 51.008016 -38.580145) (xy 51.015966 -38.499426)
			(xy 51.031789 -38.419875) (xy 51.055334 -38.342259) (xy 51.086373 -38.267323) (xy 51.124608 -38.195791)
			(xy 51.16967 -38.128351) (xy 51.221125 -38.065652) (xy 51.278478 -38.008299) (xy 51.341177 -37.956844)
			(xy 51.408617 -37.911782) (xy 51.480149 -37.873547) (xy 51.555085 -37.842508) (xy 51.632701 -37.818963)
			(xy 51.712252 -37.80314) (xy 51.792971 -37.79519) (xy 51.833526 -37.794692) (xy 51.874081 -37.79519)
			(xy 51.9548 -37.80314) (xy 52.034351 -37.818963) (xy 52.111967 -37.842508) (xy 52.186903 -37.873547)
			(xy 52.258435 -37.911782) (xy 52.325875 -37.956844) (xy 52.388574 -38.008299) (xy 52.445927 -38.065652)
			(xy 52.497382 -38.128351) (xy 52.542444 -38.195791) (xy 52.580679 -38.267323) (xy 52.611718 -38.342259)
			(xy 52.635263 -38.419875) (xy 52.651086 -38.499426) (xy 52.659036 -38.580145) (xy 52.659036 -38.661255)
			(xy 52.651086 -38.741974) (xy 52.635263 -38.821525) (xy 52.611718 -38.899141) (xy 52.580679 -38.974077)
			(xy 52.542444 -39.045609) (xy 52.497382 -39.113049) (xy 52.473199 -39.142517) (xy 55.93892 -39.142517)
			(xy 55.93892 -39.071195) (xy 55.946906 -39.000321) (xy 55.962776 -38.930786) (xy 55.986333 -38.863466)
			(xy 56.017278 -38.799207) (xy 56.055224 -38.738816) (xy 56.099693 -38.683054) (xy 56.150126 -38.632621)
			(xy 56.205888 -38.588152) (xy 56.266279 -38.550206) (xy 56.330538 -38.519261) (xy 56.397858 -38.495704)
			(xy 56.467393 -38.479834) (xy 56.538267 -38.471848) (xy 56.573928 -38.471348) (xy 56.609589 -38.471848)
			(xy 56.680463 -38.479834) (xy 56.749998 -38.495704) (xy 56.817318 -38.519261) (xy 56.881577 -38.550206)
			(xy 56.941968 -38.588152) (xy 56.99773 -38.632621) (xy 57.048163 -38.683054) (xy 57.092632 -38.738816)
			(xy 57.130578 -38.799207) (xy 57.161523 -38.863466) (xy 57.18508 -38.930786) (xy 57.20095 -39.000321)
			(xy 57.208936 -39.071195) (xy 57.208936 -39.142517) (xy 58.470792 -39.142517) (xy 58.470792 -39.071195)
			(xy 58.478778 -39.000321) (xy 58.494648 -38.930786) (xy 58.518205 -38.863466) (xy 58.54915 -38.799207)
			(xy 58.587096 -38.738816) (xy 58.631565 -38.683054) (xy 58.681998 -38.632621) (xy 58.73776 -38.588152)
			(xy 58.798151 -38.550206) (xy 58.86241 -38.519261) (xy 58.92973 -38.495704) (xy 58.999265 -38.479834)
			(xy 59.070139 -38.471848) (xy 59.1058 -38.471348) (xy 59.141461 -38.471848) (xy 59.212335 -38.479834)
			(xy 59.28187 -38.495704) (xy 59.34919 -38.519261) (xy 59.413449 -38.550206) (xy 59.47384 -38.588152)
			(xy 59.529602 -38.632621) (xy 59.580035 -38.683054) (xy 59.624504 -38.738816) (xy 59.66245 -38.799207)
			(xy 59.693395 -38.863466) (xy 59.716952 -38.930786) (xy 59.732822 -39.000321) (xy 59.740808 -39.071195)
			(xy 59.740808 -39.142517) (xy 61.275206 -39.142517) (xy 61.275206 -39.071195) (xy 61.283192 -39.000321)
			(xy 61.299062 -38.930786) (xy 61.322619 -38.863466) (xy 61.353564 -38.799207) (xy 61.39151 -38.738816)
			(xy 61.435979 -38.683054) (xy 61.486412 -38.632621) (xy 61.542174 -38.588152) (xy 61.602565 -38.550206)
			(xy 61.666824 -38.519261) (xy 61.734144 -38.495704) (xy 61.803679 -38.479834) (xy 61.874553 -38.471848)
			(xy 61.910214 -38.471348) (xy 61.945875 -38.471848) (xy 62.016749 -38.479834) (xy 62.086284 -38.495704)
			(xy 62.153604 -38.519261) (xy 62.217863 -38.550206) (xy 62.278254 -38.588152) (xy 62.334016 -38.632621)
			(xy 62.384449 -38.683054) (xy 62.428918 -38.738816) (xy 62.466864 -38.799207) (xy 62.497809 -38.863466)
			(xy 62.521366 -38.930786) (xy 62.537236 -39.000321) (xy 62.545222 -39.071195) (xy 62.545222 -39.142517)
			(xy 63.648074 -39.142517) (xy 63.648074 -39.071195) (xy 63.65606 -39.000321) (xy 63.67193 -38.930786)
			(xy 63.695487 -38.863466) (xy 63.726432 -38.799207) (xy 63.764378 -38.738816) (xy 63.808847 -38.683054)
			(xy 63.85928 -38.632621) (xy 63.915042 -38.588152) (xy 63.975433 -38.550206) (xy 64.039692 -38.519261)
			(xy 64.107012 -38.495704) (xy 64.176547 -38.479834) (xy 64.247421 -38.471848) (xy 64.283082 -38.471348)
			(xy 64.318743 -38.471848) (xy 64.389617 -38.479834) (xy 64.459152 -38.495704) (xy 64.526472 -38.519261)
			(xy 64.590731 -38.550206) (xy 64.651122 -38.588152) (xy 64.706884 -38.632621) (xy 64.757317 -38.683054)
			(xy 64.801786 -38.738816) (xy 64.839732 -38.799207) (xy 64.870677 -38.863466) (xy 64.894234 -38.930786)
			(xy 64.910104 -39.000321) (xy 64.91809 -39.071195) (xy 64.91809 -39.142517) (xy 66.639686 -39.142517)
			(xy 66.639686 -39.071195) (xy 66.647672 -39.000321) (xy 66.663542 -38.930786) (xy 66.687099 -38.863466)
			(xy 66.718044 -38.799207) (xy 66.75599 -38.738816) (xy 66.800459 -38.683054) (xy 66.850892 -38.632621)
			(xy 66.906654 -38.588152) (xy 66.967045 -38.550206) (xy 67.031304 -38.519261) (xy 67.098624 -38.495704)
			(xy 67.168159 -38.479834) (xy 67.239033 -38.471848) (xy 67.274694 -38.471348) (xy 67.310355 -38.471848)
			(xy 67.381229 -38.479834) (xy 67.450764 -38.495704) (xy 67.518084 -38.519261) (xy 67.582343 -38.550206)
			(xy 67.642734 -38.588152) (xy 67.698496 -38.632621) (xy 67.748929 -38.683054) (xy 67.793398 -38.738816)
			(xy 67.831344 -38.799207) (xy 67.862289 -38.863466) (xy 67.885846 -38.930786) (xy 67.901716 -39.000321)
			(xy 67.909702 -39.071195) (xy 67.909702 -39.142517) (xy 67.901716 -39.213391) (xy 67.885846 -39.282926)
			(xy 67.862289 -39.350246) (xy 67.831344 -39.414505) (xy 67.793398 -39.474896) (xy 67.748929 -39.530658)
			(xy 67.698496 -39.581091) (xy 67.642734 -39.62556) (xy 67.582343 -39.663506) (xy 67.518084 -39.694451)
			(xy 67.450764 -39.718008) (xy 67.381229 -39.733878) (xy 67.310355 -39.741864) (xy 67.239033 -39.741864)
			(xy 67.168159 -39.733878) (xy 67.098624 -39.718008) (xy 67.031304 -39.694451) (xy 66.967045 -39.663506)
			(xy 66.906654 -39.62556) (xy 66.850892 -39.581091) (xy 66.800459 -39.530658) (xy 66.75599 -39.474896)
			(xy 66.718044 -39.414505) (xy 66.687099 -39.350246) (xy 66.663542 -39.282926) (xy 66.647672 -39.213391)
			(xy 66.639686 -39.142517) (xy 64.91809 -39.142517) (xy 64.910104 -39.213391) (xy 64.894234 -39.282926)
			(xy 64.870677 -39.350246) (xy 64.839732 -39.414505) (xy 64.801786 -39.474896) (xy 64.757317 -39.530658)
			(xy 64.706884 -39.581091) (xy 64.651122 -39.62556) (xy 64.590731 -39.663506) (xy 64.526472 -39.694451)
			(xy 64.459152 -39.718008) (xy 64.389617 -39.733878) (xy 64.318743 -39.741864) (xy 64.247421 -39.741864)
			(xy 64.176547 -39.733878) (xy 64.107012 -39.718008) (xy 64.039692 -39.694451) (xy 63.975433 -39.663506)
			(xy 63.915042 -39.62556) (xy 63.85928 -39.581091) (xy 63.808847 -39.530658) (xy 63.764378 -39.474896)
			(xy 63.726432 -39.414505) (xy 63.695487 -39.350246) (xy 63.67193 -39.282926) (xy 63.65606 -39.213391)
			(xy 63.648074 -39.142517) (xy 62.545222 -39.142517) (xy 62.537236 -39.213391) (xy 62.521366 -39.282926)
			(xy 62.497809 -39.350246) (xy 62.466864 -39.414505) (xy 62.428918 -39.474896) (xy 62.384449 -39.530658)
			(xy 62.334016 -39.581091) (xy 62.278254 -39.62556) (xy 62.217863 -39.663506) (xy 62.153604 -39.694451)
			(xy 62.086284 -39.718008) (xy 62.016749 -39.733878) (xy 61.945875 -39.741864) (xy 61.874553 -39.741864)
			(xy 61.803679 -39.733878) (xy 61.734144 -39.718008) (xy 61.666824 -39.694451) (xy 61.602565 -39.663506)
			(xy 61.542174 -39.62556) (xy 61.486412 -39.581091) (xy 61.435979 -39.530658) (xy 61.39151 -39.474896)
			(xy 61.353564 -39.414505) (xy 61.322619 -39.350246) (xy 61.299062 -39.282926) (xy 61.283192 -39.213391)
			(xy 61.275206 -39.142517) (xy 59.740808 -39.142517) (xy 59.732822 -39.213391) (xy 59.716952 -39.282926)
			(xy 59.693395 -39.350246) (xy 59.66245 -39.414505) (xy 59.624504 -39.474896) (xy 59.580035 -39.530658)
			(xy 59.529602 -39.581091) (xy 59.47384 -39.62556) (xy 59.413449 -39.663506) (xy 59.34919 -39.694451)
			(xy 59.28187 -39.718008) (xy 59.212335 -39.733878) (xy 59.141461 -39.741864) (xy 59.070139 -39.741864)
			(xy 58.999265 -39.733878) (xy 58.92973 -39.718008) (xy 58.86241 -39.694451) (xy 58.798151 -39.663506)
			(xy 58.73776 -39.62556) (xy 58.681998 -39.581091) (xy 58.631565 -39.530658) (xy 58.587096 -39.474896)
			(xy 58.54915 -39.414505) (xy 58.518205 -39.350246) (xy 58.494648 -39.282926) (xy 58.478778 -39.213391)
			(xy 58.470792 -39.142517) (xy 57.208936 -39.142517) (xy 57.20095 -39.213391) (xy 57.18508 -39.282926)
			(xy 57.161523 -39.350246) (xy 57.130578 -39.414505) (xy 57.092632 -39.474896) (xy 57.048163 -39.530658)
			(xy 56.99773 -39.581091) (xy 56.941968 -39.62556) (xy 56.881577 -39.663506) (xy 56.817318 -39.694451)
			(xy 56.749998 -39.718008) (xy 56.680463 -39.733878) (xy 56.609589 -39.741864) (xy 56.538267 -39.741864)
			(xy 56.467393 -39.733878) (xy 56.397858 -39.718008) (xy 56.330538 -39.694451) (xy 56.266279 -39.663506)
			(xy 56.205888 -39.62556) (xy 56.150126 -39.581091) (xy 56.099693 -39.530658) (xy 56.055224 -39.474896)
			(xy 56.017278 -39.414505) (xy 55.986333 -39.350246) (xy 55.962776 -39.282926) (xy 55.946906 -39.213391)
			(xy 55.93892 -39.142517) (xy 52.473199 -39.142517) (xy 52.445927 -39.175748) (xy 52.388574 -39.233101)
			(xy 52.325875 -39.284556) (xy 52.258435 -39.329618) (xy 52.186903 -39.367853) (xy 52.111967 -39.398892)
			(xy 52.034351 -39.422437) (xy 51.9548 -39.43826) (xy 51.874081 -39.44621) (xy 51.792971 -39.44621)
			(xy 51.712252 -39.43826) (xy 51.632701 -39.422437) (xy 51.555085 -39.398892) (xy 51.480149 -39.367853)
			(xy 51.408617 -39.329618) (xy 51.341177 -39.284556) (xy 51.278478 -39.233101) (xy 51.221125 -39.175748)
			(xy 51.16967 -39.113049) (xy 51.124608 -39.045609) (xy 51.086373 -38.974077) (xy 51.055334 -38.899141)
			(xy 51.031789 -38.821525) (xy 51.015966 -38.741974) (xy 51.008016 -38.661255) (xy 0.509016 -38.661255)
			(xy 0.509016 -41.105429) (xy 55.93892 -41.105429) (xy 55.93892 -41.034107) (xy 55.946906 -40.963233)
			(xy 55.962776 -40.893698) (xy 55.986333 -40.826378) (xy 56.017278 -40.762119) (xy 56.055224 -40.701728)
			(xy 56.099693 -40.645966) (xy 56.150126 -40.595533) (xy 56.205888 -40.551064) (xy 56.266279 -40.513118)
			(xy 56.330538 -40.482173) (xy 56.397858 -40.458616) (xy 56.467393 -40.442746) (xy 56.538267 -40.43476)
			(xy 56.573928 -40.43426) (xy 56.609589 -40.43476) (xy 56.680463 -40.442746) (xy 56.749998 -40.458616)
			(xy 56.817318 -40.482173) (xy 56.881577 -40.513118) (xy 56.941968 -40.551064) (xy 56.99773 -40.595533)
			(xy 57.048163 -40.645966) (xy 57.092632 -40.701728) (xy 57.130578 -40.762119) (xy 57.161523 -40.826378)
			(xy 57.18508 -40.893698) (xy 57.20095 -40.963233) (xy 57.208936 -41.034107) (xy 57.208936 -41.105429)
			(xy 58.470792 -41.105429) (xy 58.470792 -41.034107) (xy 58.478778 -40.963233) (xy 58.494648 -40.893698)
			(xy 58.518205 -40.826378) (xy 58.54915 -40.762119) (xy 58.587096 -40.701728) (xy 58.631565 -40.645966)
			(xy 58.681998 -40.595533) (xy 58.73776 -40.551064) (xy 58.798151 -40.513118) (xy 58.86241 -40.482173)
			(xy 58.92973 -40.458616) (xy 58.999265 -40.442746) (xy 59.070139 -40.43476) (xy 59.1058 -40.43426)
			(xy 59.141461 -40.43476) (xy 59.212335 -40.442746) (xy 59.28187 -40.458616) (xy 59.34919 -40.482173)
			(xy 59.413449 -40.513118) (xy 59.47384 -40.551064) (xy 59.529602 -40.595533) (xy 59.580035 -40.645966)
			(xy 59.624504 -40.701728) (xy 59.66245 -40.762119) (xy 59.693395 -40.826378) (xy 59.716952 -40.893698)
			(xy 59.732822 -40.963233) (xy 59.740808 -41.034107) (xy 59.740808 -41.105429) (xy 61.275206 -41.105429)
			(xy 61.275206 -41.034107) (xy 61.283192 -40.963233) (xy 61.299062 -40.893698) (xy 61.322619 -40.826378)
			(xy 61.353564 -40.762119) (xy 61.39151 -40.701728) (xy 61.435979 -40.645966) (xy 61.486412 -40.595533)
			(xy 61.542174 -40.551064) (xy 61.602565 -40.513118) (xy 61.666824 -40.482173) (xy 61.734144 -40.458616)
			(xy 61.803679 -40.442746) (xy 61.874553 -40.43476) (xy 61.910214 -40.43426) (xy 61.945875 -40.43476)
			(xy 62.016749 -40.442746) (xy 62.086284 -40.458616) (xy 62.153604 -40.482173) (xy 62.217863 -40.513118)
			(xy 62.278254 -40.551064) (xy 62.334016 -40.595533) (xy 62.384449 -40.645966) (xy 62.428918 -40.701728)
			(xy 62.466864 -40.762119) (xy 62.497809 -40.826378) (xy 62.521366 -40.893698) (xy 62.537236 -40.963233)
			(xy 62.545222 -41.034107) (xy 62.545222 -41.105429) (xy 63.648074 -41.105429) (xy 63.648074 -41.034107)
			(xy 63.65606 -40.963233) (xy 63.67193 -40.893698) (xy 63.695487 -40.826378) (xy 63.726432 -40.762119)
			(xy 63.764378 -40.701728) (xy 63.808847 -40.645966) (xy 63.85928 -40.595533) (xy 63.915042 -40.551064)
			(xy 63.975433 -40.513118) (xy 64.039692 -40.482173) (xy 64.107012 -40.458616) (xy 64.176547 -40.442746)
			(xy 64.247421 -40.43476) (xy 64.283082 -40.43426) (xy 64.318743 -40.43476) (xy 64.389617 -40.442746)
			(xy 64.459152 -40.458616) (xy 64.526472 -40.482173) (xy 64.590731 -40.513118) (xy 64.651122 -40.551064)
			(xy 64.706884 -40.595533) (xy 64.757317 -40.645966) (xy 64.801786 -40.701728) (xy 64.839732 -40.762119)
			(xy 64.870677 -40.826378) (xy 64.894234 -40.893698) (xy 64.910104 -40.963233) (xy 64.91809 -41.034107)
			(xy 64.91809 -41.105429) (xy 66.639686 -41.105429) (xy 66.639686 -41.034107) (xy 66.647672 -40.963233)
			(xy 66.663542 -40.893698) (xy 66.687099 -40.826378) (xy 66.718044 -40.762119) (xy 66.75599 -40.701728)
			(xy 66.800459 -40.645966) (xy 66.850892 -40.595533) (xy 66.906654 -40.551064) (xy 66.967045 -40.513118)
			(xy 67.031304 -40.482173) (xy 67.098624 -40.458616) (xy 67.168159 -40.442746) (xy 67.239033 -40.43476)
			(xy 67.274694 -40.43426) (xy 67.310355 -40.43476) (xy 67.381229 -40.442746) (xy 67.450764 -40.458616)
			(xy 67.518084 -40.482173) (xy 67.582343 -40.513118) (xy 67.642734 -40.551064) (xy 67.698496 -40.595533)
			(xy 67.748929 -40.645966) (xy 67.793398 -40.701728) (xy 67.831344 -40.762119) (xy 67.862289 -40.826378)
			(xy 67.885846 -40.893698) (xy 67.901716 -40.963233) (xy 67.909702 -41.034107) (xy 67.909702 -41.105429)
			(xy 67.901716 -41.176303) (xy 67.885846 -41.245838) (xy 67.862289 -41.313158) (xy 67.831344 -41.377417)
			(xy 67.793398 -41.437808) (xy 67.748929 -41.49357) (xy 67.698496 -41.544003) (xy 67.642734 -41.588472)
			(xy 67.582343 -41.626418) (xy 67.518084 -41.657363) (xy 67.450764 -41.68092) (xy 67.381229 -41.69679)
			(xy 67.310355 -41.704776) (xy 67.239033 -41.704776) (xy 67.168159 -41.69679) (xy 67.098624 -41.68092)
			(xy 67.031304 -41.657363) (xy 66.967045 -41.626418) (xy 66.906654 -41.588472) (xy 66.850892 -41.544003)
			(xy 66.800459 -41.49357) (xy 66.75599 -41.437808) (xy 66.718044 -41.377417) (xy 66.687099 -41.313158)
			(xy 66.663542 -41.245838) (xy 66.647672 -41.176303) (xy 66.639686 -41.105429) (xy 64.91809 -41.105429)
			(xy 64.910104 -41.176303) (xy 64.894234 -41.245838) (xy 64.870677 -41.313158) (xy 64.839732 -41.377417)
			(xy 64.801786 -41.437808) (xy 64.757317 -41.49357) (xy 64.706884 -41.544003) (xy 64.651122 -41.588472)
			(xy 64.590731 -41.626418) (xy 64.526472 -41.657363) (xy 64.459152 -41.68092) (xy 64.389617 -41.69679)
			(xy 64.318743 -41.704776) (xy 64.247421 -41.704776) (xy 64.176547 -41.69679) (xy 64.107012 -41.68092)
			(xy 64.039692 -41.657363) (xy 63.975433 -41.626418) (xy 63.915042 -41.588472) (xy 63.85928 -41.544003)
			(xy 63.808847 -41.49357) (xy 63.764378 -41.437808) (xy 63.726432 -41.377417) (xy 63.695487 -41.313158)
			(xy 63.67193 -41.245838) (xy 63.65606 -41.176303) (xy 63.648074 -41.105429) (xy 62.545222 -41.105429)
			(xy 62.537236 -41.176303) (xy 62.521366 -41.245838) (xy 62.497809 -41.313158) (xy 62.466864 -41.377417)
			(xy 62.428918 -41.437808) (xy 62.384449 -41.49357) (xy 62.334016 -41.544003) (xy 62.278254 -41.588472)
			(xy 62.217863 -41.626418) (xy 62.153604 -41.657363) (xy 62.086284 -41.68092) (xy 62.016749 -41.69679)
			(xy 61.945875 -41.704776) (xy 61.874553 -41.704776) (xy 61.803679 -41.69679) (xy 61.734144 -41.68092)
			(xy 61.666824 -41.657363) (xy 61.602565 -41.626418) (xy 61.542174 -41.588472) (xy 61.486412 -41.544003)
			(xy 61.435979 -41.49357) (xy 61.39151 -41.437808) (xy 61.353564 -41.377417) (xy 61.322619 -41.313158)
			(xy 61.299062 -41.245838) (xy 61.283192 -41.176303) (xy 61.275206 -41.105429) (xy 59.740808 -41.105429)
			(xy 59.732822 -41.176303) (xy 59.716952 -41.245838) (xy 59.693395 -41.313158) (xy 59.66245 -41.377417)
			(xy 59.624504 -41.437808) (xy 59.580035 -41.49357) (xy 59.529602 -41.544003) (xy 59.47384 -41.588472)
			(xy 59.413449 -41.626418) (xy 59.34919 -41.657363) (xy 59.28187 -41.68092) (xy 59.212335 -41.69679)
			(xy 59.141461 -41.704776) (xy 59.070139 -41.704776) (xy 58.999265 -41.69679) (xy 58.92973 -41.68092)
			(xy 58.86241 -41.657363) (xy 58.798151 -41.626418) (xy 58.73776 -41.588472) (xy 58.681998 -41.544003)
			(xy 58.631565 -41.49357) (xy 58.587096 -41.437808) (xy 58.54915 -41.377417) (xy 58.518205 -41.313158)
			(xy 58.494648 -41.245838) (xy 58.478778 -41.176303) (xy 58.470792 -41.105429) (xy 57.208936 -41.105429)
			(xy 57.20095 -41.176303) (xy 57.18508 -41.245838) (xy 57.161523 -41.313158) (xy 57.130578 -41.377417)
			(xy 57.092632 -41.437808) (xy 57.048163 -41.49357) (xy 56.99773 -41.544003) (xy 56.941968 -41.588472)
			(xy 56.881577 -41.626418) (xy 56.817318 -41.657363) (xy 56.749998 -41.68092) (xy 56.680463 -41.69679)
			(xy 56.609589 -41.704776) (xy 56.538267 -41.704776) (xy 56.467393 -41.69679) (xy 56.397858 -41.68092)
			(xy 56.330538 -41.657363) (xy 56.266279 -41.626418) (xy 56.205888 -41.588472) (xy 56.150126 -41.544003)
			(xy 56.099693 -41.49357) (xy 56.055224 -41.437808) (xy 56.017278 -41.377417) (xy 55.986333 -41.313158)
			(xy 55.962776 -41.245838) (xy 55.946906 -41.176303) (xy 55.93892 -41.105429) (xy 0.509016 -41.105429)
			(xy 0.509016 -43.248935) (xy 55.93892 -43.248935) (xy 55.93892 -43.177613) (xy 55.946906 -43.106739)
			(xy 55.962776 -43.037204) (xy 55.986333 -42.969884) (xy 56.017278 -42.905625) (xy 56.055224 -42.845234)
			(xy 56.099693 -42.789472) (xy 56.150126 -42.739039) (xy 56.205888 -42.69457) (xy 56.266279 -42.656624)
			(xy 56.330538 -42.625679) (xy 56.397858 -42.602122) (xy 56.467393 -42.586252) (xy 56.538267 -42.578266)
			(xy 56.573928 -42.577766) (xy 56.609589 -42.578266) (xy 56.680463 -42.586252) (xy 56.749998 -42.602122)
			(xy 56.817318 -42.625679) (xy 56.881577 -42.656624) (xy 56.941968 -42.69457) (xy 56.99773 -42.739039)
			(xy 57.048163 -42.789472) (xy 57.092632 -42.845234) (xy 57.130578 -42.905625) (xy 57.161523 -42.969884)
			(xy 57.18508 -43.037204) (xy 57.20095 -43.106739) (xy 57.208936 -43.177613) (xy 57.208936 -43.248935)
			(xy 58.470792 -43.248935) (xy 58.470792 -43.177613) (xy 58.478778 -43.106739) (xy 58.494648 -43.037204)
			(xy 58.518205 -42.969884) (xy 58.54915 -42.905625) (xy 58.587096 -42.845234) (xy 58.631565 -42.789472)
			(xy 58.681998 -42.739039) (xy 58.73776 -42.69457) (xy 58.798151 -42.656624) (xy 58.86241 -42.625679)
			(xy 58.92973 -42.602122) (xy 58.999265 -42.586252) (xy 59.070139 -42.578266) (xy 59.1058 -42.577766)
			(xy 59.141461 -42.578266) (xy 59.212335 -42.586252) (xy 59.28187 -42.602122) (xy 59.34919 -42.625679)
			(xy 59.413449 -42.656624) (xy 59.47384 -42.69457) (xy 59.529602 -42.739039) (xy 59.580035 -42.789472)
			(xy 59.624504 -42.845234) (xy 59.66245 -42.905625) (xy 59.693395 -42.969884) (xy 59.716952 -43.037204)
			(xy 59.732822 -43.106739) (xy 59.740808 -43.177613) (xy 59.740808 -43.248935) (xy 61.275206 -43.248935)
			(xy 61.275206 -43.177613) (xy 61.283192 -43.106739) (xy 61.299062 -43.037204) (xy 61.322619 -42.969884)
			(xy 61.353564 -42.905625) (xy 61.39151 -42.845234) (xy 61.435979 -42.789472) (xy 61.486412 -42.739039)
			(xy 61.542174 -42.69457) (xy 61.602565 -42.656624) (xy 61.666824 -42.625679) (xy 61.734144 -42.602122)
			(xy 61.803679 -42.586252) (xy 61.874553 -42.578266) (xy 61.910214 -42.577766) (xy 61.945875 -42.578266)
			(xy 62.016749 -42.586252) (xy 62.086284 -42.602122) (xy 62.153604 -42.625679) (xy 62.217863 -42.656624)
			(xy 62.278254 -42.69457) (xy 62.334016 -42.739039) (xy 62.384449 -42.789472) (xy 62.428918 -42.845234)
			(xy 62.466864 -42.905625) (xy 62.497809 -42.969884) (xy 62.521366 -43.037204) (xy 62.537236 -43.106739)
			(xy 62.545222 -43.177613) (xy 62.545222 -43.248935) (xy 63.648074 -43.248935) (xy 63.648074 -43.177613)
			(xy 63.65606 -43.106739) (xy 63.67193 -43.037204) (xy 63.695487 -42.969884) (xy 63.726432 -42.905625)
			(xy 63.764378 -42.845234) (xy 63.808847 -42.789472) (xy 63.85928 -42.739039) (xy 63.915042 -42.69457)
			(xy 63.975433 -42.656624) (xy 64.039692 -42.625679) (xy 64.107012 -42.602122) (xy 64.176547 -42.586252)
			(xy 64.247421 -42.578266) (xy 64.283082 -42.577766) (xy 64.318743 -42.578266) (xy 64.389617 -42.586252)
			(xy 64.459152 -42.602122) (xy 64.526472 -42.625679) (xy 64.590731 -42.656624) (xy 64.651122 -42.69457)
			(xy 64.706884 -42.739039) (xy 64.757317 -42.789472) (xy 64.801786 -42.845234) (xy 64.839732 -42.905625)
			(xy 64.870677 -42.969884) (xy 64.894234 -43.037204) (xy 64.910104 -43.106739) (xy 64.91809 -43.177613)
			(xy 64.91809 -43.248935) (xy 66.639686 -43.248935) (xy 66.639686 -43.177613) (xy 66.647672 -43.106739)
			(xy 66.663542 -43.037204) (xy 66.687099 -42.969884) (xy 66.718044 -42.905625) (xy 66.75599 -42.845234)
			(xy 66.800459 -42.789472) (xy 66.850892 -42.739039) (xy 66.906654 -42.69457) (xy 66.967045 -42.656624)
			(xy 67.031304 -42.625679) (xy 67.098624 -42.602122) (xy 67.168159 -42.586252) (xy 67.239033 -42.578266)
			(xy 67.274694 -42.577766) (xy 67.310355 -42.578266) (xy 67.381229 -42.586252) (xy 67.450764 -42.602122)
			(xy 67.518084 -42.625679) (xy 67.582343 -42.656624) (xy 67.642734 -42.69457) (xy 67.698496 -42.739039)
			(xy 67.748929 -42.789472) (xy 67.793398 -42.845234) (xy 67.831344 -42.905625) (xy 67.862289 -42.969884)
			(xy 67.885846 -43.037204) (xy 67.901716 -43.106739) (xy 67.909702 -43.177613) (xy 67.909702 -43.248935)
			(xy 67.901716 -43.319809) (xy 67.885846 -43.389344) (xy 67.862289 -43.456664) (xy 67.831344 -43.520923)
			(xy 67.793398 -43.581314) (xy 67.748929 -43.637076) (xy 67.698496 -43.687509) (xy 67.642734 -43.731978)
			(xy 67.582343 -43.769924) (xy 67.518084 -43.800869) (xy 67.450764 -43.824426) (xy 67.381229 -43.840296)
			(xy 67.310355 -43.848282) (xy 67.239033 -43.848282) (xy 67.168159 -43.840296) (xy 67.098624 -43.824426)
			(xy 67.031304 -43.800869) (xy 66.967045 -43.769924) (xy 66.906654 -43.731978) (xy 66.850892 -43.687509)
			(xy 66.800459 -43.637076) (xy 66.75599 -43.581314) (xy 66.718044 -43.520923) (xy 66.687099 -43.456664)
			(xy 66.663542 -43.389344) (xy 66.647672 -43.319809) (xy 66.639686 -43.248935) (xy 64.91809 -43.248935)
			(xy 64.910104 -43.319809) (xy 64.894234 -43.389344) (xy 64.870677 -43.456664) (xy 64.839732 -43.520923)
			(xy 64.801786 -43.581314) (xy 64.757317 -43.637076) (xy 64.706884 -43.687509) (xy 64.651122 -43.731978)
			(xy 64.590731 -43.769924) (xy 64.526472 -43.800869) (xy 64.459152 -43.824426) (xy 64.389617 -43.840296)
			(xy 64.318743 -43.848282) (xy 64.247421 -43.848282) (xy 64.176547 -43.840296) (xy 64.107012 -43.824426)
			(xy 64.039692 -43.800869) (xy 63.975433 -43.769924) (xy 63.915042 -43.731978) (xy 63.85928 -43.687509)
			(xy 63.808847 -43.637076) (xy 63.764378 -43.581314) (xy 63.726432 -43.520923) (xy 63.695487 -43.456664)
			(xy 63.67193 -43.389344) (xy 63.65606 -43.319809) (xy 63.648074 -43.248935) (xy 62.545222 -43.248935)
			(xy 62.537236 -43.319809) (xy 62.521366 -43.389344) (xy 62.497809 -43.456664) (xy 62.466864 -43.520923)
			(xy 62.428918 -43.581314) (xy 62.384449 -43.637076) (xy 62.334016 -43.687509) (xy 62.278254 -43.731978)
			(xy 62.217863 -43.769924) (xy 62.153604 -43.800869) (xy 62.086284 -43.824426) (xy 62.016749 -43.840296)
			(xy 61.945875 -43.848282) (xy 61.874553 -43.848282) (xy 61.803679 -43.840296) (xy 61.734144 -43.824426)
			(xy 61.666824 -43.800869) (xy 61.602565 -43.769924) (xy 61.542174 -43.731978) (xy 61.486412 -43.687509)
			(xy 61.435979 -43.637076) (xy 61.39151 -43.581314) (xy 61.353564 -43.520923) (xy 61.322619 -43.456664)
			(xy 61.299062 -43.389344) (xy 61.283192 -43.319809) (xy 61.275206 -43.248935) (xy 59.740808 -43.248935)
			(xy 59.732822 -43.319809) (xy 59.716952 -43.389344) (xy 59.693395 -43.456664) (xy 59.66245 -43.520923)
			(xy 59.624504 -43.581314) (xy 59.580035 -43.637076) (xy 59.529602 -43.687509) (xy 59.47384 -43.731978)
			(xy 59.413449 -43.769924) (xy 59.34919 -43.800869) (xy 59.28187 -43.824426) (xy 59.212335 -43.840296)
			(xy 59.141461 -43.848282) (xy 59.070139 -43.848282) (xy 58.999265 -43.840296) (xy 58.92973 -43.824426)
			(xy 58.86241 -43.800869) (xy 58.798151 -43.769924) (xy 58.73776 -43.731978) (xy 58.681998 -43.687509)
			(xy 58.631565 -43.637076) (xy 58.587096 -43.581314) (xy 58.54915 -43.520923) (xy 58.518205 -43.456664)
			(xy 58.494648 -43.389344) (xy 58.478778 -43.319809) (xy 58.470792 -43.248935) (xy 57.208936 -43.248935)
			(xy 57.20095 -43.319809) (xy 57.18508 -43.389344) (xy 57.161523 -43.456664) (xy 57.130578 -43.520923)
			(xy 57.092632 -43.581314) (xy 57.048163 -43.637076) (xy 56.99773 -43.687509) (xy 56.941968 -43.731978)
			(xy 56.881577 -43.769924) (xy 56.817318 -43.800869) (xy 56.749998 -43.824426) (xy 56.680463 -43.840296)
			(xy 56.609589 -43.848282) (xy 56.538267 -43.848282) (xy 56.467393 -43.840296) (xy 56.397858 -43.824426)
			(xy 56.330538 -43.800869) (xy 56.266279 -43.769924) (xy 56.205888 -43.731978) (xy 56.150126 -43.687509)
			(xy 56.099693 -43.637076) (xy 56.055224 -43.581314) (xy 56.017278 -43.520923) (xy 55.986333 -43.456664)
			(xy 55.962776 -43.389344) (xy 55.946906 -43.319809) (xy 55.93892 -43.248935) (xy 0.509016 -43.248935)
			(xy 0.509016 -46.254315) (xy 1.150876 -46.254315) (xy 1.152892 -46.124702) (xy 1.162962 -45.995466)
			(xy 1.181047 -45.867105) (xy 1.207077 -45.740117) (xy 1.240952 -45.614993) (xy 1.28254 -45.492217)
			(xy 1.331681 -45.372264) (xy 1.388184 -45.255599) (xy 1.451831 -45.142671) (xy 1.522375 -45.033919)
			(xy 1.599544 -44.929763) (xy 1.683039 -44.830606) (xy 1.772537 -44.736832) (xy 1.867692 -44.648803)
			(xy 1.968135 -44.56686) (xy 2.073478 -44.491321) (xy 2.183314 -44.422476) (xy 2.297218 -44.360593)
			(xy 2.414748 -44.305912) (xy 2.535451 -44.258642) (xy 2.658859 -44.218969) (xy 2.784495 -44.187044)
			(xy 2.911872 -44.162992) (xy 3.040498 -44.146905) (xy 3.169876 -44.138846) (xy 3.23469 -44.138342)
			(xy 3.299504 -44.138846) (xy 3.428882 -44.146905) (xy 3.557508 -44.162992) (xy 3.684885 -44.187044)
			(xy 3.810521 -44.218969) (xy 3.933929 -44.258642) (xy 4.054632 -44.305912) (xy 4.172162 -44.360593)
			(xy 4.286066 -44.422476) (xy 4.395902 -44.491321) (xy 4.501245 -44.56686) (xy 4.601688 -44.648803)
			(xy 4.696843 -44.736832) (xy 4.786341 -44.830606) (xy 4.869836 -44.929763) (xy 4.947005 -45.033919)
			(xy 5.017549 -45.142671) (xy 5.081196 -45.255599) (xy 5.137699 -45.372264) (xy 5.18684 -45.492217)
			(xy 5.228428 -45.614993) (xy 5.262303 -45.740117) (xy 5.288333 -45.867105) (xy 5.306418 -45.995466)
			(xy 5.316488 -46.124702) (xy 5.318504 -46.254315) (xy 12.580876 -46.254315) (xy 12.582892 -46.124702)
			(xy 12.592962 -45.995466) (xy 12.611047 -45.867105) (xy 12.637077 -45.740117) (xy 12.670952 -45.614993)
			(xy 12.71254 -45.492217) (xy 12.761681 -45.372264) (xy 12.818184 -45.255599) (xy 12.881831 -45.142671)
			(xy 12.952375 -45.033919) (xy 13.029544 -44.929763) (xy 13.113039 -44.830606) (xy 13.202537 -44.736832)
			(xy 13.297692 -44.648803) (xy 13.398135 -44.56686) (xy 13.503478 -44.491321) (xy 13.613314 -44.422476)
			(xy 13.727218 -44.360593) (xy 13.844748 -44.305912) (xy 13.965451 -44.258642) (xy 14.088859 -44.218969)
			(xy 14.214495 -44.187044) (xy 14.341872 -44.162992) (xy 14.470498 -44.146905) (xy 14.599876 -44.138846)
			(xy 14.66469 -44.138342) (xy 14.729504 -44.138846) (xy 14.858882 -44.146905) (xy 14.987508 -44.162992)
			(xy 15.114885 -44.187044) (xy 15.240521 -44.218969) (xy 15.363929 -44.258642) (xy 15.484632 -44.305912)
			(xy 15.602162 -44.360593) (xy 15.716066 -44.422476) (xy 15.825902 -44.491321) (xy 15.931245 -44.56686)
			(xy 16.031688 -44.648803) (xy 16.126843 -44.736832) (xy 16.216341 -44.830606) (xy 16.299836 -44.929763)
			(xy 16.377005 -45.033919) (xy 16.447549 -45.142671) (xy 16.511196 -45.255599) (xy 16.567699 -45.372264)
			(xy 16.61684 -45.492217) (xy 16.658428 -45.614993) (xy 16.692303 -45.740117) (xy 16.718333 -45.867105)
			(xy 16.736418 -45.995466) (xy 16.746488 -46.124702) (xy 16.748504 -46.254315) (xy 16.742458 -46.383802)
			(xy 16.728374 -46.512663) (xy 16.706305 -46.640399) (xy 16.676338 -46.766516) (xy 16.638589 -46.890526)
			(xy 16.593202 -47.011949) (xy 16.540355 -47.130316) (xy 16.480251 -47.245168) (xy 16.413123 -47.356061)
			(xy 16.339231 -47.462567) (xy 16.25886 -47.564273) (xy 16.172322 -47.660785) (xy 16.07995 -47.75173)
			(xy 15.982104 -47.836757) (xy 15.879161 -47.915537) (xy 15.771519 -47.987764) (xy 15.659595 -48.053159)
			(xy 15.543822 -48.11147) (xy 15.424648 -48.16247) (xy 15.302534 -48.205962) (xy 15.177951 -48.241779)
			(xy 15.051384 -48.269781) (xy 14.92332 -48.28986) (xy 14.794256 -48.301939) (xy 14.66469 -48.30597)
			(xy 14.535124 -48.301939) (xy 14.40606 -48.28986) (xy 14.277996 -48.269781) (xy 14.151429 -48.241779)
			(xy 14.026846 -48.205962) (xy 13.904732 -48.16247) (xy 13.785558 -48.11147) (xy 13.669785 -48.053159)
			(xy 13.557861 -47.987764) (xy 13.450219 -47.915537) (xy 13.347276 -47.836757) (xy 13.24943 -47.75173)
			(xy 13.157058 -47.660785) (xy 13.07052 -47.564273) (xy 12.990149 -47.462567) (xy 12.916257 -47.356061)
			(xy 12.849129 -47.245168) (xy 12.789025 -47.130316) (xy 12.736178 -47.011949) (xy 12.690791 -46.890526)
			(xy 12.653042 -46.766516) (xy 12.623075 -46.640399) (xy 12.601006 -46.512663) (xy 12.586922 -46.383802)
			(xy 12.580876 -46.254315) (xy 5.318504 -46.254315) (xy 5.312458 -46.383802) (xy 5.298374 -46.512663)
			(xy 5.276305 -46.640399) (xy 5.246338 -46.766516) (xy 5.208589 -46.890526) (xy 5.163202 -47.011949)
			(xy 5.110355 -47.130316) (xy 5.050251 -47.245168) (xy 4.983123 -47.356061) (xy 4.909231 -47.462567)
			(xy 4.82886 -47.564273) (xy 4.742322 -47.660785) (xy 4.64995 -47.75173) (xy 4.552104 -47.836757)
			(xy 4.449161 -47.915537) (xy 4.341519 -47.987764) (xy 4.229595 -48.053159) (xy 4.113822 -48.11147)
			(xy 3.994648 -48.16247) (xy 3.872534 -48.205962) (xy 3.747951 -48.241779) (xy 3.621384 -48.269781)
			(xy 3.49332 -48.28986) (xy 3.364256 -48.301939) (xy 3.23469 -48.30597) (xy 3.105124 -48.301939) (xy 2.97606 -48.28986)
			(xy 2.847996 -48.269781) (xy 2.721429 -48.241779) (xy 2.596846 -48.205962) (xy 2.474732 -48.16247)
			(xy 2.355558 -48.11147) (xy 2.239785 -48.053159) (xy 2.127861 -47.987764) (xy 2.020219 -47.915537)
			(xy 1.917276 -47.836757) (xy 1.81943 -47.75173) (xy 1.727058 -47.660785) (xy 1.64052 -47.564273)
			(xy 1.560149 -47.462567) (xy 1.486257 -47.356061) (xy 1.419129 -47.245168) (xy 1.359025 -47.130316)
			(xy 1.306178 -47.011949) (xy 1.260791 -46.890526) (xy 1.223042 -46.766516) (xy 1.193075 -46.640399)
			(xy 1.171006 -46.512663) (xy 1.156922 -46.383802) (xy 1.150876 -46.254315) (xy 0.509016 -46.254315)
			(xy 0.509016 -68.310405) (xy 1.150876 -68.310405) (xy 1.152892 -68.180792) (xy 1.162962 -68.051556)
			(xy 1.181047 -67.923195) (xy 1.207077 -67.796207) (xy 1.240952 -67.671083) (xy 1.28254 -67.548307)
			(xy 1.331681 -67.428354) (xy 1.388184 -67.311689) (xy 1.451831 -67.198761) (xy 1.522375 -67.090009)
			(xy 1.599544 -66.985853) (xy 1.683039 -66.886696) (xy 1.772537 -66.792922) (xy 1.867692 -66.704893)
			(xy 1.968135 -66.62295) (xy 2.073478 -66.547411) (xy 2.183314 -66.478566) (xy 2.297218 -66.416683)
			(xy 2.414748 -66.362002) (xy 2.535451 -66.314732) (xy 2.658859 -66.275059) (xy 2.784495 -66.243134)
			(xy 2.911872 -66.219082) (xy 3.040498 -66.202995) (xy 3.169876 -66.194936) (xy 3.23469 -66.194432)
			(xy 3.299504 -66.194936) (xy 3.428882 -66.202995) (xy 3.557508 -66.219082) (xy 3.684885 -66.243134)
			(xy 3.810521 -66.275059) (xy 3.933929 -66.314732) (xy 4.054632 -66.362002) (xy 4.172162 -66.416683)
			(xy 4.286066 -66.478566) (xy 4.395902 -66.547411) (xy 4.501245 -66.62295) (xy 4.601688 -66.704893)
			(xy 4.696843 -66.792922) (xy 4.786341 -66.886696) (xy 4.869836 -66.985853) (xy 4.947005 -67.090009)
			(xy 5.017549 -67.198761) (xy 5.081196 -67.311689) (xy 5.137699 -67.428354) (xy 5.18684 -67.548307)
			(xy 5.228428 -67.671083) (xy 5.262303 -67.796207) (xy 5.288333 -67.923195) (xy 5.306418 -68.051556)
			(xy 5.316488 -68.180792) (xy 5.318504 -68.310405) (xy 5.312458 -68.439892) (xy 5.298374 -68.568753)
			(xy 5.276305 -68.696489) (xy 5.246338 -68.822606) (xy 5.208589 -68.946616) (xy 5.163202 -69.068039)
			(xy 5.110355 -69.186406) (xy 5.050251 -69.301258) (xy 4.983123 -69.412151) (xy 4.909231 -69.518657)
			(xy 4.82886 -69.620363) (xy 4.742322 -69.716875) (xy 4.64995 -69.80782) (xy 4.552104 -69.892847)
			(xy 4.449161 -69.971627) (xy 4.341519 -70.043854) (xy 4.229595 -70.109249) (xy 4.113822 -70.16756)
			(xy 3.994648 -70.21856) (xy 3.872534 -70.262052) (xy 3.747951 -70.297869) (xy 3.621384 -70.325871)
			(xy 3.49332 -70.34595) (xy 3.364256 -70.358029) (xy 3.23469 -70.36206) (xy 3.105124 -70.358029) (xy 2.97606 -70.34595)
			(xy 2.847996 -70.325871) (xy 2.721429 -70.297869) (xy 2.596846 -70.262052) (xy 2.474732 -70.21856)
			(xy 2.355558 -70.16756) (xy 2.239785 -70.109249) (xy 2.127861 -70.043854) (xy 2.020219 -69.971627)
			(xy 1.917276 -69.892847) (xy 1.81943 -69.80782) (xy 1.727058 -69.716875) (xy 1.64052 -69.620363)
			(xy 1.560149 -69.518657) (xy 1.486257 -69.412151) (xy 1.419129 -69.301258) (xy 1.359025 -69.186406)
			(xy 1.306178 -69.068039) (xy 1.260791 -68.946616) (xy 1.223042 -68.822606) (xy 1.193075 -68.696489)
			(xy 1.171006 -68.568753) (xy 1.156922 -68.439892) (xy 1.150876 -68.310405) (xy 0.509016 -68.310405)
			(xy 0.509016 -129.210054) (xy 4.036316 -129.210054) (xy 4.040361 -129.130291) (xy 4.052454 -129.051347)
			(xy 4.072473 -128.974032) (xy 4.10021 -128.899138) (xy 4.135382 -128.827435) (xy 4.177628 -128.759658)
			(xy 4.226514 -128.696502) (xy 4.281538 -128.638617) (xy 4.342137 -128.586595) (xy 4.407687 -128.540971)
			(xy 4.477517 -128.502212) (xy 4.55091 -128.470717) (xy 4.627112 -128.446808) (xy 4.705342 -128.430731)
			(xy 4.784797 -128.422651) (xy 4.82473 -128.422146) (xy 4.864663 -128.422651) (xy 4.944118 -128.430731)
			(xy 5.022348 -128.446808) (xy 5.09855 -128.470717) (xy 5.171943 -128.502212) (xy 5.241773 -128.540971)
			(xy 5.307323 -128.586595) (xy 5.367922 -128.638617) (xy 5.422946 -128.696502) (xy 5.471832 -128.759658)
			(xy 5.514078 -128.827435) (xy 5.54925 -128.899138) (xy 5.576987 -128.974032) (xy 5.597006 -129.051347)
			(xy 5.609099 -129.130291) (xy 5.613145 -129.210054) (xy 6.576316 -129.210054) (xy 6.580361 -129.130291)
			(xy 6.592454 -129.051347) (xy 6.612473 -128.974032) (xy 6.64021 -128.899138) (xy 6.675382 -128.827435)
			(xy 6.717628 -128.759658) (xy 6.766514 -128.696502) (xy 6.821538 -128.638617) (xy 6.882137 -128.586595)
			(xy 6.947687 -128.540971) (xy 7.017517 -128.502212) (xy 7.09091 -128.470717) (xy 7.167112 -128.446808)
			(xy 7.245342 -128.430731) (xy 7.324797 -128.422651) (xy 7.36473 -128.422146) (xy 7.404663 -128.422651)
			(xy 7.484118 -128.430731) (xy 7.562348 -128.446808) (xy 7.63855 -128.470717) (xy 7.711943 -128.502212)
			(xy 7.781773 -128.540971) (xy 7.847323 -128.586595) (xy 7.907922 -128.638617) (xy 7.962946 -128.696502)
			(xy 8.011832 -128.759658) (xy 8.054078 -128.827435) (xy 8.08925 -128.899138) (xy 8.116987 -128.974032)
			(xy 8.137006 -129.051347) (xy 8.149099 -129.130291) (xy 8.153145 -129.210054) (xy 9.116316 -129.210054)
			(xy 9.120361 -129.130291) (xy 9.132454 -129.051347) (xy 9.152473 -128.974032) (xy 9.18021 -128.899138)
			(xy 9.215382 -128.827435) (xy 9.257628 -128.759658) (xy 9.306514 -128.696502) (xy 9.361538 -128.638617)
			(xy 9.422137 -128.586595) (xy 9.487687 -128.540971) (xy 9.557517 -128.502212) (xy 9.63091 -128.470717)
			(xy 9.707112 -128.446808) (xy 9.785342 -128.430731) (xy 9.864797 -128.422651) (xy 9.90473 -128.422146)
			(xy 9.944663 -128.422651) (xy 10.024118 -128.430731) (xy 10.102348 -128.446808) (xy 10.17855 -128.470717)
			(xy 10.251943 -128.502212) (xy 10.321773 -128.540971) (xy 10.387323 -128.586595) (xy 10.447922 -128.638617)
			(xy 10.502946 -128.696502) (xy 10.551832 -128.759658) (xy 10.594078 -128.827435) (xy 10.62925 -128.899138)
			(xy 10.656987 -128.974032) (xy 10.677006 -129.051347) (xy 10.689099 -129.130291) (xy 10.693145 -129.210054)
			(xy 10.689099 -129.289817) (xy 10.677006 -129.368761) (xy 10.656987 -129.446076) (xy 10.62925 -129.52097)
			(xy 10.594078 -129.592673) (xy 10.551832 -129.66045) (xy 10.502946 -129.723606) (xy 10.447922 -129.781491)
			(xy 10.387323 -129.833513) (xy 10.321773 -129.879137) (xy 10.251943 -129.917896) (xy 10.17855 -129.949391)
			(xy 10.102348 -129.9733) (xy 10.024118 -129.989377) (xy 9.944663 -129.997457) (xy 9.864797 -129.997457)
			(xy 9.785342 -129.989377) (xy 9.707112 -129.9733) (xy 9.63091 -129.949391) (xy 9.557517 -129.917896)
			(xy 9.487687 -129.879137) (xy 9.422137 -129.833513) (xy 9.361538 -129.781491) (xy 9.306514 -129.723606)
			(xy 9.257628 -129.66045) (xy 9.215382 -129.592673) (xy 9.18021 -129.52097) (xy 9.152473 -129.446076)
			(xy 9.132454 -129.368761) (xy 9.120361 -129.289817) (xy 9.116316 -129.210054) (xy 8.153145 -129.210054)
			(xy 8.149099 -129.289817) (xy 8.137006 -129.368761) (xy 8.116987 -129.446076) (xy 8.08925 -129.52097)
			(xy 8.054078 -129.592673) (xy 8.011832 -129.66045) (xy 7.962946 -129.723606) (xy 7.907922 -129.781491)
			(xy 7.847323 -129.833513) (xy 7.781773 -129.879137) (xy 7.711943 -129.917896) (xy 7.63855 -129.949391)
			(xy 7.562348 -129.9733) (xy 7.484118 -129.989377) (xy 7.404663 -129.997457) (xy 7.324797 -129.997457)
			(xy 7.245342 -129.989377) (xy 7.167112 -129.9733) (xy 7.09091 -129.949391) (xy 7.017517 -129.917896)
			(xy 6.947687 -129.879137) (xy 6.882137 -129.833513) (xy 6.821538 -129.781491) (xy 6.766514 -129.723606)
			(xy 6.717628 -129.66045) (xy 6.675382 -129.592673) (xy 6.64021 -129.52097) (xy 6.612473 -129.446076)
			(xy 6.592454 -129.368761) (xy 6.580361 -129.289817) (xy 6.576316 -129.210054) (xy 5.613145 -129.210054)
			(xy 5.609099 -129.289817) (xy 5.597006 -129.368761) (xy 5.576987 -129.446076) (xy 5.54925 -129.52097)
			(xy 5.514078 -129.592673) (xy 5.471832 -129.66045) (xy 5.422946 -129.723606) (xy 5.367922 -129.781491)
			(xy 5.307323 -129.833513) (xy 5.241773 -129.879137) (xy 5.171943 -129.917896) (xy 5.09855 -129.949391)
			(xy 5.022348 -129.9733) (xy 4.944118 -129.989377) (xy 4.864663 -129.997457) (xy 4.784797 -129.997457)
			(xy 4.705342 -129.989377) (xy 4.627112 -129.9733) (xy 4.55091 -129.949391) (xy 4.477517 -129.917896)
			(xy 4.407687 -129.879137) (xy 4.342137 -129.833513) (xy 4.281538 -129.781491) (xy 4.226514 -129.723606)
			(xy 4.177628 -129.66045) (xy 4.135382 -129.592673) (xy 4.10021 -129.52097) (xy 4.072473 -129.446076)
			(xy 4.052454 -129.368761) (xy 4.040361 -129.289817) (xy 4.036316 -129.210054) (xy 0.509016 -129.210054)
			(xy 0.509016 -131.750054) (xy 5.306316 -131.750054) (xy 5.310361 -131.670291) (xy 5.322454 -131.591347)
			(xy 5.342473 -131.514032) (xy 5.37021 -131.439138) (xy 5.405382 -131.367435) (xy 5.447628 -131.299658)
			(xy 5.496514 -131.236502) (xy 5.551538 -131.178617) (xy 5.612137 -131.126595) (xy 5.677687 -131.080971)
			(xy 5.747517 -131.042212) (xy 5.82091 -131.010717) (xy 5.897112 -130.986808) (xy 5.975342 -130.970731)
			(xy 6.054797 -130.962651) (xy 6.09473 -130.962146) (xy 6.134663 -130.962651) (xy 6.214118 -130.970731)
			(xy 6.292348 -130.986808) (xy 6.36855 -131.010717) (xy 6.441943 -131.042212) (xy 6.511773 -131.080971)
			(xy 6.577323 -131.126595) (xy 6.637922 -131.178617) (xy 6.692946 -131.236502) (xy 6.741832 -131.299658)
			(xy 6.784078 -131.367435) (xy 6.81925 -131.439138) (xy 6.846987 -131.514032) (xy 6.867006 -131.591347)
			(xy 6.879099 -131.670291) (xy 6.883145 -131.750054) (xy 7.846316 -131.750054) (xy 7.850361 -131.670291)
			(xy 7.862454 -131.591347) (xy 7.882473 -131.514032) (xy 7.91021 -131.439138) (xy 7.945382 -131.367435)
			(xy 7.987628 -131.299658) (xy 8.036514 -131.236502) (xy 8.091538 -131.178617) (xy 8.152137 -131.126595)
			(xy 8.217687 -131.080971) (xy 8.287517 -131.042212) (xy 8.36091 -131.010717) (xy 8.437112 -130.986808)
			(xy 8.515342 -130.970731) (xy 8.594797 -130.962651) (xy 8.63473 -130.962146) (xy 8.674663 -130.962651)
			(xy 8.754118 -130.970731) (xy 8.832348 -130.986808) (xy 8.90855 -131.010717) (xy 8.981943 -131.042212)
			(xy 9.051773 -131.080971) (xy 9.117323 -131.126595) (xy 9.177922 -131.178617) (xy 9.232946 -131.236502)
			(xy 9.281832 -131.299658) (xy 9.324078 -131.367435) (xy 9.35925 -131.439138) (xy 9.386987 -131.514032)
			(xy 9.407006 -131.591347) (xy 9.419099 -131.670291) (xy 9.423145 -131.750054) (xy 10.386316 -131.750054)
			(xy 10.390361 -131.670291) (xy 10.402454 -131.591347) (xy 10.422473 -131.514032) (xy 10.45021 -131.439138)
			(xy 10.485382 -131.367435) (xy 10.527628 -131.299658) (xy 10.576514 -131.236502) (xy 10.631538 -131.178617)
			(xy 10.692137 -131.126595) (xy 10.757687 -131.080971) (xy 10.827517 -131.042212) (xy 10.90091 -131.010717)
			(xy 10.977112 -130.986808) (xy 11.055342 -130.970731) (xy 11.134797 -130.962651) (xy 11.17473 -130.962146)
			(xy 11.214663 -130.962651) (xy 11.294118 -130.970731) (xy 11.372348 -130.986808) (xy 11.44855 -131.010717)
			(xy 11.521943 -131.042212) (xy 11.591773 -131.080971) (xy 11.657323 -131.126595) (xy 11.717922 -131.178617)
			(xy 11.772946 -131.236502) (xy 11.821832 -131.299658) (xy 11.864078 -131.367435) (xy 11.89925 -131.439138)
			(xy 11.926987 -131.514032) (xy 11.947006 -131.591347) (xy 11.959099 -131.670291) (xy 11.963145 -131.750054)
			(xy 12.926316 -131.750054) (xy 12.930361 -131.670291) (xy 12.942454 -131.591347) (xy 12.962473 -131.514032)
			(xy 12.99021 -131.439138) (xy 13.025382 -131.367435) (xy 13.067628 -131.299658) (xy 13.116514 -131.236502)
			(xy 13.171538 -131.178617) (xy 13.232137 -131.126595) (xy 13.297687 -131.080971) (xy 13.367517 -131.042212)
			(xy 13.44091 -131.010717) (xy 13.517112 -130.986808) (xy 13.595342 -130.970731) (xy 13.674797 -130.962651)
			(xy 13.71473 -130.962146) (xy 13.754663 -130.962651) (xy 13.834118 -130.970731) (xy 13.912348 -130.986808)
			(xy 13.98855 -131.010717) (xy 14.061943 -131.042212) (xy 14.131773 -131.080971) (xy 14.197323 -131.126595)
			(xy 14.257922 -131.178617) (xy 14.312946 -131.236502) (xy 14.361832 -131.299658) (xy 14.404078 -131.367435)
			(xy 14.43925 -131.439138) (xy 14.466987 -131.514032) (xy 14.487006 -131.591347) (xy 14.499099 -131.670291)
			(xy 14.503145 -131.750054) (xy 14.499099 -131.829817) (xy 14.487006 -131.908761) (xy 14.466987 -131.986076)
			(xy 14.43925 -132.06097) (xy 14.404078 -132.132673) (xy 14.361832 -132.20045) (xy 14.312946 -132.263606)
			(xy 14.257922 -132.321491) (xy 14.197323 -132.373513) (xy 14.131773 -132.419137) (xy 14.061943 -132.457896)
			(xy 13.98855 -132.489391) (xy 13.912348 -132.5133) (xy 13.834118 -132.529377) (xy 13.754663 -132.537457)
			(xy 13.674797 -132.537457) (xy 13.595342 -132.529377) (xy 13.517112 -132.5133) (xy 13.44091 -132.489391)
			(xy 13.367517 -132.457896) (xy 13.297687 -132.419137) (xy 13.232137 -132.373513) (xy 13.171538 -132.321491)
			(xy 13.116514 -132.263606) (xy 13.067628 -132.20045) (xy 13.025382 -132.132673) (xy 12.99021 -132.06097)
			(xy 12.962473 -131.986076) (xy 12.942454 -131.908761) (xy 12.930361 -131.829817) (xy 12.926316 -131.750054)
			(xy 11.963145 -131.750054) (xy 11.959099 -131.829817) (xy 11.947006 -131.908761) (xy 11.926987 -131.986076)
			(xy 11.89925 -132.06097) (xy 11.864078 -132.132673) (xy 11.821832 -132.20045) (xy 11.772946 -132.263606)
			(xy 11.717922 -132.321491) (xy 11.657323 -132.373513) (xy 11.591773 -132.419137) (xy 11.521943 -132.457896)
			(xy 11.44855 -132.489391) (xy 11.372348 -132.5133) (xy 11.294118 -132.529377) (xy 11.214663 -132.537457)
			(xy 11.134797 -132.537457) (xy 11.055342 -132.529377) (xy 10.977112 -132.5133) (xy 10.90091 -132.489391)
			(xy 10.827517 -132.457896) (xy 10.757687 -132.419137) (xy 10.692137 -132.373513) (xy 10.631538 -132.321491)
			(xy 10.576514 -132.263606) (xy 10.527628 -132.20045) (xy 10.485382 -132.132673) (xy 10.45021 -132.06097)
			(xy 10.422473 -131.986076) (xy 10.402454 -131.908761) (xy 10.390361 -131.829817) (xy 10.386316 -131.750054)
			(xy 9.423145 -131.750054) (xy 9.419099 -131.829817) (xy 9.407006 -131.908761) (xy 9.386987 -131.986076)
			(xy 9.35925 -132.06097) (xy 9.324078 -132.132673) (xy 9.281832 -132.20045) (xy 9.232946 -132.263606)
			(xy 9.177922 -132.321491) (xy 9.117323 -132.373513) (xy 9.051773 -132.419137) (xy 8.981943 -132.457896)
			(xy 8.90855 -132.489391) (xy 8.832348 -132.5133) (xy 8.754118 -132.529377) (xy 8.674663 -132.537457)
			(xy 8.594797 -132.537457) (xy 8.515342 -132.529377) (xy 8.437112 -132.5133) (xy 8.36091 -132.489391)
			(xy 8.287517 -132.457896) (xy 8.217687 -132.419137) (xy 8.152137 -132.373513) (xy 8.091538 -132.321491)
			(xy 8.036514 -132.263606) (xy 7.987628 -132.20045) (xy 7.945382 -132.132673) (xy 7.91021 -132.06097)
			(xy 7.882473 -131.986076) (xy 7.862454 -131.908761) (xy 7.850361 -131.829817) (xy 7.846316 -131.750054)
			(xy 6.883145 -131.750054) (xy 6.879099 -131.829817) (xy 6.867006 -131.908761) (xy 6.846987 -131.986076)
			(xy 6.81925 -132.06097) (xy 6.784078 -132.132673) (xy 6.741832 -132.20045) (xy 6.692946 -132.263606)
			(xy 6.637922 -132.321491) (xy 6.577323 -132.373513) (xy 6.511773 -132.419137) (xy 6.441943 -132.457896)
			(xy 6.36855 -132.489391) (xy 6.292348 -132.5133) (xy 6.214118 -132.529377) (xy 6.134663 -132.537457)
			(xy 6.054797 -132.537457) (xy 5.975342 -132.529377) (xy 5.897112 -132.5133) (xy 5.82091 -132.489391)
			(xy 5.747517 -132.457896) (xy 5.677687 -132.419137) (xy 5.612137 -132.373513) (xy 5.551538 -132.321491)
			(xy 5.496514 -132.263606) (xy 5.447628 -132.20045) (xy 5.405382 -132.132673) (xy 5.37021 -132.06097)
			(xy 5.342473 -131.986076) (xy 5.322454 -131.908761) (xy 5.310361 -131.829817) (xy 5.306316 -131.750054)
			(xy 0.509016 -131.750054) (xy 0.509016 -132.496306) (xy 1.054354 -132.496306) (xy 1.054354 -135.69442)
			(xy 0.509016 -135.69442) (xy 0.509016 -138.163122) (xy 1.547863 -138.163122) (xy 1.547863 -138.036986)
			(xy 1.555783 -137.911098) (xy 1.571593 -137.785956) (xy 1.595228 -137.662053) (xy 1.626597 -137.53988)
			(xy 1.665575 -137.419917) (xy 1.712009 -137.302638) (xy 1.765716 -137.188506) (xy 1.826483 -137.077971)
			(xy 1.89407 -136.971471) (xy 1.968211 -136.869424) (xy 2.048614 -136.772234) (xy 2.13496 -136.680284)
			(xy 2.22691 -136.593938) (xy 2.3241 -136.513535) (xy 2.426147 -136.439394) (xy 2.532647 -136.371807)
			(xy 2.643182 -136.31104) (xy 2.757314 -136.257333) (xy 2.874593 -136.210899) (xy 2.994556 -136.171921)
			(xy 3.116729 -136.140552) (xy 3.240632 -136.116917) (xy 3.365774 -136.101107) (xy 3.491662 -136.093187)
			(xy 3.55473 -136.092692) (xy 3.617798 -136.093187) (xy 3.743686 -136.101107) (xy 3.868828 -136.116917)
			(xy 3.992731 -136.140552) (xy 4.114904 -136.171921) (xy 4.234867 -136.210899) (xy 4.352146 -136.257333)
			(xy 4.466278 -136.31104) (xy 4.576813 -136.371807) (xy 4.683313 -136.439394) (xy 4.78536 -136.513535)
			(xy 4.88255 -136.593938) (xy 4.9745 -136.680284) (xy 5.060846 -136.772234) (xy 5.141249 -136.869424)
			(xy 5.21539 -136.971471) (xy 5.282977 -137.077971) (xy 5.343744 -137.188506) (xy 5.397451 -137.302638)
			(xy 5.443885 -137.419917) (xy 5.482863 -137.53988) (xy 5.514232 -137.662053) (xy 5.537867 -137.785956)
			(xy 5.553677 -137.911098) (xy 5.561597 -138.036986) (xy 5.561597 -138.163122) (xy 12.977863 -138.163122)
			(xy 12.977863 -138.036986) (xy 12.985783 -137.911098) (xy 13.001593 -137.785956) (xy 13.025228 -137.662053)
			(xy 13.056597 -137.53988) (xy 13.095575 -137.419917) (xy 13.142009 -137.302638) (xy 13.195716 -137.188506)
			(xy 13.256483 -137.077971) (xy 13.32407 -136.971471) (xy 13.398211 -136.869424) (xy 13.478614 -136.772234)
			(xy 13.56496 -136.680284) (xy 13.65691 -136.593938) (xy 13.7541 -136.513535) (xy 13.856147 -136.439394)
			(xy 13.962647 -136.371807) (xy 14.073182 -136.31104) (xy 14.187314 -136.257333) (xy 14.304593 -136.210899)
			(xy 14.424556 -136.171921) (xy 14.546729 -136.140552) (xy 14.670632 -136.116917) (xy 14.795774 -136.101107)
			(xy 14.921662 -136.093187) (xy 14.98473 -136.092692) (xy 15.047798 -136.093187) (xy 15.173686 -136.101107)
			(xy 15.298828 -136.116917) (xy 15.422731 -136.140552) (xy 15.544904 -136.171921) (xy 15.664867 -136.210899)
			(xy 15.782146 -136.257333) (xy 15.896278 -136.31104) (xy 16.006813 -136.371807) (xy 16.113313 -136.439394)
			(xy 16.21536 -136.513535) (xy 16.31255 -136.593938) (xy 16.4045 -136.680284) (xy 16.490846 -136.772234)
			(xy 16.571249 -136.869424) (xy 16.64539 -136.971471) (xy 16.712977 -137.077971) (xy 16.773744 -137.188506)
			(xy 16.827451 -137.302638) (xy 16.873885 -137.419917) (xy 16.912863 -137.53988) (xy 16.944232 -137.662053)
			(xy 16.967867 -137.785956) (xy 16.983677 -137.911098) (xy 16.991597 -138.036986) (xy 16.991597 -138.163122)
			(xy 16.983677 -138.28901) (xy 16.967867 -138.414152) (xy 16.944232 -138.538055) (xy 16.912863 -138.660228)
			(xy 16.873885 -138.780191) (xy 16.827451 -138.89747) (xy 16.773744 -139.011602) (xy 16.712977 -139.122137)
			(xy 16.64539 -139.228637) (xy 16.571249 -139.330684) (xy 16.490846 -139.427874) (xy 16.4045 -139.519824)
			(xy 16.31255 -139.60617) (xy 16.21536 -139.686573) (xy 16.113313 -139.760714) (xy 16.006813 -139.828301)
			(xy 15.896278 -139.889068) (xy 15.782146 -139.942775) (xy 15.664867 -139.989209) (xy 15.544904 -140.028187)
			(xy 15.422731 -140.059556) (xy 15.298828 -140.083191) (xy 15.173686 -140.099001) (xy 15.047798 -140.106921)
			(xy 14.921662 -140.106921) (xy 14.795774 -140.099001) (xy 14.670632 -140.083191) (xy 14.546729 -140.059556)
			(xy 14.424556 -140.028187) (xy 14.304593 -139.989209) (xy 14.187314 -139.942775) (xy 14.073182 -139.889068)
			(xy 13.962647 -139.828301) (xy 13.856147 -139.760714) (xy 13.7541 -139.686573) (xy 13.65691 -139.60617)
			(xy 13.56496 -139.519824) (xy 13.478614 -139.427874) (xy 13.398211 -139.330684) (xy 13.32407 -139.228637)
			(xy 13.256483 -139.122137) (xy 13.195716 -139.011602) (xy 13.142009 -138.89747) (xy 13.095575 -138.780191)
			(xy 13.056597 -138.660228) (xy 13.025228 -138.538055) (xy 13.001593 -138.414152) (xy 12.985783 -138.28901)
			(xy 12.977863 -138.163122) (xy 5.561597 -138.163122) (xy 5.553677 -138.28901) (xy 5.537867 -138.414152)
			(xy 5.514232 -138.538055) (xy 5.482863 -138.660228) (xy 5.443885 -138.780191) (xy 5.397451 -138.89747)
			(xy 5.343744 -139.011602) (xy 5.282977 -139.122137) (xy 5.21539 -139.228637) (xy 5.141249 -139.330684)
			(xy 5.060846 -139.427874) (xy 4.9745 -139.519824) (xy 4.88255 -139.60617) (xy 4.78536 -139.686573)
			(xy 4.683313 -139.760714) (xy 4.576813 -139.828301) (xy 4.466278 -139.889068) (xy 4.352146 -139.942775)
			(xy 4.234867 -139.989209) (xy 4.114904 -140.028187) (xy 3.992731 -140.059556) (xy 3.868828 -140.083191)
			(xy 3.743686 -140.099001) (xy 3.617798 -140.106921) (xy 3.491662 -140.106921) (xy 3.365774 -140.099001)
			(xy 3.240632 -140.083191) (xy 3.116729 -140.059556) (xy 2.994556 -140.028187) (xy 2.874593 -139.989209)
			(xy 2.757314 -139.942775) (xy 2.643182 -139.889068) (xy 2.532647 -139.828301) (xy 2.426147 -139.760714)
			(xy 2.3241 -139.686573) (xy 2.22691 -139.60617) (xy 2.13496 -139.519824) (xy 2.048614 -139.427874)
			(xy 1.968211 -139.330684) (xy 1.89407 -139.228637) (xy 1.826483 -139.122137) (xy 1.765716 -139.011602)
			(xy 1.712009 -138.89747) (xy 1.665575 -138.780191) (xy 1.626597 -138.660228) (xy 1.595228 -138.538055)
			(xy 1.571593 -138.414152) (xy 1.555783 -138.28901) (xy 1.547863 -138.163122) (xy 0.509016 -138.163122)
			(xy 0.509016 -142.210028) (xy 2.181354 -142.210028) (xy 2.185399 -142.130265) (xy 2.197492 -142.051321)
			(xy 2.217511 -141.974006) (xy 2.245248 -141.899112) (xy 2.28042 -141.827409) (xy 2.322666 -141.759632)
			(xy 2.371552 -141.696476) (xy 2.426576 -141.638591) (xy 2.487175 -141.586569) (xy 2.552725 -141.540945)
			(xy 2.622555 -141.502186) (xy 2.695948 -141.470691) (xy 2.77215 -141.446782) (xy 2.85038 -141.430705)
			(xy 2.929835 -141.422625) (xy 2.969768 -141.42212) (xy 3.009701 -141.422625) (xy 3.089156 -141.430705)
			(xy 3.167386 -141.446782) (xy 3.243588 -141.470691) (xy 3.316981 -141.502186) (xy 3.386811 -141.540945)
			(xy 3.452361 -141.586569) (xy 3.51296 -141.638591) (xy 3.567984 -141.696476) (xy 3.61687 -141.759632)
			(xy 3.659116 -141.827409) (xy 3.694288 -141.899112) (xy 3.722025 -141.974006) (xy 3.742044 -142.051321)
			(xy 3.754137 -142.130265) (xy 3.758183 -142.210028) (xy 4.671316 -142.210028) (xy 4.675361 -142.130265)
			(xy 4.687454 -142.051321) (xy 4.707473 -141.974006) (xy 4.73521 -141.899112) (xy 4.770382 -141.827409)
			(xy 4.812628 -141.759632) (xy 4.861514 -141.696476) (xy 4.916538 -141.638591) (xy 4.977137 -141.586569)
			(xy 5.042687 -141.540945) (xy 5.112517 -141.502186) (xy 5.18591 -141.470691) (xy 5.262112 -141.446782)
			(xy 5.340342 -141.430705) (xy 5.419797 -141.422625) (xy 5.45973 -141.42212) (xy 5.499663 -141.422625)
			(xy 5.579118 -141.430705) (xy 5.657348 -141.446782) (xy 5.73355 -141.470691) (xy 5.806943 -141.502186)
			(xy 5.876773 -141.540945) (xy 5.942323 -141.586569) (xy 6.002922 -141.638591) (xy 6.057946 -141.696476)
			(xy 6.106832 -141.759632) (xy 6.149078 -141.827409) (xy 6.18425 -141.899112) (xy 6.211987 -141.974006)
			(xy 6.232006 -142.051321) (xy 6.244099 -142.130265) (xy 6.248145 -142.210028) (xy 12.291316 -142.210028)
			(xy 12.295361 -142.130265) (xy 12.307454 -142.051321) (xy 12.327473 -141.974006) (xy 12.35521 -141.899112)
			(xy 12.390382 -141.827409) (xy 12.432628 -141.759632) (xy 12.481514 -141.696476) (xy 12.536538 -141.638591)
			(xy 12.597137 -141.586569) (xy 12.662687 -141.540945) (xy 12.732517 -141.502186) (xy 12.80591 -141.470691)
			(xy 12.882112 -141.446782) (xy 12.960342 -141.430705) (xy 13.039797 -141.422625) (xy 13.07973 -141.42212)
			(xy 13.119663 -141.422625) (xy 13.199118 -141.430705) (xy 13.277348 -141.446782) (xy 13.35355 -141.470691)
			(xy 13.426943 -141.502186) (xy 13.496773 -141.540945) (xy 13.562323 -141.586569) (xy 13.622922 -141.638591)
			(xy 13.677946 -141.696476) (xy 13.726832 -141.759632) (xy 13.769078 -141.827409) (xy 13.80425 -141.899112)
			(xy 13.831987 -141.974006) (xy 13.852006 -142.051321) (xy 13.864099 -142.130265) (xy 13.868145 -142.210028)
			(xy 14.781278 -142.210028) (xy 14.785323 -142.130265) (xy 14.797416 -142.051321) (xy 14.817435 -141.974006)
			(xy 14.845172 -141.899112) (xy 14.880344 -141.827409) (xy 14.92259 -141.759632) (xy 14.971476 -141.696476)
			(xy 15.0265 -141.638591) (xy 15.087099 -141.586569) (xy 15.152649 -141.540945) (xy 15.222479 -141.502186)
			(xy 15.295872 -141.470691) (xy 15.372074 -141.446782) (xy 15.450304 -141.430705) (xy 15.529759 -141.422625)
			(xy 15.569692 -141.42212) (xy 15.609625 -141.422625) (xy 15.68908 -141.430705) (xy 15.76731 -141.446782)
			(xy 15.843512 -141.470691) (xy 15.916905 -141.502186) (xy 15.986735 -141.540945) (xy 16.052285 -141.586569)
			(xy 16.112884 -141.638591) (xy 16.167908 -141.696476) (xy 16.216794 -141.759632) (xy 16.25904 -141.827409)
			(xy 16.294212 -141.899112) (xy 16.321949 -141.974006) (xy 16.341968 -142.051321) (xy 16.354061 -142.130265)
			(xy 16.358107 -142.210028) (xy 16.354061 -142.289791) (xy 16.341968 -142.368735) (xy 16.321949 -142.44605)
			(xy 16.294212 -142.520944) (xy 16.25904 -142.592647) (xy 16.216794 -142.660424) (xy 16.167908 -142.72358)
			(xy 16.112884 -142.781465) (xy 16.052285 -142.833487) (xy 15.986735 -142.879111) (xy 15.916905 -142.91787)
			(xy 15.843512 -142.949365) (xy 15.76731 -142.973274) (xy 15.68908 -142.989351) (xy 15.609625 -142.997431)
			(xy 15.529759 -142.997431) (xy 15.450304 -142.989351) (xy 15.372074 -142.973274) (xy 15.295872 -142.949365)
			(xy 15.222479 -142.91787) (xy 15.152649 -142.879111) (xy 15.087099 -142.833487) (xy 15.0265 -142.781465)
			(xy 14.971476 -142.72358) (xy 14.92259 -142.660424) (xy 14.880344 -142.592647) (xy 14.845172 -142.520944)
			(xy 14.817435 -142.44605) (xy 14.797416 -142.368735) (xy 14.785323 -142.289791) (xy 14.781278 -142.210028)
			(xy 13.868145 -142.210028) (xy 13.864099 -142.289791) (xy 13.852006 -142.368735) (xy 13.831987 -142.44605)
			(xy 13.80425 -142.520944) (xy 13.769078 -142.592647) (xy 13.726832 -142.660424) (xy 13.677946 -142.72358)
			(xy 13.622922 -142.781465) (xy 13.562323 -142.833487) (xy 13.496773 -142.879111) (xy 13.426943 -142.91787)
			(xy 13.35355 -142.949365) (xy 13.277348 -142.973274) (xy 13.199118 -142.989351) (xy 13.119663 -142.997431)
			(xy 13.039797 -142.997431) (xy 12.960342 -142.989351) (xy 12.882112 -142.973274) (xy 12.80591 -142.949365)
			(xy 12.732517 -142.91787) (xy 12.662687 -142.879111) (xy 12.597137 -142.833487) (xy 12.536538 -142.781465)
			(xy 12.481514 -142.72358) (xy 12.432628 -142.660424) (xy 12.390382 -142.592647) (xy 12.35521 -142.520944)
			(xy 12.327473 -142.44605) (xy 12.307454 -142.368735) (xy 12.295361 -142.289791) (xy 12.291316 -142.210028)
			(xy 6.248145 -142.210028) (xy 6.244099 -142.289791) (xy 6.232006 -142.368735) (xy 6.211987 -142.44605)
			(xy 6.18425 -142.520944) (xy 6.149078 -142.592647) (xy 6.106832 -142.660424) (xy 6.057946 -142.72358)
			(xy 6.002922 -142.781465) (xy 5.942323 -142.833487) (xy 5.876773 -142.879111) (xy 5.806943 -142.91787)
			(xy 5.73355 -142.949365) (xy 5.657348 -142.973274) (xy 5.579118 -142.989351) (xy 5.499663 -142.997431)
			(xy 5.419797 -142.997431) (xy 5.340342 -142.989351) (xy 5.262112 -142.973274) (xy 5.18591 -142.949365)
			(xy 5.112517 -142.91787) (xy 5.042687 -142.879111) (xy 4.977137 -142.833487) (xy 4.916538 -142.781465)
			(xy 4.861514 -142.72358) (xy 4.812628 -142.660424) (xy 4.770382 -142.592647) (xy 4.73521 -142.520944)
			(xy 4.707473 -142.44605) (xy 4.687454 -142.368735) (xy 4.675361 -142.289791) (xy 4.671316 -142.210028)
			(xy 3.758183 -142.210028) (xy 3.754137 -142.289791) (xy 3.742044 -142.368735) (xy 3.722025 -142.44605)
			(xy 3.694288 -142.520944) (xy 3.659116 -142.592647) (xy 3.61687 -142.660424) (xy 3.567984 -142.72358)
			(xy 3.51296 -142.781465) (xy 3.452361 -142.833487) (xy 3.386811 -142.879111) (xy 3.316981 -142.91787)
			(xy 3.243588 -142.949365) (xy 3.167386 -142.973274) (xy 3.089156 -142.989351) (xy 3.009701 -142.997431)
			(xy 2.929835 -142.997431) (xy 2.85038 -142.989351) (xy 2.77215 -142.973274) (xy 2.695948 -142.949365)
			(xy 2.622555 -142.91787) (xy 2.552725 -142.879111) (xy 2.487175 -142.833487) (xy 2.426576 -142.781465)
			(xy 2.371552 -142.72358) (xy 2.322666 -142.660424) (xy 2.28042 -142.592647) (xy 2.245248 -142.520944)
			(xy 2.217511 -142.44605) (xy 2.197492 -142.368735) (xy 2.185399 -142.289791) (xy 2.181354 -142.210028)
			(xy 0.509016 -142.210028) (xy 0.509016 -152.374854) (xy 1.29566 -152.374854) (xy 1.299673 -152.279104)
			(xy 1.311684 -152.184027) (xy 1.331609 -152.090287) (xy 1.359308 -151.998544) (xy 1.394587 -151.90944)
			(xy 1.437198 -151.823601) (xy 1.486842 -151.741628) (xy 1.543172 -151.664097) (xy 1.605791 -151.591551)
			(xy 1.674262 -151.5245) (xy 1.748103 -151.463413) (xy 1.826797 -151.40872) (xy 1.909791 -151.360803)
			(xy 1.996504 -151.319999) (xy 2.086327 -151.286594) (xy 2.17863 -151.260823) (xy 2.272766 -151.242865)
			(xy 2.368075 -151.232848) (xy 2.463888 -151.230841) (xy 2.559532 -151.236858) (xy 2.654338 -151.250858)
			(xy 2.747639 -151.272742) (xy 2.838782 -151.302356) (xy 2.927128 -151.339493) (xy 3.012056 -151.383892)
			(xy 3.092971 -151.435243) (xy 3.169305 -151.493183) (xy 3.240524 -151.557309) (xy 3.306126 -151.627168)
			(xy 3.365653 -151.702272) (xy 3.418687 -151.782094) (xy 3.464855 -151.866074) (xy 3.503834 -151.953622)
			(xy 3.53535 -152.044125) (xy 3.559183 -152.136948) (xy 3.575165 -152.23144) (xy 3.583184 -152.326937)
			(xy 3.583686 -152.374854) (xy 3.583184 -152.422771) (xy 3.575165 -152.518268) (xy 3.559183 -152.61276)
			(xy 3.53535 -152.705583) (xy 3.503834 -152.796086) (xy 3.464855 -152.883634) (xy 3.418687 -152.967614)
			(xy 3.365653 -153.047436) (xy 3.306126 -153.12254) (xy 3.240524 -153.192399) (xy 3.169305 -153.256525)
			(xy 3.092971 -153.314465) (xy 3.012056 -153.365816) (xy 2.927128 -153.410215) (xy 2.838782 -153.447352)
			(xy 2.747639 -153.476966) (xy 2.654338 -153.49885) (xy 2.559532 -153.51285) (xy 2.463888 -153.518867)
			(xy 2.368075 -153.51686) (xy 2.272766 -153.506843) (xy 2.17863 -153.488885) (xy 2.086327 -153.463114)
			(xy 1.996504 -153.429709) (xy 1.909791 -153.388905) (xy 1.826797 -153.340988) (xy 1.748103 -153.286295)
			(xy 1.674262 -153.225208) (xy 1.605791 -153.158157) (xy 1.543172 -153.085611) (xy 1.486842 -153.00808)
			(xy 1.437198 -152.926107) (xy 1.394587 -152.840268) (xy 1.359308 -152.751164) (xy 1.331609 -152.659421)
			(xy 1.311684 -152.565681) (xy 1.299673 -152.470604) (xy 1.29566 -152.374854) (xy 0.509016 -152.374854)
			(xy 0.509016 -159.325056) (xy 1.29566 -159.325056) (xy 1.299673 -159.229306) (xy 1.311684 -159.134229)
			(xy 1.331609 -159.040489) (xy 1.359308 -158.948746) (xy 1.394587 -158.859642) (xy 1.437198 -158.773803)
			(xy 1.486842 -158.69183) (xy 1.543172 -158.614299) (xy 1.605791 -158.541753) (xy 1.674262 -158.474702)
			(xy 1.748103 -158.413615) (xy 1.826797 -158.358922) (xy 1.909791 -158.311005) (xy 1.996504 -158.270201)
			(xy 2.086327 -158.236796) (xy 2.17863 -158.211025) (xy 2.272766 -158.193067) (xy 2.368075 -158.18305)
			(xy 2.463888 -158.181043) (xy 2.559532 -158.18706) (xy 2.654338 -158.20106) (xy 2.747639 -158.222944)
			(xy 2.838782 -158.252558) (xy 2.927128 -158.289695) (xy 3.012056 -158.334094) (xy 3.092971 -158.385445)
			(xy 3.169305 -158.443385) (xy 3.240524 -158.507511) (xy 3.306126 -158.57737) (xy 3.365653 -158.652474)
			(xy 3.418687 -158.732296) (xy 3.464855 -158.816276) (xy 3.503834 -158.903824) (xy 3.53535 -158.994327)
			(xy 3.559183 -159.08715) (xy 3.575165 -159.181642) (xy 3.583184 -159.277139) (xy 3.583686 -159.325056)
			(xy 3.583184 -159.372973) (xy 3.575165 -159.46847) (xy 3.559183 -159.562962) (xy 3.53535 -159.655785)
			(xy 3.503834 -159.746288) (xy 3.464855 -159.833836) (xy 3.418687 -159.917816) (xy 3.365653 -159.997638)
			(xy 3.306126 -160.072742) (xy 3.240524 -160.142601) (xy 3.169305 -160.206727) (xy 3.092971 -160.264667)
			(xy 3.012056 -160.316018) (xy 2.927128 -160.360417) (xy 2.838782 -160.397554) (xy 2.747639 -160.427168)
			(xy 2.654338 -160.449052) (xy 2.559532 -160.463052) (xy 2.463888 -160.469069) (xy 2.368075 -160.467062)
			(xy 2.272766 -160.457045) (xy 2.17863 -160.439087) (xy 2.086327 -160.413316) (xy 1.996504 -160.379911)
			(xy 1.909791 -160.339107) (xy 1.826797 -160.29119) (xy 1.748103 -160.236497) (xy 1.674262 -160.17541)
			(xy 1.605791 -160.108359) (xy 1.543172 -160.035813) (xy 1.486842 -159.958282) (xy 1.437198 -159.876309)
			(xy 1.394587 -159.79047) (xy 1.359308 -159.701366) (xy 1.331609 -159.609623) (xy 1.311684 -159.515883)
			(xy 1.299673 -159.420806) (xy 1.29566 -159.325056) (xy 0.509016 -159.325056) (xy 0.509016 -176.896492)
			(xy 3.864613 -176.896492) (xy 3.86662 -176.793019) (xy 3.876639 -176.690013) (xy 3.89461 -176.588093)
			(xy 3.920425 -176.487872) (xy 3.953929 -176.389953) (xy 3.994921 -176.294925) (xy 4.043152 -176.203359)
			(xy 4.098335 -176.115806) (xy 4.160136 -176.032792) (xy 4.228185 -175.954818) (xy 4.302071 -175.882351)
			(xy 4.38135 -175.815827) (xy 4.465547 -175.755647) (xy 4.554153 -175.702173) (xy 4.646637 -175.655726)
			(xy 4.742443 -175.616585) (xy 4.840993 -175.584986) (xy 4.941696 -175.561119) (xy 5.043945 -175.545127)
			(xy 5.147126 -175.537108) (xy 5.198872 -175.536606) (xy 5.250618 -175.537108) (xy 5.353799 -175.545127)
			(xy 5.456048 -175.561119) (xy 5.556751 -175.584986) (xy 5.655301 -175.616585) (xy 5.751107 -175.655726)
			(xy 5.843591 -175.702173) (xy 5.932197 -175.755647) (xy 6.016394 -175.815827) (xy 6.095673 -175.882351)
			(xy 6.169559 -175.954818) (xy 6.237608 -176.032792) (xy 6.299409 -176.115806) (xy 6.354592 -176.203359)
			(xy 6.402823 -176.294925) (xy 6.443815 -176.389953) (xy 6.477319 -176.487872) (xy 6.503134 -176.588093)
			(xy 6.521105 -176.690013) (xy 6.531124 -176.793019) (xy 6.533131 -176.896492) (xy 6.527114 -176.999809)
			(xy 6.513108 -177.102349) (xy 6.491198 -177.203496) (xy 6.461516 -177.30264) (xy 6.424241 -177.399186)
			(xy 6.379595 -177.492554) (xy 6.327849 -177.582181) (xy 6.269313 -177.667528) (xy 6.20434 -177.748083)
			(xy 6.133319 -177.82336) (xy 6.056678 -177.892908) (xy 5.974879 -177.956307) (xy 5.888412 -178.013177)
			(xy 5.797799 -178.063176) (xy 5.703583 -178.106002) (xy 5.606333 -178.141398) (xy 5.506631 -178.169152)
			(xy 5.405079 -178.189096) (xy 5.302286 -178.201111) (xy 5.198872 -178.205124) (xy 5.095458 -178.201111)
			(xy 4.992665 -178.189096) (xy 4.891113 -178.169152) (xy 4.791411 -178.141398) (xy 4.694161 -178.106002)
			(xy 4.599945 -178.063176) (xy 4.509332 -178.013177) (xy 4.422865 -177.956307) (xy 4.341066 -177.892908)
			(xy 4.264425 -177.82336) (xy 4.193404 -177.748083) (xy 4.128431 -177.667528) (xy 4.069895 -177.582181)
			(xy 4.018149 -177.492554) (xy 3.973503 -177.399186) (xy 3.936228 -177.30264) (xy 3.906546 -177.203496)
			(xy 3.884636 -177.102349) (xy 3.87063 -176.999809) (xy 3.864613 -176.896492) (xy 0.509016 -176.896492)
			(xy 0.509016 -178.706119) (xy 1.313934 -178.706119) (xy 1.313934 -178.634797) (xy 1.32192 -178.563923)
			(xy 1.33779 -178.494388) (xy 1.361347 -178.427068) (xy 1.392292 -178.362809) (xy 1.430238 -178.302418)
			(xy 1.474707 -178.246656) (xy 1.52514 -178.196223) (xy 1.580902 -178.151754) (xy 1.641293 -178.113808)
			(xy 1.705552 -178.082863) (xy 1.772872 -178.059306) (xy 1.842407 -178.043436) (xy 1.913281 -178.03545)
			(xy 1.948942 -178.03495) (xy 1.984603 -178.03545) (xy 2.055477 -178.043436) (xy 2.125012 -178.059306)
			(xy 2.192332 -178.082863) (xy 2.256591 -178.113808) (xy 2.316982 -178.151754) (xy 2.372744 -178.196223)
			(xy 2.423177 -178.246656) (xy 2.467646 -178.302418) (xy 2.505592 -178.362809) (xy 2.536537 -178.427068)
			(xy 2.560094 -178.494388) (xy 2.575964 -178.563923) (xy 2.58395 -178.634797) (xy 2.58395 -178.706119)
			(xy 7.813794 -178.706119) (xy 7.813794 -178.634797) (xy 7.82178 -178.563923) (xy 7.83765 -178.494388)
			(xy 7.861207 -178.427068) (xy 7.892152 -178.362809) (xy 7.930098 -178.302418) (xy 7.974567 -178.246656)
			(xy 8.025 -178.196223) (xy 8.080762 -178.151754) (xy 8.141153 -178.113808) (xy 8.205412 -178.082863)
			(xy 8.272732 -178.059306) (xy 8.342267 -178.043436) (xy 8.413141 -178.03545) (xy 8.448802 -178.03495)
			(xy 8.484463 -178.03545) (xy 8.555337 -178.043436) (xy 8.624872 -178.059306) (xy 8.692192 -178.082863)
			(xy 8.756451 -178.113808) (xy 8.816842 -178.151754) (xy 8.872604 -178.196223) (xy 8.923037 -178.246656)
			(xy 8.967506 -178.302418) (xy 9.005452 -178.362809) (xy 9.036397 -178.427068) (xy 9.059954 -178.494388)
			(xy 9.075824 -178.563923) (xy 9.08381 -178.634797) (xy 9.08381 -178.706119) (xy 9.075824 -178.776993)
			(xy 9.059954 -178.846528) (xy 9.036397 -178.913848) (xy 9.005452 -178.978107) (xy 8.967506 -179.038498)
			(xy 8.923037 -179.09426) (xy 8.872604 -179.144693) (xy 8.816842 -179.189162) (xy 8.756451 -179.227108)
			(xy 8.692192 -179.258053) (xy 8.624872 -179.28161) (xy 8.555337 -179.29748) (xy 8.484463 -179.305466)
			(xy 8.413141 -179.305466) (xy 8.342267 -179.29748) (xy 8.272732 -179.28161) (xy 8.205412 -179.258053)
			(xy 8.141153 -179.227108) (xy 8.080762 -179.189162) (xy 8.025 -179.144693) (xy 7.974567 -179.09426)
			(xy 7.930098 -179.038498) (xy 7.892152 -178.978107) (xy 7.861207 -178.913848) (xy 7.83765 -178.846528)
			(xy 7.82178 -178.776993) (xy 7.813794 -178.706119) (xy 2.58395 -178.706119) (xy 2.575964 -178.776993)
			(xy 2.560094 -178.846528) (xy 2.536537 -178.913848) (xy 2.505592 -178.978107) (xy 2.467646 -179.038498)
			(xy 2.423177 -179.09426) (xy 2.372744 -179.144693) (xy 2.316982 -179.189162) (xy 2.256591 -179.227108)
			(xy 2.192332 -179.258053) (xy 2.125012 -179.28161) (xy 2.055477 -179.29748) (xy 1.984603 -179.305466)
			(xy 1.913281 -179.305466) (xy 1.842407 -179.29748) (xy 1.772872 -179.28161) (xy 1.705552 -179.258053)
			(xy 1.641293 -179.227108) (xy 1.580902 -179.189162) (xy 1.52514 -179.144693) (xy 1.474707 -179.09426)
			(xy 1.430238 -179.038498) (xy 1.392292 -178.978107) (xy 1.361347 -178.913848) (xy 1.33779 -178.846528)
			(xy 1.32192 -178.776993) (xy 1.313934 -178.706119) (xy 0.509016 -178.706119) (xy 0.509016 -179.706117)
			(xy 3.31393 -179.706117) (xy 3.31393 -179.634795) (xy 3.321916 -179.563921) (xy 3.337786 -179.494386)
			(xy 3.361343 -179.427066) (xy 3.392288 -179.362807) (xy 3.430234 -179.302416) (xy 3.474703 -179.246654)
			(xy 3.525136 -179.196221) (xy 3.580898 -179.151752) (xy 3.641289 -179.113806) (xy 3.705548 -179.082861)
			(xy 3.772868 -179.059304) (xy 3.842403 -179.043434) (xy 3.913277 -179.035448) (xy 3.948938 -179.034948)
			(xy 3.984599 -179.035448) (xy 4.055473 -179.043434) (xy 4.125008 -179.059304) (xy 4.192328 -179.082861)
			(xy 4.256587 -179.113806) (xy 4.316978 -179.151752) (xy 4.37274 -179.196221) (xy 4.423173 -179.246654)
			(xy 4.467642 -179.302416) (xy 4.505588 -179.362807) (xy 4.536533 -179.427066) (xy 4.56009 -179.494386)
			(xy 4.57596 -179.563921) (xy 4.583946 -179.634795) (xy 4.583946 -179.706117) (xy 5.813798 -179.706117)
			(xy 5.813798 -179.634795) (xy 5.821784 -179.563921) (xy 5.837654 -179.494386) (xy 5.861211 -179.427066)
			(xy 5.892156 -179.362807) (xy 5.930102 -179.302416) (xy 5.974571 -179.246654) (xy 6.025004 -179.196221)
			(xy 6.080766 -179.151752) (xy 6.141157 -179.113806) (xy 6.205416 -179.082861) (xy 6.272736 -179.059304)
			(xy 6.342271 -179.043434) (xy 6.413145 -179.035448) (xy 6.448806 -179.034948) (xy 6.484467 -179.035448)
			(xy 6.555341 -179.043434) (xy 6.624876 -179.059304) (xy 6.692196 -179.082861) (xy 6.756455 -179.113806)
			(xy 6.816846 -179.151752) (xy 6.872608 -179.196221) (xy 6.923041 -179.246654) (xy 6.96751 -179.302416)
			(xy 7.005456 -179.362807) (xy 7.036401 -179.427066) (xy 7.059958 -179.494386) (xy 7.075828 -179.563921)
			(xy 7.083814 -179.634795) (xy 7.083814 -179.706117) (xy 7.075828 -179.776991) (xy 7.059958 -179.846526)
			(xy 7.036401 -179.913846) (xy 7.005456 -179.978105) (xy 6.96751 -180.038496) (xy 6.923041 -180.094258)
			(xy 6.872608 -180.144691) (xy 6.816846 -180.18916) (xy 6.756455 -180.227106) (xy 6.692196 -180.258051)
			(xy 6.624876 -180.281608) (xy 6.555341 -180.297478) (xy 6.484467 -180.305464) (xy 6.413145 -180.305464)
			(xy 6.342271 -180.297478) (xy 6.272736 -180.281608) (xy 6.205416 -180.258051) (xy 6.141157 -180.227106)
			(xy 6.080766 -180.18916) (xy 6.025004 -180.144691) (xy 5.974571 -180.094258) (xy 5.930102 -180.038496)
			(xy 5.892156 -179.978105) (xy 5.861211 -179.913846) (xy 5.837654 -179.846526) (xy 5.821784 -179.776991)
			(xy 5.813798 -179.706117) (xy 4.583946 -179.706117) (xy 4.57596 -179.776991) (xy 4.56009 -179.846526)
			(xy 4.536533 -179.913846) (xy 4.505588 -179.978105) (xy 4.467642 -180.038496) (xy 4.423173 -180.094258)
			(xy 4.37274 -180.144691) (xy 4.316978 -180.18916) (xy 4.256587 -180.227106) (xy 4.192328 -180.258051)
			(xy 4.125008 -180.281608) (xy 4.055473 -180.297478) (xy 3.984599 -180.305464) (xy 3.913277 -180.305464)
			(xy 3.842403 -180.297478) (xy 3.772868 -180.281608) (xy 3.705548 -180.258051) (xy 3.641289 -180.227106)
			(xy 3.580898 -180.18916) (xy 3.525136 -180.144691) (xy 3.474703 -180.094258) (xy 3.430234 -180.038496)
			(xy 3.392288 -179.978105) (xy 3.361343 -179.913846) (xy 3.337786 -179.846526) (xy 3.321916 -179.776991)
			(xy 3.31393 -179.706117) (xy 0.509016 -179.706117) (xy 0.509016 -180.706115) (xy 1.313934 -180.706115)
			(xy 1.313934 -180.634793) (xy 1.32192 -180.563919) (xy 1.33779 -180.494384) (xy 1.361347 -180.427064)
			(xy 1.392292 -180.362805) (xy 1.430238 -180.302414) (xy 1.474707 -180.246652) (xy 1.52514 -180.196219)
			(xy 1.580902 -180.15175) (xy 1.641293 -180.113804) (xy 1.705552 -180.082859) (xy 1.772872 -180.059302)
			(xy 1.842407 -180.043432) (xy 1.913281 -180.035446) (xy 1.948942 -180.034946) (xy 1.984603 -180.035446)
			(xy 2.055477 -180.043432) (xy 2.125012 -180.059302) (xy 2.192332 -180.082859) (xy 2.256591 -180.113804)
			(xy 2.316982 -180.15175) (xy 2.372744 -180.196219) (xy 2.423177 -180.246652) (xy 2.467646 -180.302414)
			(xy 2.505592 -180.362805) (xy 2.536537 -180.427064) (xy 2.560094 -180.494384) (xy 2.575964 -180.563919)
			(xy 2.58395 -180.634793) (xy 2.58395 -180.706115) (xy 7.813794 -180.706115) (xy 7.813794 -180.634793)
			(xy 7.82178 -180.563919) (xy 7.83765 -180.494384) (xy 7.861207 -180.427064) (xy 7.892152 -180.362805)
			(xy 7.930098 -180.302414) (xy 7.974567 -180.246652) (xy 8.025 -180.196219) (xy 8.080762 -180.15175)
			(xy 8.141153 -180.113804) (xy 8.205412 -180.082859) (xy 8.272732 -180.059302) (xy 8.342267 -180.043432)
			(xy 8.413141 -180.035446) (xy 8.448802 -180.034946) (xy 8.484463 -180.035446) (xy 8.555337 -180.043432)
			(xy 8.624872 -180.059302) (xy 8.692192 -180.082859) (xy 8.756451 -180.113804) (xy 8.816842 -180.15175)
			(xy 8.872604 -180.196219) (xy 8.923037 -180.246652) (xy 8.967506 -180.302414) (xy 9.005452 -180.362805)
			(xy 9.036397 -180.427064) (xy 9.059954 -180.494384) (xy 9.075824 -180.563919) (xy 9.08381 -180.634793)
			(xy 9.08381 -180.706115) (xy 9.075824 -180.776989) (xy 9.059954 -180.846524) (xy 9.036397 -180.913844)
			(xy 9.005452 -180.978103) (xy 8.967506 -181.038494) (xy 8.923037 -181.094256) (xy 8.872604 -181.144689)
			(xy 8.816842 -181.189158) (xy 8.756451 -181.227104) (xy 8.692192 -181.258049) (xy 8.624872 -181.281606)
			(xy 8.555337 -181.297476) (xy 8.484463 -181.305462) (xy 8.413141 -181.305462) (xy 8.342267 -181.297476)
			(xy 8.272732 -181.281606) (xy 8.205412 -181.258049) (xy 8.141153 -181.227104) (xy 8.080762 -181.189158)
			(xy 8.025 -181.144689) (xy 7.974567 -181.094256) (xy 7.930098 -181.038494) (xy 7.892152 -180.978103)
			(xy 7.861207 -180.913844) (xy 7.83765 -180.846524) (xy 7.82178 -180.776989) (xy 7.813794 -180.706115)
			(xy 2.58395 -180.706115) (xy 2.575964 -180.776989) (xy 2.560094 -180.846524) (xy 2.536537 -180.913844)
			(xy 2.505592 -180.978103) (xy 2.467646 -181.038494) (xy 2.423177 -181.094256) (xy 2.372744 -181.144689)
			(xy 2.316982 -181.189158) (xy 2.256591 -181.227104) (xy 2.192332 -181.258049) (xy 2.125012 -181.281606)
			(xy 2.055477 -181.297476) (xy 1.984603 -181.305462) (xy 1.913281 -181.305462) (xy 1.842407 -181.297476)
			(xy 1.772872 -181.281606) (xy 1.705552 -181.258049) (xy 1.641293 -181.227104) (xy 1.580902 -181.189158)
			(xy 1.52514 -181.144689) (xy 1.474707 -181.094256) (xy 1.430238 -181.038494) (xy 1.392292 -180.978103)
			(xy 1.361347 -180.913844) (xy 1.33779 -180.846524) (xy 1.32192 -180.776989) (xy 1.313934 -180.706115)
			(xy 0.509016 -180.706115) (xy 0.509016 -181.706113) (xy 3.31393 -181.706113) (xy 3.31393 -181.634791)
			(xy 3.321916 -181.563917) (xy 3.337786 -181.494382) (xy 3.361343 -181.427062) (xy 3.392288 -181.362803)
			(xy 3.430234 -181.302412) (xy 3.474703 -181.24665) (xy 3.525136 -181.196217) (xy 3.580898 -181.151748)
			(xy 3.641289 -181.113802) (xy 3.705548 -181.082857) (xy 3.772868 -181.0593) (xy 3.842403 -181.04343)
			(xy 3.913277 -181.035444) (xy 3.948938 -181.034944) (xy 3.984599 -181.035444) (xy 4.055473 -181.04343)
			(xy 4.125008 -181.0593) (xy 4.192328 -181.082857) (xy 4.256587 -181.113802) (xy 4.316978 -181.151748)
			(xy 4.37274 -181.196217) (xy 4.423173 -181.24665) (xy 4.467642 -181.302412) (xy 4.505588 -181.362803)
			(xy 4.536533 -181.427062) (xy 4.56009 -181.494382) (xy 4.57596 -181.563917) (xy 4.583946 -181.634791)
			(xy 4.583946 -181.706113) (xy 5.813798 -181.706113) (xy 5.813798 -181.634791) (xy 5.821784 -181.563917)
			(xy 5.837654 -181.494382) (xy 5.861211 -181.427062) (xy 5.892156 -181.362803) (xy 5.930102 -181.302412)
			(xy 5.974571 -181.24665) (xy 6.025004 -181.196217) (xy 6.080766 -181.151748) (xy 6.141157 -181.113802)
			(xy 6.205416 -181.082857) (xy 6.272736 -181.0593) (xy 6.342271 -181.04343) (xy 6.413145 -181.035444)
			(xy 6.448806 -181.034944) (xy 6.484467 -181.035444) (xy 6.555341 -181.04343) (xy 6.624876 -181.0593)
			(xy 6.692196 -181.082857) (xy 6.756455 -181.113802) (xy 6.816846 -181.151748) (xy 6.872608 -181.196217)
			(xy 6.923041 -181.24665) (xy 6.96751 -181.302412) (xy 7.005456 -181.362803) (xy 7.036401 -181.427062)
			(xy 7.059958 -181.494382) (xy 7.075828 -181.563917) (xy 7.083814 -181.634791) (xy 7.083814 -181.706113)
			(xy 7.075828 -181.776987) (xy 7.059958 -181.846522) (xy 7.036401 -181.913842) (xy 7.005456 -181.978101)
			(xy 6.96751 -182.038492) (xy 6.923041 -182.094254) (xy 6.872608 -182.144687) (xy 6.816846 -182.189156)
			(xy 6.756455 -182.227102) (xy 6.692196 -182.258047) (xy 6.624876 -182.281604) (xy 6.555341 -182.297474)
			(xy 6.484467 -182.30546) (xy 6.413145 -182.30546) (xy 6.342271 -182.297474) (xy 6.272736 -182.281604)
			(xy 6.205416 -182.258047) (xy 6.141157 -182.227102) (xy 6.080766 -182.189156) (xy 6.025004 -182.144687)
			(xy 5.974571 -182.094254) (xy 5.930102 -182.038492) (xy 5.892156 -181.978101) (xy 5.861211 -181.913842)
			(xy 5.837654 -181.846522) (xy 5.821784 -181.776987) (xy 5.813798 -181.706113) (xy 4.583946 -181.706113)
			(xy 4.57596 -181.776987) (xy 4.56009 -181.846522) (xy 4.536533 -181.913842) (xy 4.505588 -181.978101)
			(xy 4.467642 -182.038492) (xy 4.423173 -182.094254) (xy 4.37274 -182.144687) (xy 4.316978 -182.189156)
			(xy 4.256587 -182.227102) (xy 4.192328 -182.258047) (xy 4.125008 -182.281604) (xy 4.055473 -182.297474)
			(xy 3.984599 -182.30546) (xy 3.913277 -182.30546) (xy 3.842403 -182.297474) (xy 3.772868 -182.281604)
			(xy 3.705548 -182.258047) (xy 3.641289 -182.227102) (xy 3.580898 -182.189156) (xy 3.525136 -182.144687)
			(xy 3.474703 -182.094254) (xy 3.430234 -182.038492) (xy 3.392288 -181.978101) (xy 3.361343 -181.913842)
			(xy 3.337786 -181.846522) (xy 3.321916 -181.776987) (xy 3.31393 -181.706113) (xy 0.509016 -181.706113)
			(xy 0.509016 -182.706111) (xy 1.313934 -182.706111) (xy 1.313934 -182.634789) (xy 1.32192 -182.563915)
			(xy 1.33779 -182.49438) (xy 1.361347 -182.42706) (xy 1.392292 -182.362801) (xy 1.430238 -182.30241)
			(xy 1.474707 -182.246648) (xy 1.52514 -182.196215) (xy 1.580902 -182.151746) (xy 1.641293 -182.1138)
			(xy 1.705552 -182.082855) (xy 1.772872 -182.059298) (xy 1.842407 -182.043428) (xy 1.913281 -182.035442)
			(xy 1.948942 -182.034942) (xy 1.984603 -182.035442) (xy 2.055477 -182.043428) (xy 2.125012 -182.059298)
			(xy 2.192332 -182.082855) (xy 2.256591 -182.1138) (xy 2.316982 -182.151746) (xy 2.372744 -182.196215)
			(xy 2.423177 -182.246648) (xy 2.467646 -182.30241) (xy 2.505592 -182.362801) (xy 2.536537 -182.42706)
			(xy 2.560094 -182.49438) (xy 2.575964 -182.563915) (xy 2.58395 -182.634789) (xy 2.58395 -182.706111)
			(xy 7.813794 -182.706111) (xy 7.813794 -182.634789) (xy 7.82178 -182.563915) (xy 7.83765 -182.49438)
			(xy 7.861207 -182.42706) (xy 7.892152 -182.362801) (xy 7.930098 -182.30241) (xy 7.974567 -182.246648)
			(xy 8.025 -182.196215) (xy 8.080762 -182.151746) (xy 8.141153 -182.1138) (xy 8.205412 -182.082855)
			(xy 8.272732 -182.059298) (xy 8.342267 -182.043428) (xy 8.413141 -182.035442) (xy 8.448802 -182.034942)
			(xy 8.484463 -182.035442) (xy 8.555337 -182.043428) (xy 8.624872 -182.059298) (xy 8.692192 -182.082855)
			(xy 8.756451 -182.1138) (xy 8.816842 -182.151746) (xy 8.872604 -182.196215) (xy 8.923037 -182.246648)
			(xy 8.967506 -182.30241) (xy 9.005452 -182.362801) (xy 9.036397 -182.42706) (xy 9.059954 -182.49438)
			(xy 9.075824 -182.563915) (xy 9.08381 -182.634789) (xy 9.08381 -182.706111) (xy 9.075824 -182.776985)
			(xy 9.059954 -182.84652) (xy 9.036397 -182.91384) (xy 9.005452 -182.978099) (xy 8.967506 -183.03849)
			(xy 8.923037 -183.094252) (xy 8.872604 -183.144685) (xy 8.816842 -183.189154) (xy 8.756451 -183.2271)
			(xy 8.692192 -183.258045) (xy 8.624872 -183.281602) (xy 8.555337 -183.297472) (xy 8.484463 -183.305458)
			(xy 8.413141 -183.305458) (xy 8.342267 -183.297472) (xy 8.272732 -183.281602) (xy 8.205412 -183.258045)
			(xy 8.141153 -183.2271) (xy 8.080762 -183.189154) (xy 8.025 -183.144685) (xy 7.974567 -183.094252)
			(xy 7.930098 -183.03849) (xy 7.892152 -182.978099) (xy 7.861207 -182.91384) (xy 7.83765 -182.84652)
			(xy 7.82178 -182.776985) (xy 7.813794 -182.706111) (xy 2.58395 -182.706111) (xy 2.575964 -182.776985)
			(xy 2.560094 -182.84652) (xy 2.536537 -182.91384) (xy 2.505592 -182.978099) (xy 2.467646 -183.03849)
			(xy 2.423177 -183.094252) (xy 2.372744 -183.144685) (xy 2.316982 -183.189154) (xy 2.256591 -183.2271)
			(xy 2.192332 -183.258045) (xy 2.125012 -183.281602) (xy 2.055477 -183.297472) (xy 1.984603 -183.305458)
			(xy 1.913281 -183.305458) (xy 1.842407 -183.297472) (xy 1.772872 -183.281602) (xy 1.705552 -183.258045)
			(xy 1.641293 -183.2271) (xy 1.580902 -183.189154) (xy 1.52514 -183.144685) (xy 1.474707 -183.094252)
			(xy 1.430238 -183.03849) (xy 1.392292 -182.978099) (xy 1.361347 -182.91384) (xy 1.33779 -182.84652)
			(xy 1.32192 -182.776985) (xy 1.313934 -182.706111) (xy 0.509016 -182.706111) (xy 0.509016 -184.706107)
			(xy 1.313934 -184.706107) (xy 1.313934 -184.634785) (xy 1.32192 -184.563911) (xy 1.33779 -184.494376)
			(xy 1.361347 -184.427056) (xy 1.392292 -184.362797) (xy 1.430238 -184.302406) (xy 1.474707 -184.246644)
			(xy 1.52514 -184.196211) (xy 1.580902 -184.151742) (xy 1.641293 -184.113796) (xy 1.705552 -184.082851)
			(xy 1.772872 -184.059294) (xy 1.842407 -184.043424) (xy 1.913281 -184.035438) (xy 1.948942 -184.034938)
			(xy 1.984603 -184.035438) (xy 2.055477 -184.043424) (xy 2.125012 -184.059294) (xy 2.192332 -184.082851)
			(xy 2.256591 -184.113796) (xy 2.316982 -184.151742) (xy 2.372744 -184.196211) (xy 2.423177 -184.246644)
			(xy 2.467646 -184.302406) (xy 2.505592 -184.362797) (xy 2.536537 -184.427056) (xy 2.560094 -184.494376)
			(xy 2.575964 -184.563911) (xy 2.58395 -184.634785) (xy 2.58395 -184.706107) (xy 7.813794 -184.706107)
			(xy 7.813794 -184.634785) (xy 7.82178 -184.563911) (xy 7.83765 -184.494376) (xy 7.861207 -184.427056)
			(xy 7.892152 -184.362797) (xy 7.930098 -184.302406) (xy 7.974567 -184.246644) (xy 8.025 -184.196211)
			(xy 8.080762 -184.151742) (xy 8.141153 -184.113796) (xy 8.205412 -184.082851) (xy 8.272732 -184.059294)
			(xy 8.342267 -184.043424) (xy 8.413141 -184.035438) (xy 8.448802 -184.034938) (xy 8.484463 -184.035438)
			(xy 8.555337 -184.043424) (xy 8.624872 -184.059294) (xy 8.692192 -184.082851) (xy 8.756451 -184.113796)
			(xy 8.816842 -184.151742) (xy 8.872604 -184.196211) (xy 8.923037 -184.246644) (xy 8.967506 -184.302406)
			(xy 9.005452 -184.362797) (xy 9.036397 -184.427056) (xy 9.059954 -184.494376) (xy 9.075824 -184.563911)
			(xy 9.08381 -184.634785) (xy 9.08381 -184.706107) (xy 9.075824 -184.776981) (xy 9.059954 -184.846516)
			(xy 9.036397 -184.913836) (xy 9.005452 -184.978095) (xy 8.967506 -185.038486) (xy 8.923037 -185.094248)
			(xy 8.872604 -185.144681) (xy 8.816842 -185.18915) (xy 8.756451 -185.227096) (xy 8.692192 -185.258041)
			(xy 8.624872 -185.281598) (xy 8.555337 -185.297468) (xy 8.484463 -185.305454) (xy 8.413141 -185.305454)
			(xy 8.342267 -185.297468) (xy 8.272732 -185.281598) (xy 8.205412 -185.258041) (xy 8.141153 -185.227096)
			(xy 8.080762 -185.18915) (xy 8.025 -185.144681) (xy 7.974567 -185.094248) (xy 7.930098 -185.038486)
			(xy 7.892152 -184.978095) (xy 7.861207 -184.913836) (xy 7.83765 -184.846516) (xy 7.82178 -184.776981)
			(xy 7.813794 -184.706107) (xy 2.58395 -184.706107) (xy 2.575964 -184.776981) (xy 2.560094 -184.846516)
			(xy 2.536537 -184.913836) (xy 2.505592 -184.978095) (xy 2.467646 -185.038486) (xy 2.423177 -185.094248)
			(xy 2.372744 -185.144681) (xy 2.316982 -185.18915) (xy 2.256591 -185.227096) (xy 2.192332 -185.258041)
			(xy 2.125012 -185.281598) (xy 2.055477 -185.297468) (xy 1.984603 -185.305454) (xy 1.913281 -185.305454)
			(xy 1.842407 -185.297468) (xy 1.772872 -185.281598) (xy 1.705552 -185.258041) (xy 1.641293 -185.227096)
			(xy 1.580902 -185.18915) (xy 1.52514 -185.144681) (xy 1.474707 -185.094248) (xy 1.430238 -185.038486)
			(xy 1.392292 -184.978095) (xy 1.361347 -184.913836) (xy 1.33779 -184.846516) (xy 1.32192 -184.776981)
			(xy 1.313934 -184.706107) (xy 0.509016 -184.706107) (xy 0.509016 -185.706105) (xy 3.31393 -185.706105)
			(xy 3.31393 -185.634783) (xy 3.321916 -185.563909) (xy 3.337786 -185.494374) (xy 3.361343 -185.427054)
			(xy 3.392288 -185.362795) (xy 3.430234 -185.302404) (xy 3.474703 -185.246642) (xy 3.525136 -185.196209)
			(xy 3.580898 -185.15174) (xy 3.641289 -185.113794) (xy 3.705548 -185.082849) (xy 3.772868 -185.059292)
			(xy 3.842403 -185.043422) (xy 3.913277 -185.035436) (xy 3.948938 -185.034936) (xy 3.984599 -185.035436)
			(xy 4.055473 -185.043422) (xy 4.125008 -185.059292) (xy 4.192328 -185.082849) (xy 4.256587 -185.113794)
			(xy 4.316978 -185.15174) (xy 4.37274 -185.196209) (xy 4.423173 -185.246642) (xy 4.467642 -185.302404)
			(xy 4.505588 -185.362795) (xy 4.536533 -185.427054) (xy 4.56009 -185.494374) (xy 4.57596 -185.563909)
			(xy 4.583946 -185.634783) (xy 4.583946 -185.706105) (xy 5.813798 -185.706105) (xy 5.813798 -185.634783)
			(xy 5.821784 -185.563909) (xy 5.837654 -185.494374) (xy 5.861211 -185.427054) (xy 5.892156 -185.362795)
			(xy 5.930102 -185.302404) (xy 5.974571 -185.246642) (xy 6.025004 -185.196209) (xy 6.080766 -185.15174)
			(xy 6.141157 -185.113794) (xy 6.205416 -185.082849) (xy 6.272736 -185.059292) (xy 6.342271 -185.043422)
			(xy 6.413145 -185.035436) (xy 6.448806 -185.034936) (xy 6.484467 -185.035436) (xy 6.555341 -185.043422)
			(xy 6.624876 -185.059292) (xy 6.692196 -185.082849) (xy 6.756455 -185.113794) (xy 6.816846 -185.15174)
			(xy 6.872608 -185.196209) (xy 6.923041 -185.246642) (xy 6.96751 -185.302404) (xy 7.005456 -185.362795)
			(xy 7.036401 -185.427054) (xy 7.059958 -185.494374) (xy 7.075828 -185.563909) (xy 7.083814 -185.634783)
			(xy 7.083814 -185.706105) (xy 7.075828 -185.776979) (xy 7.059958 -185.846514) (xy 7.036401 -185.913834)
			(xy 7.005456 -185.978093) (xy 6.96751 -186.038484) (xy 6.923041 -186.094246) (xy 6.872608 -186.144679)
			(xy 6.816846 -186.189148) (xy 6.756455 -186.227094) (xy 6.692196 -186.258039) (xy 6.624876 -186.281596)
			(xy 6.555341 -186.297466) (xy 6.484467 -186.305452) (xy 6.413145 -186.305452) (xy 6.342271 -186.297466)
			(xy 6.272736 -186.281596) (xy 6.205416 -186.258039) (xy 6.141157 -186.227094) (xy 6.080766 -186.189148)
			(xy 6.025004 -186.144679) (xy 5.974571 -186.094246) (xy 5.930102 -186.038484) (xy 5.892156 -185.978093)
			(xy 5.861211 -185.913834) (xy 5.837654 -185.846514) (xy 5.821784 -185.776979) (xy 5.813798 -185.706105)
			(xy 4.583946 -185.706105) (xy 4.57596 -185.776979) (xy 4.56009 -185.846514) (xy 4.536533 -185.913834)
			(xy 4.505588 -185.978093) (xy 4.467642 -186.038484) (xy 4.423173 -186.094246) (xy 4.37274 -186.144679)
			(xy 4.316978 -186.189148) (xy 4.256587 -186.227094) (xy 4.192328 -186.258039) (xy 4.125008 -186.281596)
			(xy 4.055473 -186.297466) (xy 3.984599 -186.305452) (xy 3.913277 -186.305452) (xy 3.842403 -186.297466)
			(xy 3.772868 -186.281596) (xy 3.705548 -186.258039) (xy 3.641289 -186.227094) (xy 3.580898 -186.189148)
			(xy 3.525136 -186.144679) (xy 3.474703 -186.094246) (xy 3.430234 -186.038484) (xy 3.392288 -185.978093)
			(xy 3.361343 -185.913834) (xy 3.337786 -185.846514) (xy 3.321916 -185.776979) (xy 3.31393 -185.706105)
			(xy 0.509016 -185.706105) (xy 0.509016 -187.706101) (xy 3.31393 -187.706101) (xy 3.31393 -187.634779)
			(xy 3.321916 -187.563905) (xy 3.337786 -187.49437) (xy 3.361343 -187.42705) (xy 3.392288 -187.362791)
			(xy 3.430234 -187.3024) (xy 3.474703 -187.246638) (xy 3.525136 -187.196205) (xy 3.580898 -187.151736)
			(xy 3.641289 -187.11379) (xy 3.705548 -187.082845) (xy 3.772868 -187.059288) (xy 3.842403 -187.043418)
			(xy 3.913277 -187.035432) (xy 3.948938 -187.034932) (xy 3.984599 -187.035432) (xy 4.055473 -187.043418)
			(xy 4.125008 -187.059288) (xy 4.192328 -187.082845) (xy 4.256587 -187.11379) (xy 4.316978 -187.151736)
			(xy 4.37274 -187.196205) (xy 4.423173 -187.246638) (xy 4.467642 -187.3024) (xy 4.505588 -187.362791)
			(xy 4.536533 -187.42705) (xy 4.56009 -187.49437) (xy 4.57596 -187.563905) (xy 4.583946 -187.634779)
			(xy 4.583946 -187.706101) (xy 4.57596 -187.776975) (xy 4.56009 -187.84651) (xy 4.536533 -187.91383)
			(xy 4.505588 -187.978089) (xy 4.467642 -188.03848) (xy 4.423173 -188.094242) (xy 4.37274 -188.144675)
			(xy 4.316978 -188.189144) (xy 4.256587 -188.22709) (xy 4.192328 -188.258035) (xy 4.125008 -188.281592)
			(xy 4.055473 -188.297462) (xy 3.984599 -188.305448) (xy 3.913277 -188.305448) (xy 3.842403 -188.297462)
			(xy 3.772868 -188.281592) (xy 3.705548 -188.258035) (xy 3.641289 -188.22709) (xy 3.580898 -188.189144)
			(xy 3.525136 -188.144675) (xy 3.474703 -188.094242) (xy 3.430234 -188.03848) (xy 3.392288 -187.978089)
			(xy 3.361343 -187.91383) (xy 3.337786 -187.84651) (xy 3.321916 -187.776975) (xy 3.31393 -187.706101)
			(xy 0.509016 -187.706101) (xy 0.509016 -188.706099) (xy 1.313934 -188.706099) (xy 1.313934 -188.634777)
			(xy 1.32192 -188.563903) (xy 1.33779 -188.494368) (xy 1.361347 -188.427048) (xy 1.392292 -188.362789)
			(xy 1.430238 -188.302398) (xy 1.474707 -188.246636) (xy 1.52514 -188.196203) (xy 1.580902 -188.151734)
			(xy 1.641293 -188.113788) (xy 1.705552 -188.082843) (xy 1.772872 -188.059286) (xy 1.842407 -188.043416)
			(xy 1.913281 -188.03543) (xy 1.948942 -188.03493) (xy 1.984603 -188.03543) (xy 2.055477 -188.043416)
			(xy 2.125012 -188.059286) (xy 2.192332 -188.082843) (xy 2.256591 -188.113788) (xy 2.316982 -188.151734)
			(xy 2.372744 -188.196203) (xy 2.423177 -188.246636) (xy 2.467646 -188.302398) (xy 2.505592 -188.362789)
			(xy 2.536537 -188.427048) (xy 2.560094 -188.494368) (xy 2.575964 -188.563903) (xy 2.58395 -188.634777)
			(xy 2.58395 -188.706099) (xy 2.575964 -188.776973) (xy 2.560094 -188.846508) (xy 2.536537 -188.913828)
			(xy 2.505592 -188.978087) (xy 2.467646 -189.038478) (xy 2.423177 -189.09424) (xy 2.372744 -189.144673)
			(xy 2.316982 -189.189142) (xy 2.256591 -189.227088) (xy 2.192332 -189.258033) (xy 2.125012 -189.28159)
			(xy 2.055477 -189.29746) (xy 1.984603 -189.305446) (xy 1.913281 -189.305446) (xy 1.842407 -189.29746)
			(xy 1.772872 -189.28159) (xy 1.705552 -189.258033) (xy 1.641293 -189.227088) (xy 1.580902 -189.189142)
			(xy 1.52514 -189.144673) (xy 1.474707 -189.09424) (xy 1.430238 -189.038478) (xy 1.392292 -188.978087)
			(xy 1.361347 -188.913828) (xy 1.33779 -188.846508) (xy 1.32192 -188.776973) (xy 1.313934 -188.706099)
			(xy 0.509016 -188.706099) (xy 0.509016 -204.069696) (xy 0.898652 -204.069696) (xy 0.898652 -192.163446)
			(xy 1.542542 -191.519302) (xy 1.558523 -191.502584) (xy 1.584759 -191.464503) (xy 1.60368 -191.422308)
			(xy 1.614662 -191.377387) (xy 1.617344 -191.331221) (xy 1.611637 -191.285331) (xy 1.597729 -191.241228)
			(xy 1.576078 -191.200366) (xy 1.547398 -191.16409) (xy 1.53035 -191.148462) (xy 1.5042 -191.124935)
			(xy 1.456717 -191.073031) (xy 1.415258 -191.016201) (xy 1.380329 -190.955139) (xy 1.352357 -190.890593)
			(xy 1.331685 -190.823353) (xy 1.318567 -190.754241) (xy 1.313161 -190.684102) (xy 1.315536 -190.613796)
			(xy 1.32566 -190.544183) (xy 1.343411 -190.476113) (xy 1.368572 -190.41042) (xy 1.400834 -190.347908)
			(xy 1.439803 -190.289342) (xy 1.485002 -190.235438) (xy 1.535878 -190.186856) (xy 1.591808 -190.14419)
			(xy 1.652108 -190.107962) (xy 1.716041 -190.078616) (xy 1.782823 -190.05651) (xy 1.851639 -190.041916)
			(xy 1.921645 -190.035011) (xy 1.991986 -190.03588) (xy 2.061801 -190.044513) (xy 2.130235 -190.060803)
			(xy 2.196451 -190.084552) (xy 2.259638 -190.115469) (xy 2.319025 -190.153176) (xy 2.373884 -190.197211)
			(xy 2.423544 -190.247036) (xy 2.467397 -190.30204) (xy 2.504907 -190.361551) (xy 2.535614 -190.424841)
			(xy 2.559144 -190.491136) (xy 2.575208 -190.559623) (xy 2.579878 -190.594488) (xy 2.582964 -190.61613)
			(xy 2.595573 -190.657984) (xy 2.615157 -190.697063) (xy 2.641138 -190.732216) (xy 2.672752 -190.762404)
			(xy 2.709064 -190.786739) (xy 2.749004 -190.804501) (xy 2.791395 -190.815167) (xy 2.834986 -190.818424)
			(xy 2.87849 -190.814173) (xy 2.920627 -190.802542) (xy 2.960151 -190.783872) (xy 2.995898 -190.758715)
			(xy 3.011678 -190.743586) (xy 3.61696 -190.138304) (xy 4.424172 -190.138304) (xy 6.042914 -188.519562)
			(xy 6.058915 -188.502851) (xy 6.085173 -188.464763) (xy 6.104102 -188.42255) (xy 6.115077 -188.377609)
			(xy 6.117734 -188.331423) (xy 6.111986 -188.285519) (xy 6.098022 -188.241414) (xy 6.076305 -188.200566)
			(xy 6.047552 -188.164324) (xy 6.030468 -188.148722) (xy 6.003589 -188.124549) (xy 5.954925 -188.071089)
			(xy 5.912641 -188.012452) (xy 5.877285 -187.949396) (xy 5.849312 -187.882735) (xy 5.829084 -187.81333)
			(xy 5.816862 -187.742079) (xy 5.812805 -187.6699) (xy 5.816964 -187.597728) (xy 5.829287 -187.526493)
			(xy 5.849613 -187.457117) (xy 5.87768 -187.390496) (xy 5.913126 -187.32749) (xy 5.955492 -187.268913)
			(xy 6.004232 -187.215522) (xy 6.058716 -187.168007) (xy 6.118239 -187.126981) (xy 6.182034 -187.092974)
			(xy 6.249275 -187.066427) (xy 6.319095 -187.047681) (xy 6.390591 -187.036979) (xy 6.462839 -187.034459)
			(xy 6.534907 -187.040153) (xy 6.605863 -187.053989) (xy 6.67479 -187.075788) (xy 6.740799 -187.105267)
			(xy 6.803036 -187.142046) (xy 6.860698 -187.185649) (xy 6.91304 -187.235515) (xy 6.959384 -187.290998)
			(xy 6.999134 -187.351381) (xy 7.031775 -187.415885) (xy 7.056885 -187.483676) (xy 7.07414 -187.553879)
			(xy 7.079234 -187.589668) (xy 7.082529 -187.611199) (xy 7.095395 -187.652808) (xy 7.115167 -187.691613)
			(xy 7.141266 -187.726479) (xy 7.172928 -187.756384) (xy 7.209226 -187.780452) (xy 7.249096 -187.797979)
			(xy 7.29137 -187.808451) (xy 7.334811 -187.811562) (xy 7.378146 -187.80722) (xy 7.420106 -187.795553)
			(xy 7.459463 -187.776901) (xy 7.495063 -187.751813) (xy 7.51078 -187.736734) (xy 7.82701 -187.420504)
			(xy 9.163812 -187.420504) (xy 9.4361 -187.148216) (xy 9.4361 -170.81373) (xy 10.753344 -169.496232)
			(xy 18.901156 -161.34842) (xy 18.901156 -133.812026) (xy 16.187166 -131.098036) (xy 15.677388 -131.098036)
			(xy 13.664692 -129.08534) (xy 13.648401 -129.069796) (xy 13.61144 -129.044087) (xy 13.570526 -129.025295)
			(xy 13.52694 -129.014008) (xy 13.482048 -129.01058) (xy 13.437254 -129.015119) (xy 13.393962 -129.027482)
			(xy 13.353526 -129.047282) (xy 13.317213 -129.073899) (xy 13.286161 -129.106499) (xy 13.26134 -129.144062)
			(xy 13.243529 -129.185413) (xy 13.233284 -129.229255) (xy 13.231622 -129.25171) (xy 13.22905 -129.291094)
			(xy 13.217018 -129.369101) (xy 13.197248 -129.445515) (xy 13.169936 -129.519569) (xy 13.135358 -129.590522)
			(xy 13.09386 -129.657662) (xy 13.045857 -129.720317) (xy 12.991831 -129.777859) (xy 12.932322 -129.829712)
			(xy 12.867928 -129.875355) (xy 12.799293 -129.914331) (xy 12.727105 -129.94625) (xy 12.652087 -129.970793)
			(xy 12.574992 -129.987712) (xy 12.496592 -129.996839) (xy 12.417672 -129.998082) (xy 12.339023 -129.991429)
			(xy 12.261433 -129.976945) (xy 12.18568 -129.954778) (xy 12.112523 -129.925148) (xy 12.042694 -129.888352)
			(xy 11.976894 -129.844759) (xy 11.915782 -129.794807) (xy 11.859971 -129.738995) (xy 11.810018 -129.677883)
			(xy 11.766426 -129.612083) (xy 11.729631 -129.542254) (xy 11.700001 -129.469097) (xy 11.677834 -129.393343)
			(xy 11.663351 -129.315754) (xy 11.656698 -129.237105) (xy 11.657941 -129.158185) (xy 11.667069 -129.079784)
			(xy 11.683988 -129.002689) (xy 11.708531 -128.927672) (xy 11.740451 -128.855484) (xy 11.779427 -128.786849)
			(xy 11.825071 -128.722455) (xy 11.876923 -128.662947) (xy 11.934466 -128.608921) (xy 11.997121 -128.560918)
			(xy 12.064261 -128.51942) (xy 12.135214 -128.484842) (xy 12.209268 -128.457531) (xy 12.285682 -128.437761)
			(xy 12.36369 -128.425729) (xy 12.403074 -128.423162) (xy 12.425539 -128.421509) (xy 12.469404 -128.411291)
			(xy 12.51078 -128.393497) (xy 12.548368 -128.368683) (xy 12.580991 -128.33763) (xy 12.607626 -128.301309)
			(xy 12.627437 -128.26086) (xy 12.639803 -128.217551) (xy 12.644337 -128.17274) (xy 12.640896 -128.127832)
			(xy 12.629589 -128.084234) (xy 12.61077 -128.043315) (xy 12.585029 -128.006355) (xy 12.569444 -127.990092)
			(xy 6.621272 -122.041666) (xy 6.621272 -116.101114) (xy 0.925576 -110.405418) (xy 0.925576 -104.056942)
			(xy 3.20294 -101.779324) (xy 3.218267 -101.763322) (xy 3.243694 -101.72704) (xy 3.262443 -101.686897)
			(xy 3.273945 -101.644111) (xy 3.27785 -101.599978) (xy 3.274041 -101.555837) (xy 3.262633 -101.513026)
			(xy 3.243972 -101.472842) (xy 3.218624 -101.436505) (xy 3.187357 -101.405115) (xy 3.151119 -101.379625)
			(xy 3.111008 -101.360807) (xy 3.068242 -101.349232) (xy 3.046222 -101.346762) (xy 2.981783 -101.340403)
			(xy 2.853792 -101.320697) (xy 2.727272 -101.293079) (xy 2.602711 -101.257656) (xy 2.480591 -101.214565)
			(xy 2.361383 -101.163973) (xy 2.245548 -101.106074) (xy 2.133532 -101.041093) (xy 2.025768 -100.969279)
			(xy 1.922673 -100.890912) (xy 1.824644 -100.806292) (xy 1.73206 -100.715748) (xy 1.645279 -100.619627)
			(xy 1.564635 -100.518303) (xy 1.49044 -100.412165) (xy 1.42298 -100.301624) (xy 1.362516 -100.187107)
			(xy 1.309282 -100.069055) (xy 1.263482 -99.947925) (xy 1.225294 -99.824184) (xy 1.194865 -99.69831)
			(xy 1.172314 -99.570789) (xy 1.157725 -99.442114) (xy 1.151157 -99.312781) (xy 1.152635 -99.18329)
			(xy 1.162152 -99.054141) (xy 1.179672 -98.925832) (xy 1.205128 -98.798859) (xy 1.23842 -98.673712)
			(xy 1.279421 -98.550875) (xy 1.327973 -98.430821) (xy 1.383887 -98.314015) (xy 1.446948 -98.200907)
			(xy 1.516912 -98.091934) (xy 1.593509 -97.987516) (xy 1.676444 -97.888058) (xy 1.765396 -97.793943)
			(xy 1.860022 -97.705534) (xy 1.959956 -97.623173) (xy 2.064812 -97.547178) (xy 2.174186 -97.477843)
			(xy 2.287655 -97.415434) (xy 2.404782 -97.360193) (xy 2.525113 -97.312334) (xy 2.648184 -97.27204)
			(xy 2.773521 -97.239469) (xy 2.900638 -97.214745) (xy 3.029046 -97.197963) (xy 3.158248 -97.18919)
			(xy 3.287745 -97.188458) (xy 3.417038 -97.19577) (xy 3.545627 -97.211099) (xy 3.673016 -97.234384)
			(xy 3.798712 -97.265537) (xy 3.922231 -97.304437) (xy 4.043096 -97.350933) (xy 4.160839 -97.404846)
			(xy 4.275007 -97.465968) (xy 4.385157 -97.534063) (xy 4.490866 -97.608868) (xy 4.591725 -97.690094)
			(xy 4.687344 -97.777427) (xy 4.777354 -97.870531) (xy 4.861408 -97.969045) (xy 4.939181 -98.07259)
			(xy 5.010372 -98.180765) (xy 5.074708 -98.293153) (xy 5.131939 -98.40932) (xy 5.181844 -98.528817)
			(xy 5.224231 -98.651183) (xy 5.258936 -98.775946) (xy 5.285826 -98.902623) (xy 5.304795 -99.030725)
			(xy 5.315772 -99.159759) (xy 5.318713 -99.289225) (xy 5.313607 -99.418624) (xy 5.300475 -99.547456)
			(xy 5.279366 -99.675223) (xy 5.250362 -99.801433) (xy 5.213575 -99.925598) (xy 5.169148 -100.047238)
			(xy 5.117251 -100.165884) (xy 5.058086 -100.281077) (xy 4.99188 -100.392374) (xy 4.918889 -100.499343)
			(xy 4.839396 -100.601573) (xy 4.753707 -100.698668) (xy 4.662152 -100.790254) (xy 4.565086 -100.875976)
			(xy 4.462883 -100.955504) (xy 4.409694 -100.992432) (xy 4.390926 -101.005876) (xy 4.358138 -101.038371)
			(xy 4.331758 -101.076253) (xy 4.312651 -101.118275) (xy 4.301447 -101.163057) (xy 4.298514 -101.209125)
			(xy 4.303948 -101.254967) (xy 4.317571 -101.299073) (xy 4.338935 -101.339994) (xy 4.367337 -101.376384)
			(xy 4.401843 -101.407048) (xy 4.441319 -101.430976) (xy 4.484468 -101.447382) (xy 4.529869 -101.455727)
			(xy 4.55295 -101.456236) (xy 5.02793 -101.456236) (xy 5.044544 -101.455657) (xy 5.076644 -101.447074)
			(xy 5.105441 -101.430496) (xy 5.117592 -101.419152) (xy 7.327392 -99.209098) (xy 7.327392 -63.930276)
			(xy 6.120892 -62.723776) (xy 6.052312 -62.706758) (xy 6.01853 -62.717172) (xy 5.979563 -62.728701)
			(xy 5.899938 -62.74495) (xy 5.819101 -62.753301) (xy 5.737835 -62.753673) (xy 5.656925 -62.746062)
			(xy 5.577154 -62.730543) (xy 5.499292 -62.707264) (xy 5.424094 -62.676451) (xy 5.352284 -62.638402)
			(xy 5.284559 -62.593484) (xy 5.221572 -62.542133) (xy 5.163932 -62.484844) (xy 5.112198 -62.422172)
			(xy 5.066868 -62.354721) (xy 5.028382 -62.283145) (xy 4.997111 -62.208136) (xy 4.973357 -62.130418)
			(xy 4.957351 -62.050743) (xy 4.949247 -61.969881) (xy 4.949123 -61.888614) (xy 4.956981 -61.807728)
			(xy 4.972744 -61.728005) (xy 4.996261 -61.650215) (xy 5.027303 -61.57511) (xy 5.065571 -61.503417)
			(xy 5.110695 -61.435829) (xy 5.162239 -61.372999) (xy 5.219703 -61.315535) (xy 5.282533 -61.263992)
			(xy 5.350122 -61.218869) (xy 5.421815 -61.180601) (xy 5.496919 -61.149559) (xy 5.574709 -61.126043)
			(xy 5.654433 -61.11028) (xy 5.735319 -61.102423) (xy 5.816586 -61.102547) (xy 5.897448 -61.110652)
			(xy 5.977123 -61.126658) (xy 6.054841 -61.150412) (xy 6.12985 -61.181684) (xy 6.201426 -61.220171)
			(xy 6.268876 -61.265501) (xy 6.331548 -61.317236) (xy 6.388836 -61.374876) (xy 6.440187 -61.437863)
			(xy 6.485104 -61.505589) (xy 6.523153 -61.577398) (xy 6.553965 -61.652597) (xy 6.577244 -61.730459)
			(xy 6.592763 -61.81023) (xy 6.600374 -61.89114) (xy 6.600001 -61.972406) (xy 6.59165 -62.053243)
			(xy 6.5754 -62.132868) (xy 6.563868 -62.171834) (xy 6.553454 -62.205616) (xy 6.570472 -62.274196)
			(xy 6.757416 -62.46114) (xy 6.769591 -62.472468) (xy 6.798395 -62.489059) (xy 6.830508 -62.497642)
			(xy 6.863748 -62.497635) (xy 6.895857 -62.489038) (xy 6.924654 -62.472434) (xy 6.948181 -62.448953)
			(xy 6.964841 -62.420189) (xy 6.973502 -62.388097) (xy 6.974078 -62.371478) (xy 6.974332 -61.549026)
			(xy 8.764016 -59.759088) (xy 8.775811 -59.746487) (xy 8.792789 -59.716454) (xy 8.801079 -59.682965)
			(xy 8.800074 -59.64848) (xy 8.795512 -59.631834) (xy 8.783483 -59.591002) (xy 8.766853 -59.507516)
			(xy 8.758892 -59.422763) (xy 8.759685 -59.33764) (xy 8.769225 -59.253049) (xy 8.787409 -59.169888)
			(xy 8.814045 -59.089036) (xy 8.84885 -59.01135) (xy 8.86968 -58.974228) (xy 8.880304 -58.954765)
			(xy 8.895474 -58.913108) (xy 8.903183 -58.869449) (xy 8.903197 -58.825115) (xy 8.895516 -58.781451)
			(xy 8.880373 -58.739784) (xy 8.858228 -58.701377) (xy 8.829753 -58.667396) (xy 8.795812 -58.638874)
			(xy 8.757436 -58.616676) (xy 8.715789 -58.601475) (xy 8.672136 -58.593734) (xy 8.64997 -58.593228)
			(xy 8.289036 -58.593228) (xy 7.840472 -59.041792) (xy 7.823454 -59.110372) (xy 7.833868 -59.144154)
			(xy 7.84541 -59.183117) (xy 7.86166 -59.262742) (xy 7.870012 -59.343579) (xy 7.870385 -59.424845)
			(xy 7.862776 -59.505755) (xy 7.847257 -59.585526) (xy 7.823979 -59.663388) (xy 7.793167 -59.738588)
			(xy 7.755118 -59.810397) (xy 7.710202 -59.878123) (xy 7.658851 -59.941111) (xy 7.601563 -59.998751)
			(xy 7.538891 -60.050487) (xy 7.471442 -60.095817) (xy 7.399866 -60.134305) (xy 7.324857 -60.165577)
			(xy 7.247139 -60.189331) (xy 7.167465 -60.205339) (xy 7.086603 -60.213444) (xy 7.005336 -60.213569)
			(xy 6.92445 -60.205712) (xy 6.844726 -60.18995) (xy 6.766935 -60.166435) (xy 6.691831 -60.135393)
			(xy 6.620137 -60.097126) (xy 6.552548 -60.052003) (xy 6.489718 -60.000461) (xy 6.432253 -59.942997)
			(xy 6.380709 -59.880168) (xy 6.335584 -59.81258) (xy 6.297315 -59.740888) (xy 6.266272 -59.665783)
			(xy 6.242755 -59.587994) (xy 6.22699 -59.50827) (xy 6.219132 -59.427384) (xy 6.219255 -59.346117)
			(xy 6.227358 -59.265255) (xy 6.243364 -59.18558) (xy 6.267116 -59.107862) (xy 6.298387 -59.032852)
			(xy 6.336872 -58.961275) (xy 6.382201 -58.893825) (xy 6.433935 -58.831152) (xy 6.491574 -58.773862)
			(xy 6.55456 -58.72251) (xy 6.622285 -58.677592) (xy 6.694094 -58.639542) (xy 6.769293 -58.608728)
			(xy 6.847154 -58.585448) (xy 6.926925 -58.569927) (xy 7.007835 -58.562316) (xy 7.089101 -58.562686)
			(xy 7.169938 -58.571037) (xy 7.249564 -58.587285) (xy 7.28853 -58.598816) (xy 7.322312 -58.60923)
			(xy 7.390892 -58.592212) (xy 7.565644 -58.41746) (xy 7.577066 -58.405317) (xy 7.593773 -58.376482)
			(xy 7.602441 -58.344305) (xy 7.602479 -58.31098) (xy 7.593883 -58.278783) (xy 7.577241 -58.249911)
			(xy 7.553688 -58.226335) (xy 7.524833 -58.209665) (xy 7.492644 -58.201038) (xy 7.475982 -58.200544)
			(xy 6.194044 -58.200544) (xy 6.17743 -58.201113) (xy 6.145329 -58.209702) (xy 6.116533 -58.226283)
			(xy 6.104382 -58.237628) (xy 5.325364 -59.0169) (xy 5.313575 -59.029506) (xy 5.296598 -59.059537)
			(xy 5.288306 -59.093024) (xy 5.289309 -59.127508) (xy 5.293868 -59.144154) (xy 5.305397 -59.18312)
			(xy 5.321646 -59.262746) (xy 5.329997 -59.343582) (xy 5.330368 -59.424847) (xy 5.322757 -59.505756)
			(xy 5.307237 -59.585527) (xy 5.283958 -59.663388) (xy 5.253145 -59.738586) (xy 5.215096 -59.810395)
			(xy 5.170179 -59.87812) (xy 5.118828 -59.941106) (xy 5.06154 -59.998745) (xy 4.998867 -60.050479)
			(xy 4.931418 -60.095808) (xy 4.859842 -60.134294) (xy 4.784833 -60.165565) (xy 4.707116 -60.189318)
			(xy 4.627441 -60.205324) (xy 4.54658 -60.213428) (xy 4.465314 -60.213552) (xy 4.384428 -60.205694)
			(xy 4.304705 -60.189931) (xy 4.226916 -60.166414) (xy 4.151812 -60.135372) (xy 4.08012 -60.097104)
			(xy 4.012532 -60.051981) (xy 3.949703 -60.000438) (xy 3.892239 -59.942974) (xy 3.840696 -59.880144)
			(xy 3.795573 -59.812556) (xy 3.757306 -59.740863) (xy 3.726264 -59.665759) (xy 3.702748 -59.58797)
			(xy 3.686985 -59.508247) (xy 3.679128 -59.427361) (xy 3.679252 -59.346095) (xy 3.687357 -59.265234)
			(xy 3.703363 -59.185559) (xy 3.727117 -59.107842) (xy 3.758388 -59.032833) (xy 3.796874 -58.961258)
			(xy 3.842204 -58.893809) (xy 3.893939 -58.831137) (xy 3.951578 -58.773849) (xy 4.014564 -58.722498)
			(xy 4.08229 -58.677581) (xy 4.154098 -58.639533) (xy 4.229297 -58.60872) (xy 4.307158 -58.585442)
			(xy 4.386929 -58.569922) (xy 4.467838 -58.562312) (xy 4.549103 -58.562684) (xy 4.629939 -58.571035)
			(xy 4.709564 -58.587284) (xy 4.74853 -58.598816) (xy 4.765178 -58.603335) (xy 4.799646 -58.604283)
			(xy 4.833117 -58.595997) (xy 4.863163 -58.579079) (xy 4.875784 -58.56732) (xy 5.878322 -57.565036)
			(xy 10.66546 -57.565036) (xy 11.444732 -58.344308) (xy 11.444732 -58.395362) (xy 11.445211 -58.418209)
			(xy 11.453357 -58.463171) (xy 11.469412 -58.505952) (xy 11.492858 -58.545172) (xy 11.52294 -58.579567)
			(xy 11.558687 -58.608029) (xy 11.598947 -58.62964) (xy 11.642423 -58.643704) (xy 11.687713 -58.649767)
			(xy 11.733357 -58.647634) (xy 11.777884 -58.637373) (xy 11.799062 -58.628788) (xy 11.836749 -58.613171)
			(xy 11.914534 -58.588564) (xy 11.994366 -58.571745) (xy 12.075467 -58.562879) (xy 12.157046 -58.56205)
			(xy 12.238311 -58.569268) (xy 12.318467 -58.584462) (xy 12.396736 -58.607484) (xy 12.472353 -58.63811)
			(xy 12.544584 -58.676041) (xy 12.612722 -58.720907) (xy 12.676106 -58.772273) (xy 12.734118 -58.829637)
			(xy 12.786192 -58.89244) (xy 12.831821 -58.960071) (xy 12.87056 -59.031871) (xy 12.902033 -59.10714)
			(xy 12.925932 -59.185145) (xy 12.942024 -59.265127) (xy 12.950154 -59.346305) (xy 12.950241 -59.427889)
			(xy 12.942286 -59.509084) (xy 12.926364 -59.589099) (xy 12.902632 -59.667155) (xy 12.871321 -59.742492)
			(xy 12.832735 -59.814374) (xy 12.787251 -59.882103) (xy 12.735312 -59.945017) (xy 12.677423 -60.002505)
			(xy 12.614149 -60.054006) (xy 12.546106 -60.099019) (xy 12.510262 -60.118498) (xy 12.495264 -60.12706)
			(xy 12.470128 -60.150715) (xy 12.452274 -60.180256) (xy 12.443015 -60.213507) (xy 12.442444 -60.230766)
			(xy 12.442444 -61.104018) (xy 12.442953 -61.126255) (xy 12.45068 -61.170051) (xy 12.465912 -61.211834)
			(xy 12.488186 -61.250327) (xy 12.516819 -61.284355) (xy 12.550939 -61.31288) (xy 12.589503 -61.33503)
			(xy 12.631334 -61.35013) (xy 12.675155 -61.357717) (xy 12.719628 -61.357561) (xy 12.763394 -61.349665)
			(xy 12.805118 -61.334272) (xy 12.843525 -61.311851) (xy 12.860782 -61.29782) (xy 12.892199 -61.271849)
			(xy 12.959283 -61.225538) (xy 13.030603 -61.18606) (xy 13.105466 -61.153801) (xy 13.183142 -61.129073)
			(xy 13.262876 -61.112117) (xy 13.343893 -61.103098) (xy 13.425404 -61.102105) (xy 13.506616 -61.109146)
			(xy 13.58674 -61.124153) (xy 13.664996 -61.14698) (xy 13.740622 -61.177405) (xy 13.812884 -61.215132)
			(xy 13.881077 -61.259795) (xy 13.944539 -61.310957) (xy 14.002652 -61.368123) (xy 14.054851 -61.430736)
			(xy 14.100628 -61.498186) (xy 14.139538 -61.569817) (xy 14.171202 -61.644933) (xy 14.195312 -61.722803)
			(xy 14.211634 -61.80267) (xy 14.220009 -61.883755) (xy 14.220355 -61.965272) (xy 14.21267 -62.046426)
			(xy 14.197027 -62.126428) (xy 14.173579 -62.2045) (xy 14.142554 -62.279882) (xy 14.104254 -62.351842)
			(xy 14.059052 -62.419678) (xy 14.007387 -62.482732) (xy 13.949761 -62.540389) (xy 13.886736 -62.592089)
			(xy 13.818925 -62.637329) (xy 13.746987 -62.675669) (xy 13.671622 -62.706736) (xy 13.593562 -62.730227)
			(xy 13.513569 -62.745914) (xy 13.432419 -62.753645) (xy 13.350903 -62.753343) (xy 13.269812 -62.745014)
			(xy 13.189937 -62.728736) (xy 13.15085 -62.717172) (xy 13.117068 -62.706758) (xy 13.048488 -62.723776)
			(xy 10.174732 -65.597532) (xy 10.174732 -68.310405) (xy 12.580876 -68.310405) (xy 12.582892 -68.180792)
			(xy 12.592962 -68.051556) (xy 12.611047 -67.923195) (xy 12.637077 -67.796207) (xy 12.670952 -67.671083)
			(xy 12.71254 -67.548307) (xy 12.761681 -67.428354) (xy 12.818184 -67.311689) (xy 12.881831 -67.198761)
			(xy 12.952375 -67.090009) (xy 13.029544 -66.985853) (xy 13.113039 -66.886696) (xy 13.202537 -66.792922)
			(xy 13.297692 -66.704893) (xy 13.398135 -66.62295) (xy 13.503478 -66.547411) (xy 13.613314 -66.478566)
			(xy 13.727218 -66.416683) (xy 13.844748 -66.362002) (xy 13.965451 -66.314732) (xy 14.088859 -66.275059)
			(xy 14.214495 -66.243134) (xy 14.341872 -66.219082) (xy 14.470498 -66.202995) (xy 14.599876 -66.194936)
			(xy 14.66469 -66.194432) (xy 14.729504 -66.194936) (xy 14.858882 -66.202995) (xy 14.987508 -66.219082)
			(xy 15.114885 -66.243134) (xy 15.240521 -66.275059) (xy 15.363929 -66.314732) (xy 15.484632 -66.362002)
			(xy 15.602162 -66.416683) (xy 15.716066 -66.478566) (xy 15.825902 -66.547411) (xy 15.931245 -66.62295)
			(xy 16.031688 -66.704893) (xy 16.126843 -66.792922) (xy 16.216341 -66.886696) (xy 16.299836 -66.985853)
			(xy 16.377005 -67.090009) (xy 16.447549 -67.198761) (xy 16.511196 -67.311689) (xy 16.567699 -67.428354)
			(xy 16.61684 -67.548307) (xy 16.658428 -67.671083) (xy 16.692303 -67.796207) (xy 16.718333 -67.923195)
			(xy 16.736418 -68.051556) (xy 16.746488 -68.180792) (xy 16.748504 -68.310405) (xy 16.742458 -68.439892)
			(xy 16.728374 -68.568753) (xy 16.706305 -68.696489) (xy 16.676338 -68.822606) (xy 16.638589 -68.946616)
			(xy 16.593202 -69.068039) (xy 16.540355 -69.186406) (xy 16.480251 -69.301258) (xy 16.413123 -69.412151)
			(xy 16.339231 -69.518657) (xy 16.25886 -69.620363) (xy 16.172322 -69.716875) (xy 16.07995 -69.80782)
			(xy 15.982104 -69.892847) (xy 15.879161 -69.971627) (xy 15.771519 -70.043854) (xy 15.659595 -70.109249)
			(xy 15.543822 -70.16756) (xy 15.424648 -70.21856) (xy 15.302534 -70.262052) (xy 15.177951 -70.297869)
			(xy 15.051384 -70.325871) (xy 14.92332 -70.34595) (xy 14.794256 -70.358029) (xy 14.66469 -70.36206)
			(xy 14.535124 -70.358029) (xy 14.40606 -70.34595) (xy 14.277996 -70.325871) (xy 14.151429 -70.297869)
			(xy 14.026846 -70.262052) (xy 13.904732 -70.21856) (xy 13.785558 -70.16756) (xy 13.669785 -70.109249)
			(xy 13.557861 -70.043854) (xy 13.450219 -69.971627) (xy 13.347276 -69.892847) (xy 13.24943 -69.80782)
			(xy 13.157058 -69.716875) (xy 13.07052 -69.620363) (xy 12.990149 -69.518657) (xy 12.916257 -69.412151)
			(xy 12.849129 -69.301258) (xy 12.789025 -69.186406) (xy 12.736178 -69.068039) (xy 12.690791 -68.946616)
			(xy 12.653042 -68.822606) (xy 12.623075 -68.696489) (xy 12.601006 -68.568753) (xy 12.586922 -68.439892)
			(xy 12.580876 -68.310405) (xy 10.174732 -68.310405) (xy 10.174732 -78.001368) (xy 10.175181 -78.024414)
			(xy 10.18345 -78.069756) (xy 10.199761 -78.112863) (xy 10.223578 -78.152323) (xy 10.25412 -78.186841)
			(xy 10.290386 -78.215286) (xy 10.331186 -78.236725) (xy 10.375184 -78.250455) (xy 10.420936 -78.256025)
			(xy 10.466943 -78.253255) (xy 10.511696 -78.242233) (xy 10.553728 -78.223322) (xy 10.591661 -78.197141)
			(xy 10.60831 -78.1812) (xy 17.264888 -71.524622) (xy 17.264888 -59.484006) (xy 17.26436 -59.467388)
			(xy 17.255756 -59.435285) (xy 17.239158 -59.406491) (xy 17.227804 -59.394344) (xy 13.740892 -55.907686)
			(xy 13.672312 -55.890668) (xy 13.63853 -55.901082) (xy 13.599405 -55.912674) (xy 13.519443 -55.92898)
			(xy 13.438263 -55.937322) (xy 13.356656 -55.937617) (xy 13.275418 -55.929864) (xy 13.19534 -55.914137)
			(xy 13.117203 -55.890591) (xy 13.041769 -55.859454) (xy 12.969773 -55.821031) (xy 12.901917 -55.775695)
			(xy 12.838863 -55.723889) (xy 12.781224 -55.666117) (xy 12.729563 -55.602944) (xy 12.684383 -55.534984)
			(xy 12.646126 -55.462899) (xy 12.615163 -55.387394) (xy 12.591796 -55.309203) (xy 12.576254 -55.22909)
			(xy 12.568688 -55.147834) (xy 12.569171 -55.066228) (xy 12.5777 -54.985067) (xy 12.594189 -54.905143)
			(xy 12.61848 -54.827235) (xy 12.650336 -54.752101) (xy 12.689444 -54.680475) (xy 12.735426 -54.613055)
			(xy 12.787831 -54.550498) (xy 12.84615 -54.493413) (xy 12.909814 -54.442357) (xy 12.978202 -54.397828)
			(xy 13.014198 -54.378606) (xy 13.03326 -54.36825) (xy 13.067837 -54.342055) (xy 13.097457 -54.310364)
			(xy 13.121258 -54.274098) (xy 13.138548 -54.234314) (xy 13.148823 -54.19217) (xy 13.151784 -54.148892)
			(xy 13.147345 -54.105741) (xy 13.135635 -54.063973) (xy 13.116994 -54.024804) (xy 13.091967 -53.989373)
			(xy 13.076936 -53.97373) (xy 12.470892 -53.367686) (xy 12.402312 -53.350668) (xy 12.36853 -53.361082)
			(xy 12.328815 -53.372829) (xy 12.247628 -53.389222) (xy 12.165208 -53.39741) (xy 12.082382 -53.397309)
			(xy 11.999982 -53.388921) (xy 11.918835 -53.37233) (xy 11.839756 -53.347702) (xy 11.763538 -53.315285)
			(xy 11.690945 -53.275404) (xy 11.622708 -53.22846) (xy 11.590782 -53.202078) (xy 11.573509 -53.188068)
			(xy 11.5351 -53.165657) (xy 11.493376 -53.150272) (xy 11.449612 -53.142382) (xy 11.405143 -53.142228)
			(xy 11.361325 -53.149815) (xy 11.319496 -53.164911) (xy 11.280933 -53.187056) (xy 11.246811 -53.215574)
			(xy 11.218173 -53.249594) (xy 11.195891 -53.288079) (xy 11.180647 -53.329855) (xy 11.172905 -53.373645)
			(xy 11.172444 -53.39588) (xy 11.172444 -54.269132) (xy 11.173067 -54.286382) (xy 11.182354 -54.319612)
			(xy 11.20019 -54.349147) (xy 11.225276 -54.372836) (xy 11.240262 -54.3814) (xy 11.275972 -54.400798)
			(xy 11.343773 -54.445609) (xy 11.406845 -54.496863) (xy 11.464579 -54.554063) (xy 11.516416 -54.616657)
			(xy 11.561855 -54.684039) (xy 11.600457 -54.755558) (xy 11.631848 -54.830522) (xy 11.655726 -54.908206)
			(xy 11.671859 -54.987861) (xy 11.68009 -55.068714) (xy 11.680342 -55.149985) (xy 11.672611 -55.230888)
			(xy 11.656971 -55.31064) (xy 11.633575 -55.388471) (xy 11.602648 -55.463628) (xy 11.56449 -55.535385)
			(xy 11.519468 -55.603047) (xy 11.46802 -55.66596) (xy 11.410641 -55.723516) (xy 11.347887 -55.775159)
			(xy 11.280365 -55.82039) (xy 11.208727 -55.85877) (xy 11.133666 -55.889929) (xy 11.055908 -55.913566)
			(xy 10.976204 -55.929453) (xy 10.895326 -55.937434) (xy 10.814054 -55.937434) (xy 10.733176 -55.929453)
			(xy 10.653472 -55.913566) (xy 10.575714 -55.889929) (xy 10.500653 -55.85877) (xy 10.429015 -55.82039)
			(xy 10.361493 -55.775159) (xy 10.298739 -55.723516) (xy 10.24136 -55.66596) (xy 10.189912 -55.603047)
			(xy 10.14489 -55.535385) (xy 10.106732 -55.463628) (xy 10.075805 -55.388471) (xy 10.052409 -55.31064)
			(xy 10.036769 -55.230888) (xy 10.029038 -55.149985) (xy 10.02929 -55.068714) (xy 10.037521 -54.987861)
			(xy 10.053654 -54.908206) (xy 10.077532 -54.830522) (xy 10.108923 -54.755558) (xy 10.147525 -54.684039)
			(xy 10.192964 -54.616657) (xy 10.244801 -54.554063) (xy 10.302535 -54.496863) (xy 10.365607 -54.445609)
			(xy 10.433408 -54.400798) (xy 10.469118 -54.3814) (xy 10.484134 -54.372869) (xy 10.509263 -54.3492)
			(xy 10.527111 -54.31965) (xy 10.536366 -54.286393) (xy 10.536936 -54.269132) (xy 10.536936 -52.02174)
			(xy 10.69213 -51.866546) (xy 10.708045 -51.849871) (xy 10.734234 -51.811946) (xy 10.753154 -51.769919)
			(xy 10.764182 -51.725168) (xy 10.766959 -51.679163) (xy 10.761391 -51.633411) (xy 10.747663 -51.589414)
			(xy 10.726224 -51.548615) (xy 10.697778 -51.512352) (xy 10.663258 -51.481814) (xy 10.623796 -51.458003)
			(xy 10.580686 -51.441701) (xy 10.535343 -51.433442) (xy 10.512298 -51.432968) (xy 8.633206 -51.432968)
			(xy 7.840472 -52.225702) (xy 7.823454 -52.294282) (xy 7.833868 -52.328064) (xy 7.845433 -52.367281)
			(xy 7.861733 -52.447406) (xy 7.870036 -52.52875) (xy 7.870261 -52.610516) (xy 7.862405 -52.691904)
			(xy 7.846545 -52.772117) (xy 7.822836 -52.850371) (xy 7.791511 -52.925899) (xy 7.752876 -52.997962)
			(xy 7.707309 -53.065854) (xy 7.655257 -53.128912) (xy 7.597228 -53.186517) (xy 7.533791 -53.238107)
			(xy 7.465567 -53.283176) (xy 7.393223 -53.321282) (xy 7.317468 -53.352054) (xy 7.239043 -53.375189)
			(xy 7.158716 -53.390461) (xy 7.077272 -53.397721) (xy 6.99551 -53.396898) (xy 6.914229 -53.388) (xy 6.834226 -53.371114)
			(xy 6.756282 -53.346405) (xy 6.681162 -53.314114) (xy 6.6096 -53.274559) (xy 6.542297 -53.228126)
			(xy 6.510782 -53.202078) (xy 6.493524 -53.188051) (xy 6.455112 -53.165646) (xy 6.413387 -53.150265)
			(xy 6.369622 -53.14238) (xy 6.325153 -53.14223) (xy 6.281336 -53.149819) (xy 6.239508 -53.164917)
			(xy 6.200945 -53.187062) (xy 6.166823 -53.215579) (xy 6.138184 -53.249599) (xy 6.115901 -53.288082)
			(xy 6.100654 -53.329856) (xy 6.092908 -53.373645) (xy 6.092444 -53.39588) (xy 6.092444 -54.269132)
			(xy 6.093067 -54.286382) (xy 6.102354 -54.319612) (xy 6.12019 -54.349147) (xy 6.145276 -54.372836)
			(xy 6.160262 -54.3814) (xy 6.195972 -54.400798) (xy 6.263773 -54.445609) (xy 6.326845 -54.496863)
			(xy 6.384579 -54.554063) (xy 6.436416 -54.616657) (xy 6.481855 -54.684039) (xy 6.520457 -54.755558)
			(xy 6.551848 -54.830522) (xy 6.575726 -54.908206) (xy 6.591859 -54.987861) (xy 6.60009 -55.068714)
			(xy 6.600342 -55.149985) (xy 6.592611 -55.230888) (xy 6.576971 -55.31064) (xy 6.553575 -55.388471)
			(xy 6.522648 -55.463628) (xy 6.48449 -55.535385) (xy 6.439468 -55.603047) (xy 6.38802 -55.66596)
			(xy 6.330641 -55.723516) (xy 6.267887 -55.775159) (xy 6.200365 -55.82039) (xy 6.128727 -55.85877)
			(xy 6.053666 -55.889929) (xy 5.975908 -55.913566) (xy 5.896204 -55.929453) (xy 5.815326 -55.937434)
			(xy 5.734054 -55.937434) (xy 5.653176 -55.929453) (xy 5.573472 -55.913566) (xy 5.495714 -55.889929)
			(xy 5.420653 -55.85877) (xy 5.349015 -55.82039) (xy 5.281493 -55.775159) (xy 5.218739 -55.723516)
			(xy 5.16136 -55.66596) (xy 5.109912 -55.603047) (xy 5.06489 -55.535385) (xy 5.026732 -55.463628)
			(xy 4.995805 -55.388471) (xy 4.972409 -55.31064) (xy 4.956769 -55.230888) (xy 4.949038 -55.149985)
			(xy 4.94929 -55.068714) (xy 4.957521 -54.987861) (xy 4.973654 -54.908206) (xy 4.997532 -54.830522)
			(xy 5.028923 -54.755558) (xy 5.067525 -54.684039) (xy 5.112964 -54.616657) (xy 5.164801 -54.554063)
			(xy 5.222535 -54.496863) (xy 5.285607 -54.445609) (xy 5.353408 -54.400798) (xy 5.389118 -54.3814)
			(xy 5.404134 -54.372869) (xy 5.429263 -54.3492) (xy 5.447111 -54.31965) (xy 5.456366 -54.286393)
			(xy 5.456936 -54.269132) (xy 5.456936 -53.39588) (xy 5.456462 -53.373642) (xy 5.448733 -53.329842)
			(xy 5.433499 -53.288056) (xy 5.411223 -53.249561) (xy 5.382587 -53.21553) (xy 5.348463 -53.187004)
			(xy 5.309895 -53.164853) (xy 5.268061 -53.149754) (xy 5.224236 -53.142168) (xy 5.17976 -53.142326)
			(xy 5.135991 -53.150224) (xy 5.094264 -53.16562) (xy 5.055855 -53.188045) (xy 5.038598 -53.202078)
			(xy 5.007183 -53.228052) (xy 4.940099 -53.274363) (xy 4.868779 -53.313841) (xy 4.793916 -53.346101)
			(xy 4.71624 -53.370829) (xy 4.636506 -53.387785) (xy 4.555489 -53.396803) (xy 4.473977 -53.397797)
			(xy 4.392765 -53.390756) (xy 4.312641 -53.375749) (xy 4.234385 -53.352922) (xy 4.158758 -53.322497)
			(xy 4.086496 -53.28477) (xy 4.018303 -53.240108) (xy 3.954841 -53.188945) (xy 3.896727 -53.131779)
			(xy 3.844528 -53.069166) (xy 3.798751 -53.001716) (xy 3.759841 -52.930085) (xy 3.728177 -52.854968)
			(xy 3.704066 -52.777098) (xy 3.687744 -52.697232) (xy 3.679369 -52.616146) (xy 3.679023 -52.534629)
			(xy 3.686708 -52.453475) (xy 3.702351 -52.373472) (xy 3.725799 -52.2954) (xy 3.756824 -52.220018)
			(xy 3.795124 -52.148058) (xy 3.840326 -52.080221) (xy 3.891991 -52.017167) (xy 3.949617 -51.95951)
			(xy 4.012642 -51.90781) (xy 4.080453 -51.862569) (xy 4.152392 -51.82423) (xy 4.227757 -51.793163)
			(xy 4.305816 -51.769672) (xy 4.38581 -51.753984) (xy 4.46696 -51.746254) (xy 4.548477 -51.746555)
			(xy 4.629567 -51.754884) (xy 4.709443 -51.771162) (xy 4.74853 -51.782726) (xy 4.782312 -51.79314)
			(xy 4.850892 -51.776122) (xy 6.541262 -50.085752) (xy 13.124434 -50.085752) (xy 14.369676 -51.331042)
			(xy 39.818314 -51.331042) (xy 39.824323 -51.215104) (xy 39.838316 -51.099857) (xy 39.860227 -50.985851)
			(xy 39.889952 -50.873627) (xy 39.927348 -50.763721) (xy 39.972237 -50.656658) (xy 40.024406 -50.552946)
			(xy 40.083606 -50.453081) (xy 40.149555 -50.357538) (xy 40.221938 -50.266772) (xy 40.300411 -50.181217)
			(xy 40.384599 -50.101279) (xy 40.474101 -50.02734) (xy 40.568492 -49.959752) (xy 40.66732 -49.898838)
			(xy 40.770116 -49.844886) (xy 40.876389 -49.798156) (xy 40.985633 -49.758868) (xy 41.097326 -49.727211)
			(xy 41.210938 -49.703335) (xy 41.325926 -49.687354) (xy 41.441743 -49.679345) (xy 41.49979 -49.678844)
			(xy 41.557837 -49.679345) (xy 41.673654 -49.687354) (xy 41.788642 -49.703335) (xy 41.902254 -49.727211)
			(xy 42.013947 -49.758868) (xy 42.123191 -49.798156) (xy 42.229464 -49.844886) (xy 42.33226 -49.898838)
			(xy 42.431088 -49.959752) (xy 42.474869 -49.991101) (xy 63.647829 -49.991101) (xy 63.653878 -49.915531)
			(xy 63.667925 -49.841033) (xy 63.689811 -49.76845) (xy 63.719288 -49.698604) (xy 63.756023 -49.632287)
			(xy 63.799598 -49.570251) (xy 63.84952 -49.513198) (xy 63.905224 -49.461774) (xy 63.966079 -49.416563)
			(xy 64.031394 -49.378076) (xy 64.10043 -49.34675) (xy 64.172405 -49.32294) (xy 64.246503 -49.306915)
			(xy 64.321884 -49.298856) (xy 64.35979 -49.298352) (xy 64.397696 -49.298856) (xy 64.473077 -49.306915)
			(xy 64.547175 -49.32294) (xy 64.61915 -49.34675) (xy 64.688186 -49.378076) (xy 64.753501 -49.416563)
			(xy 64.814356 -49.461774) (xy 64.87006 -49.513198) (xy 64.919982 -49.570251) (xy 64.963557 -49.632287)
			(xy 65.000292 -49.698604) (xy 65.029769 -49.76845) (xy 65.051655 -49.841033) (xy 65.065702 -49.915531)
			(xy 65.071751 -49.991101) (xy 66.187829 -49.991101) (xy 66.193878 -49.915531) (xy 66.207925 -49.841033)
			(xy 66.229811 -49.76845) (xy 66.259288 -49.698604) (xy 66.296023 -49.632287) (xy 66.339598 -49.570251)
			(xy 66.38952 -49.513198) (xy 66.445224 -49.461774) (xy 66.506079 -49.416563) (xy 66.571394 -49.378076)
			(xy 66.64043 -49.34675) (xy 66.712405 -49.32294) (xy 66.786503 -49.306915) (xy 66.861884 -49.298856)
			(xy 66.89979 -49.298352) (xy 66.937696 -49.298856) (xy 67.013077 -49.306915) (xy 67.087175 -49.32294)
			(xy 67.15915 -49.34675) (xy 67.228186 -49.378076) (xy 67.293501 -49.416563) (xy 67.354356 -49.461774)
			(xy 67.41006 -49.513198) (xy 67.459982 -49.570251) (xy 67.503557 -49.632287) (xy 67.540292 -49.698604)
			(xy 67.569769 -49.76845) (xy 67.591655 -49.841033) (xy 67.605702 -49.915531) (xy 67.611751 -49.991101)
			(xy 68.727829 -49.991101) (xy 68.733878 -49.915531) (xy 68.747925 -49.841033) (xy 68.769811 -49.76845)
			(xy 68.799288 -49.698604) (xy 68.836023 -49.632287) (xy 68.879598 -49.570251) (xy 68.92952 -49.513198)
			(xy 68.985224 -49.461774) (xy 69.046079 -49.416563) (xy 69.111394 -49.378076) (xy 69.18043 -49.34675)
			(xy 69.252405 -49.32294) (xy 69.326503 -49.306915) (xy 69.401884 -49.298856) (xy 69.43979 -49.298352)
			(xy 69.477696 -49.298856) (xy 69.553077 -49.306915) (xy 69.627175 -49.32294) (xy 69.69915 -49.34675)
			(xy 69.768186 -49.378076) (xy 69.833501 -49.416563) (xy 69.894356 -49.461774) (xy 69.95006 -49.513198)
			(xy 69.999982 -49.570251) (xy 70.043557 -49.632287) (xy 70.080292 -49.698604) (xy 70.109769 -49.76845)
			(xy 70.131655 -49.841033) (xy 70.145702 -49.915531) (xy 70.151751 -49.991101) (xy 71.267829 -49.991101)
			(xy 71.273878 -49.915531) (xy 71.287925 -49.841033) (xy 71.309811 -49.76845) (xy 71.339288 -49.698604)
			(xy 71.376023 -49.632287) (xy 71.419598 -49.570251) (xy 71.46952 -49.513198) (xy 71.525224 -49.461774)
			(xy 71.586079 -49.416563) (xy 71.651394 -49.378076) (xy 71.72043 -49.34675) (xy 71.792405 -49.32294)
			(xy 71.866503 -49.306915) (xy 71.941884 -49.298856) (xy 71.97979 -49.298352) (xy 72.017696 -49.298856)
			(xy 72.093077 -49.306915) (xy 72.167175 -49.32294) (xy 72.23915 -49.34675) (xy 72.308186 -49.378076)
			(xy 72.373501 -49.416563) (xy 72.434356 -49.461774) (xy 72.49006 -49.513198) (xy 72.539982 -49.570251)
			(xy 72.583557 -49.632287) (xy 72.620292 -49.698604) (xy 72.649769 -49.76845) (xy 72.671655 -49.841033)
			(xy 72.685702 -49.915531) (xy 72.691751 -49.991101) (xy 73.807829 -49.991101) (xy 73.813878 -49.915531)
			(xy 73.827925 -49.841033) (xy 73.849811 -49.76845) (xy 73.879288 -49.698604) (xy 73.916023 -49.632287)
			(xy 73.959598 -49.570251) (xy 74.00952 -49.513198) (xy 74.065224 -49.461774) (xy 74.126079 -49.416563)
			(xy 74.191394 -49.378076) (xy 74.26043 -49.34675) (xy 74.332405 -49.32294) (xy 74.406503 -49.306915)
			(xy 74.481884 -49.298856) (xy 74.51979 -49.298352) (xy 74.557696 -49.298856) (xy 74.633077 -49.306915)
			(xy 74.707175 -49.32294) (xy 74.77915 -49.34675) (xy 74.848186 -49.378076) (xy 74.913501 -49.416563)
			(xy 74.974356 -49.461774) (xy 75.03006 -49.513198) (xy 75.079982 -49.570251) (xy 75.123557 -49.632287)
			(xy 75.160292 -49.698604) (xy 75.189769 -49.76845) (xy 75.211655 -49.841033) (xy 75.225702 -49.915531)
			(xy 75.231751 -49.991101) (xy 76.347829 -49.991101) (xy 76.353878 -49.915531) (xy 76.367925 -49.841033)
			(xy 76.389811 -49.76845) (xy 76.419288 -49.698604) (xy 76.456023 -49.632287) (xy 76.499598 -49.570251)
			(xy 76.54952 -49.513198) (xy 76.605224 -49.461774) (xy 76.666079 -49.416563) (xy 76.731394 -49.378076)
			(xy 76.80043 -49.34675) (xy 76.872405 -49.32294) (xy 76.946503 -49.306915) (xy 77.021884 -49.298856)
			(xy 77.05979 -49.298352) (xy 77.097696 -49.298856) (xy 77.173077 -49.306915) (xy 77.247175 -49.32294)
			(xy 77.31915 -49.34675) (xy 77.388186 -49.378076) (xy 77.453501 -49.416563) (xy 77.514356 -49.461774)
			(xy 77.57006 -49.513198) (xy 77.619982 -49.570251) (xy 77.663557 -49.632287) (xy 77.700292 -49.698604)
			(xy 77.729769 -49.76845) (xy 77.751655 -49.841033) (xy 77.765702 -49.915531) (xy 77.771751 -49.991101)
			(xy 78.887829 -49.991101) (xy 78.893878 -49.915531) (xy 78.907925 -49.841033) (xy 78.929811 -49.76845)
			(xy 78.959288 -49.698604) (xy 78.996023 -49.632287) (xy 79.039598 -49.570251) (xy 79.08952 -49.513198)
			(xy 79.145224 -49.461774) (xy 79.206079 -49.416563) (xy 79.271394 -49.378076) (xy 79.34043 -49.34675)
			(xy 79.412405 -49.32294) (xy 79.486503 -49.306915) (xy 79.561884 -49.298856) (xy 79.59979 -49.298352)
			(xy 79.637696 -49.298856) (xy 79.713077 -49.306915) (xy 79.787175 -49.32294) (xy 79.85915 -49.34675)
			(xy 79.928186 -49.378076) (xy 79.993501 -49.416563) (xy 80.054356 -49.461774) (xy 80.11006 -49.513198)
			(xy 80.159982 -49.570251) (xy 80.203557 -49.632287) (xy 80.240292 -49.698604) (xy 80.269769 -49.76845)
			(xy 80.291655 -49.841033) (xy 80.305702 -49.915531) (xy 80.311751 -49.991101) (xy 81.427829 -49.991101)
			(xy 81.433878 -49.915531) (xy 81.447925 -49.841033) (xy 81.469811 -49.76845) (xy 81.499288 -49.698604)
			(xy 81.536023 -49.632287) (xy 81.579598 -49.570251) (xy 81.62952 -49.513198) (xy 81.685224 -49.461774)
			(xy 81.746079 -49.416563) (xy 81.811394 -49.378076) (xy 81.88043 -49.34675) (xy 81.952405 -49.32294)
			(xy 82.026503 -49.306915) (xy 82.101884 -49.298856) (xy 82.13979 -49.298352) (xy 82.177696 -49.298856)
			(xy 82.253077 -49.306915) (xy 82.327175 -49.32294) (xy 82.39915 -49.34675) (xy 82.468186 -49.378076)
			(xy 82.533501 -49.416563) (xy 82.594356 -49.461774) (xy 82.65006 -49.513198) (xy 82.699982 -49.570251)
			(xy 82.743557 -49.632287) (xy 82.780292 -49.698604) (xy 82.809769 -49.76845) (xy 82.831655 -49.841033)
			(xy 82.845702 -49.915531) (xy 82.851751 -49.991101) (xy 82.849732 -50.066885) (xy 82.83967 -50.142025)
			(xy 82.821678 -50.21567) (xy 82.79596 -50.286986) (xy 82.762808 -50.355163) (xy 82.722596 -50.419431)
			(xy 82.675781 -50.47906) (xy 82.622893 -50.533376) (xy 82.564531 -50.581762) (xy 82.501356 -50.62367)
			(xy 82.434085 -50.658626) (xy 82.36348 -50.686233) (xy 82.290339 -50.706179) (xy 82.215494 -50.718238)
			(xy 82.13979 -50.722273) (xy 82.064086 -50.718238) (xy 81.989241 -50.706179) (xy 81.9161 -50.686233)
			(xy 81.845495 -50.658626) (xy 81.778224 -50.62367) (xy 81.715049 -50.581762) (xy 81.656687 -50.533376)
			(xy 81.603799 -50.47906) (xy 81.556984 -50.419431) (xy 81.516772 -50.355163) (xy 81.48362 -50.286986)
			(xy 81.457902 -50.21567) (xy 81.43991 -50.142025) (xy 81.429848 -50.066885) (xy 81.427829 -49.991101)
			(xy 80.311751 -49.991101) (xy 80.309732 -50.066885) (xy 80.29967 -50.142025) (xy 80.281678 -50.21567)
			(xy 80.25596 -50.286986) (xy 80.222808 -50.355163) (xy 80.182596 -50.419431) (xy 80.135781 -50.47906)
			(xy 80.082893 -50.533376) (xy 80.024531 -50.581762) (xy 79.961356 -50.62367) (xy 79.894085 -50.658626)
			(xy 79.82348 -50.686233) (xy 79.750339 -50.706179) (xy 79.675494 -50.718238) (xy 79.59979 -50.722273)
			(xy 79.524086 -50.718238) (xy 79.449241 -50.706179) (xy 79.3761 -50.686233) (xy 79.305495 -50.658626)
			(xy 79.238224 -50.62367) (xy 79.175049 -50.581762) (xy 79.116687 -50.533376) (xy 79.063799 -50.47906)
			(xy 79.016984 -50.419431) (xy 78.976772 -50.355163) (xy 78.94362 -50.286986) (xy 78.917902 -50.21567)
			(xy 78.89991 -50.142025) (xy 78.889848 -50.066885) (xy 78.887829 -49.991101) (xy 77.771751 -49.991101)
			(xy 77.769732 -50.066885) (xy 77.75967 -50.142025) (xy 77.741678 -50.21567) (xy 77.71596 -50.286986)
			(xy 77.682808 -50.355163) (xy 77.642596 -50.419431) (xy 77.595781 -50.47906) (xy 77.542893 -50.533376)
			(xy 77.484531 -50.581762) (xy 77.421356 -50.62367) (xy 77.354085 -50.658626) (xy 77.28348 -50.686233)
			(xy 77.210339 -50.706179) (xy 77.135494 -50.718238) (xy 77.05979 -50.722273) (xy 76.984086 -50.718238)
			(xy 76.909241 -50.706179) (xy 76.8361 -50.686233) (xy 76.765495 -50.658626) (xy 76.698224 -50.62367)
			(xy 76.635049 -50.581762) (xy 76.576687 -50.533376) (xy 76.523799 -50.47906) (xy 76.476984 -50.419431)
			(xy 76.436772 -50.355163) (xy 76.40362 -50.286986) (xy 76.377902 -50.21567) (xy 76.35991 -50.142025)
			(xy 76.349848 -50.066885) (xy 76.347829 -49.991101) (xy 75.231751 -49.991101) (xy 75.229732 -50.066885)
			(xy 75.21967 -50.142025) (xy 75.201678 -50.21567) (xy 75.17596 -50.286986) (xy 75.142808 -50.355163)
			(xy 75.102596 -50.419431) (xy 75.055781 -50.47906) (xy 75.002893 -50.533376) (xy 74.944531 -50.581762)
			(xy 74.881356 -50.62367) (xy 74.814085 -50.658626) (xy 74.74348 -50.686233) (xy 74.670339 -50.706179)
			(xy 74.595494 -50.718238) (xy 74.51979 -50.722273) (xy 74.444086 -50.718238) (xy 74.369241 -50.706179)
			(xy 74.2961 -50.686233) (xy 74.225495 -50.658626) (xy 74.158224 -50.62367) (xy 74.095049 -50.581762)
			(xy 74.036687 -50.533376) (xy 73.983799 -50.47906) (xy 73.936984 -50.419431) (xy 73.896772 -50.355163)
			(xy 73.86362 -50.286986) (xy 73.837902 -50.21567) (xy 73.81991 -50.142025) (xy 73.809848 -50.066885)
			(xy 73.807829 -49.991101) (xy 72.691751 -49.991101) (xy 72.689732 -50.066885) (xy 72.67967 -50.142025)
			(xy 72.661678 -50.21567) (xy 72.63596 -50.286986) (xy 72.602808 -50.355163) (xy 72.562596 -50.419431)
			(xy 72.515781 -50.47906) (xy 72.462893 -50.533376) (xy 72.404531 -50.581762) (xy 72.341356 -50.62367)
			(xy 72.274085 -50.658626) (xy 72.20348 -50.686233) (xy 72.130339 -50.706179) (xy 72.055494 -50.718238)
			(xy 71.97979 -50.722273) (xy 71.904086 -50.718238) (xy 71.829241 -50.706179) (xy 71.7561 -50.686233)
			(xy 71.685495 -50.658626) (xy 71.618224 -50.62367) (xy 71.555049 -50.581762) (xy 71.496687 -50.533376)
			(xy 71.443799 -50.47906) (xy 71.396984 -50.419431) (xy 71.356772 -50.355163) (xy 71.32362 -50.286986)
			(xy 71.297902 -50.21567) (xy 71.27991 -50.142025) (xy 71.269848 -50.066885) (xy 71.267829 -49.991101)
			(xy 70.151751 -49.991101) (xy 70.149732 -50.066885) (xy 70.13967 -50.142025) (xy 70.121678 -50.21567)
			(xy 70.09596 -50.286986) (xy 70.062808 -50.355163) (xy 70.022596 -50.419431) (xy 69.975781 -50.47906)
			(xy 69.922893 -50.533376) (xy 69.864531 -50.581762) (xy 69.801356 -50.62367) (xy 69.734085 -50.658626)
			(xy 69.66348 -50.686233) (xy 69.590339 -50.706179) (xy 69.515494 -50.718238) (xy 69.43979 -50.722273)
			(xy 69.364086 -50.718238) (xy 69.289241 -50.706179) (xy 69.2161 -50.686233) (xy 69.145495 -50.658626)
			(xy 69.078224 -50.62367) (xy 69.015049 -50.581762) (xy 68.956687 -50.533376) (xy 68.903799 -50.47906)
			(xy 68.856984 -50.419431) (xy 68.816772 -50.355163) (xy 68.78362 -50.286986) (xy 68.757902 -50.21567)
			(xy 68.73991 -50.142025) (xy 68.729848 -50.066885) (xy 68.727829 -49.991101) (xy 67.611751 -49.991101)
			(xy 67.609732 -50.066885) (xy 67.59967 -50.142025) (xy 67.581678 -50.21567) (xy 67.55596 -50.286986)
			(xy 67.522808 -50.355163) (xy 67.482596 -50.419431) (xy 67.435781 -50.47906) (xy 67.382893 -50.533376)
			(xy 67.324531 -50.581762) (xy 67.261356 -50.62367) (xy 67.194085 -50.658626) (xy 67.12348 -50.686233)
			(xy 67.050339 -50.706179) (xy 66.975494 -50.718238) (xy 66.89979 -50.722273) (xy 66.824086 -50.718238)
			(xy 66.749241 -50.706179) (xy 66.6761 -50.686233) (xy 66.605495 -50.658626) (xy 66.538224 -50.62367)
			(xy 66.475049 -50.581762) (xy 66.416687 -50.533376) (xy 66.363799 -50.47906) (xy 66.316984 -50.419431)
			(xy 66.276772 -50.355163) (xy 66.24362 -50.286986) (xy 66.217902 -50.21567) (xy 66.19991 -50.142025)
			(xy 66.189848 -50.066885) (xy 66.187829 -49.991101) (xy 65.071751 -49.991101) (xy 65.069732 -50.066885)
			(xy 65.05967 -50.142025) (xy 65.041678 -50.21567) (xy 65.01596 -50.286986) (xy 64.982808 -50.355163)
			(xy 64.942596 -50.419431) (xy 64.895781 -50.47906) (xy 64.842893 -50.533376) (xy 64.784531 -50.581762)
			(xy 64.721356 -50.62367) (xy 64.654085 -50.658626) (xy 64.58348 -50.686233) (xy 64.510339 -50.706179)
			(xy 64.435494 -50.718238) (xy 64.35979 -50.722273) (xy 64.284086 -50.718238) (xy 64.209241 -50.706179)
			(xy 64.1361 -50.686233) (xy 64.065495 -50.658626) (xy 63.998224 -50.62367) (xy 63.935049 -50.581762)
			(xy 63.876687 -50.533376) (xy 63.823799 -50.47906) (xy 63.776984 -50.419431) (xy 63.736772 -50.355163)
			(xy 63.70362 -50.286986) (xy 63.677902 -50.21567) (xy 63.65991 -50.142025) (xy 63.649848 -50.066885)
			(xy 63.647829 -49.991101) (xy 42.474869 -49.991101) (xy 42.525479 -50.02734) (xy 42.614981 -50.101279)
			(xy 42.699169 -50.181217) (xy 42.777642 -50.266772) (xy 42.850025 -50.357538) (xy 42.915974 -50.453081)
			(xy 42.975174 -50.552946) (xy 43.027343 -50.656658) (xy 43.072232 -50.763721) (xy 43.109628 -50.873627)
			(xy 43.139353 -50.985851) (xy 43.161264 -51.099857) (xy 43.175257 -51.215104) (xy 43.181266 -51.331042)
			(xy 43.179263 -51.447118) (xy 43.169255 -51.56278) (xy 43.151292 -51.677475) (xy 43.125459 -51.790658)
			(xy 43.091879 -51.901789) (xy 43.050711 -52.010338) (xy 43.002153 -52.115788) (xy 42.946436 -52.217637)
			(xy 42.883824 -52.3154) (xy 42.814617 -52.40861) (xy 42.739144 -52.496823) (xy 42.657765 -52.579619)
			(xy 42.570868 -52.656603) (xy 42.526017 -52.691121) (xy 63.647829 -52.691121) (xy 63.653878 -52.615551)
			(xy 63.667925 -52.541053) (xy 63.689811 -52.46847) (xy 63.719288 -52.398624) (xy 63.756023 -52.332307)
			(xy 63.799598 -52.270271) (xy 63.84952 -52.213218) (xy 63.905224 -52.161794) (xy 63.966079 -52.116583)
			(xy 64.031394 -52.078096) (xy 64.10043 -52.04677) (xy 64.172405 -52.02296) (xy 64.246503 -52.006935)
			(xy 64.321884 -51.998876) (xy 64.35979 -51.998372) (xy 64.397696 -51.998876) (xy 64.473077 -52.006935)
			(xy 64.547175 -52.02296) (xy 64.61915 -52.04677) (xy 64.688186 -52.078096) (xy 64.753501 -52.116583)
			(xy 64.814356 -52.161794) (xy 64.87006 -52.213218) (xy 64.919982 -52.270271) (xy 64.963557 -52.332307)
			(xy 65.000292 -52.398624) (xy 65.029769 -52.46847) (xy 65.051655 -52.541053) (xy 65.065702 -52.615551)
			(xy 65.071751 -52.691121) (xy 66.187829 -52.691121) (xy 66.193878 -52.615551) (xy 66.207925 -52.541053)
			(xy 66.229811 -52.46847) (xy 66.259288 -52.398624) (xy 66.296023 -52.332307) (xy 66.339598 -52.270271)
			(xy 66.38952 -52.213218) (xy 66.445224 -52.161794) (xy 66.506079 -52.116583) (xy 66.571394 -52.078096)
			(xy 66.64043 -52.04677) (xy 66.712405 -52.02296) (xy 66.786503 -52.006935) (xy 66.861884 -51.998876)
			(xy 66.89979 -51.998372) (xy 66.937696 -51.998876) (xy 67.013077 -52.006935) (xy 67.087175 -52.02296)
			(xy 67.15915 -52.04677) (xy 67.228186 -52.078096) (xy 67.293501 -52.116583) (xy 67.354356 -52.161794)
			(xy 67.41006 -52.213218) (xy 67.459982 -52.270271) (xy 67.503557 -52.332307) (xy 67.540292 -52.398624)
			(xy 67.569769 -52.46847) (xy 67.591655 -52.541053) (xy 67.605702 -52.615551) (xy 67.611751 -52.691121)
			(xy 68.727829 -52.691121) (xy 68.733878 -52.615551) (xy 68.747925 -52.541053) (xy 68.769811 -52.46847)
			(xy 68.799288 -52.398624) (xy 68.836023 -52.332307) (xy 68.879598 -52.270271) (xy 68.92952 -52.213218)
			(xy 68.985224 -52.161794) (xy 69.046079 -52.116583) (xy 69.111394 -52.078096) (xy 69.18043 -52.04677)
			(xy 69.252405 -52.02296) (xy 69.326503 -52.006935) (xy 69.401884 -51.998876) (xy 69.43979 -51.998372)
			(xy 69.477696 -51.998876) (xy 69.553077 -52.006935) (xy 69.627175 -52.02296) (xy 69.69915 -52.04677)
			(xy 69.768186 -52.078096) (xy 69.833501 -52.116583) (xy 69.894356 -52.161794) (xy 69.95006 -52.213218)
			(xy 69.999982 -52.270271) (xy 70.043557 -52.332307) (xy 70.080292 -52.398624) (xy 70.109769 -52.46847)
			(xy 70.131655 -52.541053) (xy 70.145702 -52.615551) (xy 70.151751 -52.691121) (xy 71.267829 -52.691121)
			(xy 71.273878 -52.615551) (xy 71.287925 -52.541053) (xy 71.309811 -52.46847) (xy 71.339288 -52.398624)
			(xy 71.376023 -52.332307) (xy 71.419598 -52.270271) (xy 71.46952 -52.213218) (xy 71.525224 -52.161794)
			(xy 71.586079 -52.116583) (xy 71.651394 -52.078096) (xy 71.72043 -52.04677) (xy 71.792405 -52.02296)
			(xy 71.866503 -52.006935) (xy 71.941884 -51.998876) (xy 71.97979 -51.998372) (xy 72.017696 -51.998876)
			(xy 72.093077 -52.006935) (xy 72.167175 -52.02296) (xy 72.23915 -52.04677) (xy 72.308186 -52.078096)
			(xy 72.373501 -52.116583) (xy 72.434356 -52.161794) (xy 72.49006 -52.213218) (xy 72.539982 -52.270271)
			(xy 72.583557 -52.332307) (xy 72.620292 -52.398624) (xy 72.649769 -52.46847) (xy 72.671655 -52.541053)
			(xy 72.685702 -52.615551) (xy 72.691751 -52.691121) (xy 73.807829 -52.691121) (xy 73.813878 -52.615551)
			(xy 73.827925 -52.541053) (xy 73.849811 -52.46847) (xy 73.879288 -52.398624) (xy 73.916023 -52.332307)
			(xy 73.959598 -52.270271) (xy 74.00952 -52.213218) (xy 74.065224 -52.161794) (xy 74.126079 -52.116583)
			(xy 74.191394 -52.078096) (xy 74.26043 -52.04677) (xy 74.332405 -52.02296) (xy 74.406503 -52.006935)
			(xy 74.481884 -51.998876) (xy 74.51979 -51.998372) (xy 74.557696 -51.998876) (xy 74.633077 -52.006935)
			(xy 74.707175 -52.02296) (xy 74.77915 -52.04677) (xy 74.848186 -52.078096) (xy 74.913501 -52.116583)
			(xy 74.974356 -52.161794) (xy 75.03006 -52.213218) (xy 75.079982 -52.270271) (xy 75.123557 -52.332307)
			(xy 75.160292 -52.398624) (xy 75.189769 -52.46847) (xy 75.211655 -52.541053) (xy 75.225702 -52.615551)
			(xy 75.231751 -52.691121) (xy 76.347829 -52.691121) (xy 76.353878 -52.615551) (xy 76.367925 -52.541053)
			(xy 76.389811 -52.46847) (xy 76.419288 -52.398624) (xy 76.456023 -52.332307) (xy 76.499598 -52.270271)
			(xy 76.54952 -52.213218) (xy 76.605224 -52.161794) (xy 76.666079 -52.116583) (xy 76.731394 -52.078096)
			(xy 76.80043 -52.04677) (xy 76.872405 -52.02296) (xy 76.946503 -52.006935) (xy 77.021884 -51.998876)
			(xy 77.05979 -51.998372) (xy 77.097696 -51.998876) (xy 77.173077 -52.006935) (xy 77.247175 -52.02296)
			(xy 77.31915 -52.04677) (xy 77.388186 -52.078096) (xy 77.453501 -52.116583) (xy 77.514356 -52.161794)
			(xy 77.57006 -52.213218) (xy 77.619982 -52.270271) (xy 77.663557 -52.332307) (xy 77.700292 -52.398624)
			(xy 77.729769 -52.46847) (xy 77.751655 -52.541053) (xy 77.765702 -52.615551) (xy 77.771751 -52.691121)
			(xy 78.887829 -52.691121) (xy 78.893878 -52.615551) (xy 78.907925 -52.541053) (xy 78.929811 -52.46847)
			(xy 78.959288 -52.398624) (xy 78.996023 -52.332307) (xy 79.039598 -52.270271) (xy 79.08952 -52.213218)
			(xy 79.145224 -52.161794) (xy 79.206079 -52.116583) (xy 79.271394 -52.078096) (xy 79.34043 -52.04677)
			(xy 79.412405 -52.02296) (xy 79.486503 -52.006935) (xy 79.561884 -51.998876) (xy 79.59979 -51.998372)
			(xy 79.637696 -51.998876) (xy 79.713077 -52.006935) (xy 79.787175 -52.02296) (xy 79.85915 -52.04677)
			(xy 79.928186 -52.078096) (xy 79.993501 -52.116583) (xy 80.054356 -52.161794) (xy 80.11006 -52.213218)
			(xy 80.159982 -52.270271) (xy 80.203557 -52.332307) (xy 80.240292 -52.398624) (xy 80.269769 -52.46847)
			(xy 80.291655 -52.541053) (xy 80.305702 -52.615551) (xy 80.311751 -52.691121) (xy 81.427829 -52.691121)
			(xy 81.433878 -52.615551) (xy 81.447925 -52.541053) (xy 81.469811 -52.46847) (xy 81.499288 -52.398624)
			(xy 81.536023 -52.332307) (xy 81.579598 -52.270271) (xy 81.62952 -52.213218) (xy 81.685224 -52.161794)
			(xy 81.746079 -52.116583) (xy 81.811394 -52.078096) (xy 81.88043 -52.04677) (xy 81.952405 -52.02296)
			(xy 82.026503 -52.006935) (xy 82.101884 -51.998876) (xy 82.13979 -51.998372) (xy 82.177696 -51.998876)
			(xy 82.253077 -52.006935) (xy 82.327175 -52.02296) (xy 82.39915 -52.04677) (xy 82.468186 -52.078096)
			(xy 82.533501 -52.116583) (xy 82.594356 -52.161794) (xy 82.65006 -52.213218) (xy 82.699982 -52.270271)
			(xy 82.743557 -52.332307) (xy 82.780292 -52.398624) (xy 82.809769 -52.46847) (xy 82.831655 -52.541053)
			(xy 82.845702 -52.615551) (xy 82.851751 -52.691121) (xy 82.849732 -52.766905) (xy 82.83967 -52.842045)
			(xy 82.821678 -52.91569) (xy 82.79596 -52.987006) (xy 82.762808 -53.055183) (xy 82.722596 -53.119451)
			(xy 82.675781 -53.17908) (xy 82.622893 -53.233396) (xy 82.564531 -53.281782) (xy 82.501356 -53.32369)
			(xy 82.434085 -53.358646) (xy 82.36348 -53.386253) (xy 82.290339 -53.406199) (xy 82.215494 -53.418258)
			(xy 82.13979 -53.422293) (xy 82.064086 -53.418258) (xy 81.989241 -53.406199) (xy 81.9161 -53.386253)
			(xy 81.845495 -53.358646) (xy 81.778224 -53.32369) (xy 81.715049 -53.281782) (xy 81.656687 -53.233396)
			(xy 81.603799 -53.17908) (xy 81.556984 -53.119451) (xy 81.516772 -53.055183) (xy 81.48362 -52.987006)
			(xy 81.457902 -52.91569) (xy 81.43991 -52.842045) (xy 81.429848 -52.766905) (xy 81.427829 -52.691121)
			(xy 80.311751 -52.691121) (xy 80.309732 -52.766905) (xy 80.29967 -52.842045) (xy 80.281678 -52.91569)
			(xy 80.25596 -52.987006) (xy 80.222808 -53.055183) (xy 80.182596 -53.119451) (xy 80.135781 -53.17908)
			(xy 80.082893 -53.233396) (xy 80.024531 -53.281782) (xy 79.961356 -53.32369) (xy 79.894085 -53.358646)
			(xy 79.82348 -53.386253) (xy 79.750339 -53.406199) (xy 79.675494 -53.418258) (xy 79.59979 -53.422293)
			(xy 79.524086 -53.418258) (xy 79.449241 -53.406199) (xy 79.3761 -53.386253) (xy 79.305495 -53.358646)
			(xy 79.238224 -53.32369) (xy 79.175049 -53.281782) (xy 79.116687 -53.233396) (xy 79.063799 -53.17908)
			(xy 79.016984 -53.119451) (xy 78.976772 -53.055183) (xy 78.94362 -52.987006) (xy 78.917902 -52.91569)
			(xy 78.89991 -52.842045) (xy 78.889848 -52.766905) (xy 78.887829 -52.691121) (xy 77.771751 -52.691121)
			(xy 77.769732 -52.766905) (xy 77.75967 -52.842045) (xy 77.741678 -52.91569) (xy 77.71596 -52.987006)
			(xy 77.682808 -53.055183) (xy 77.642596 -53.119451) (xy 77.595781 -53.17908) (xy 77.542893 -53.233396)
			(xy 77.484531 -53.281782) (xy 77.421356 -53.32369) (xy 77.354085 -53.358646) (xy 77.28348 -53.386253)
			(xy 77.210339 -53.406199) (xy 77.135494 -53.418258) (xy 77.05979 -53.422293) (xy 76.984086 -53.418258)
			(xy 76.909241 -53.406199) (xy 76.8361 -53.386253) (xy 76.765495 -53.358646) (xy 76.698224 -53.32369)
			(xy 76.635049 -53.281782) (xy 76.576687 -53.233396) (xy 76.523799 -53.17908) (xy 76.476984 -53.119451)
			(xy 76.436772 -53.055183) (xy 76.40362 -52.987006) (xy 76.377902 -52.91569) (xy 76.35991 -52.842045)
			(xy 76.349848 -52.766905) (xy 76.347829 -52.691121) (xy 75.231751 -52.691121) (xy 75.229732 -52.766905)
			(xy 75.21967 -52.842045) (xy 75.201678 -52.91569) (xy 75.17596 -52.987006) (xy 75.142808 -53.055183)
			(xy 75.102596 -53.119451) (xy 75.055781 -53.17908) (xy 75.002893 -53.233396) (xy 74.944531 -53.281782)
			(xy 74.881356 -53.32369) (xy 74.814085 -53.358646) (xy 74.74348 -53.386253) (xy 74.670339 -53.406199)
			(xy 74.595494 -53.418258) (xy 74.51979 -53.422293) (xy 74.444086 -53.418258) (xy 74.369241 -53.406199)
			(xy 74.2961 -53.386253) (xy 74.225495 -53.358646) (xy 74.158224 -53.32369) (xy 74.095049 -53.281782)
			(xy 74.036687 -53.233396) (xy 73.983799 -53.17908) (xy 73.936984 -53.119451) (xy 73.896772 -53.055183)
			(xy 73.86362 -52.987006) (xy 73.837902 -52.91569) (xy 73.81991 -52.842045) (xy 73.809848 -52.766905)
			(xy 73.807829 -52.691121) (xy 72.691751 -52.691121) (xy 72.689732 -52.766905) (xy 72.67967 -52.842045)
			(xy 72.661678 -52.91569) (xy 72.63596 -52.987006) (xy 72.602808 -53.055183) (xy 72.562596 -53.119451)
			(xy 72.515781 -53.17908) (xy 72.462893 -53.233396) (xy 72.404531 -53.281782) (xy 72.341356 -53.32369)
			(xy 72.274085 -53.358646) (xy 72.20348 -53.386253) (xy 72.130339 -53.406199) (xy 72.055494 -53.418258)
			(xy 71.97979 -53.422293) (xy 71.904086 -53.418258) (xy 71.829241 -53.406199) (xy 71.7561 -53.386253)
			(xy 71.685495 -53.358646) (xy 71.618224 -53.32369) (xy 71.555049 -53.281782) (xy 71.496687 -53.233396)
			(xy 71.443799 -53.17908) (xy 71.396984 -53.119451) (xy 71.356772 -53.055183) (xy 71.32362 -52.987006)
			(xy 71.297902 -52.91569) (xy 71.27991 -52.842045) (xy 71.269848 -52.766905) (xy 71.267829 -52.691121)
			(xy 70.151751 -52.691121) (xy 70.149732 -52.766905) (xy 70.13967 -52.842045) (xy 70.121678 -52.91569)
			(xy 70.09596 -52.987006) (xy 70.062808 -53.055183) (xy 70.022596 -53.119451) (xy 69.975781 -53.17908)
			(xy 69.922893 -53.233396) (xy 69.864531 -53.281782) (xy 69.801356 -53.32369) (xy 69.734085 -53.358646)
			(xy 69.66348 -53.386253) (xy 69.590339 -53.406199) (xy 69.515494 -53.418258) (xy 69.43979 -53.422293)
			(xy 69.364086 -53.418258) (xy 69.289241 -53.406199) (xy 69.2161 -53.386253) (xy 69.145495 -53.358646)
			(xy 69.078224 -53.32369) (xy 69.015049 -53.281782) (xy 68.956687 -53.233396) (xy 68.903799 -53.17908)
			(xy 68.856984 -53.119451) (xy 68.816772 -53.055183) (xy 68.78362 -52.987006) (xy 68.757902 -52.91569)
			(xy 68.73991 -52.842045) (xy 68.729848 -52.766905) (xy 68.727829 -52.691121) (xy 67.611751 -52.691121)
			(xy 67.609732 -52.766905) (xy 67.59967 -52.842045) (xy 67.581678 -52.91569) (xy 67.55596 -52.987006)
			(xy 67.522808 -53.055183) (xy 67.482596 -53.119451) (xy 67.435781 -53.17908) (xy 67.382893 -53.233396)
			(xy 67.324531 -53.281782) (xy 67.261356 -53.32369) (xy 67.194085 -53.358646) (xy 67.12348 -53.386253)
			(xy 67.050339 -53.406199) (xy 66.975494 -53.418258) (xy 66.89979 -53.422293) (xy 66.824086 -53.418258)
			(xy 66.749241 -53.406199) (xy 66.6761 -53.386253) (xy 66.605495 -53.358646) (xy 66.538224 -53.32369)
			(xy 66.475049 -53.281782) (xy 66.416687 -53.233396) (xy 66.363799 -53.17908) (xy 66.316984 -53.119451)
			(xy 66.276772 -53.055183) (xy 66.24362 -52.987006) (xy 66.217902 -52.91569) (xy 66.19991 -52.842045)
			(xy 66.189848 -52.766905) (xy 66.187829 -52.691121) (xy 65.071751 -52.691121) (xy 65.069732 -52.766905)
			(xy 65.05967 -52.842045) (xy 65.041678 -52.91569) (xy 65.01596 -52.987006) (xy 64.982808 -53.055183)
			(xy 64.942596 -53.119451) (xy 64.895781 -53.17908) (xy 64.842893 -53.233396) (xy 64.784531 -53.281782)
			(xy 64.721356 -53.32369) (xy 64.654085 -53.358646) (xy 64.58348 -53.386253) (xy 64.510339 -53.406199)
			(xy 64.435494 -53.418258) (xy 64.35979 -53.422293) (xy 64.284086 -53.418258) (xy 64.209241 -53.406199)
			(xy 64.1361 -53.386253) (xy 64.065495 -53.358646) (xy 63.998224 -53.32369) (xy 63.935049 -53.281782)
			(xy 63.876687 -53.233396) (xy 63.823799 -53.17908) (xy 63.776984 -53.119451) (xy 63.736772 -53.055183)
			(xy 63.70362 -52.987006) (xy 63.677902 -52.91569) (xy 63.65991 -52.842045) (xy 63.649848 -52.766905)
			(xy 63.647829 -52.691121) (xy 42.526017 -52.691121) (xy 42.478867 -52.727408) (xy 42.3822 -52.791698)
			(xy 42.281328 -52.849165) (xy 42.176731 -52.899536) (xy 42.068908 -52.942571) (xy 41.958374 -52.978065)
			(xy 41.845654 -53.005848) (xy 41.731286 -53.025788) (xy 41.615814 -53.03779) (xy 41.49979 -53.041797)
			(xy 41.383766 -53.03779) (xy 41.268294 -53.025788) (xy 41.153926 -53.005848) (xy 41.041206 -52.978065)
			(xy 40.930672 -52.942571) (xy 40.822849 -52.899536) (xy 40.718252 -52.849165) (xy 40.61738 -52.791698)
			(xy 40.520713 -52.727408) (xy 40.428712 -52.656603) (xy 40.341815 -52.579619) (xy 40.260436 -52.496823)
			(xy 40.184963 -52.40861) (xy 40.115756 -52.3154) (xy 40.053144 -52.217637) (xy 39.997427 -52.115788)
			(xy 39.948869 -52.010338) (xy 39.907701 -51.901789) (xy 39.874121 -51.790658) (xy 39.848288 -51.677475)
			(xy 39.830325 -51.56278) (xy 39.820317 -51.447118) (xy 39.818314 -51.331042) (xy 14.369676 -51.331042)
			(xy 18.471959 -55.433484) (xy 29.519874 -55.433484) (xy 29.519874 -55.346584) (xy 29.527892 -55.260055)
			(xy 29.54386 -55.174635) (xy 29.567641 -55.091053) (xy 29.599033 -55.010021) (xy 29.637767 -54.932232)
			(xy 29.683514 -54.858348) (xy 29.735883 -54.789001) (xy 29.794427 -54.724781) (xy 29.858647 -54.666237)
			(xy 29.927994 -54.613868) (xy 30.001878 -54.568121) (xy 30.079667 -54.529387) (xy 30.160699 -54.497995)
			(xy 30.244281 -54.474214) (xy 30.329701 -54.458246) (xy 30.41623 -54.450228) (xy 30.45968 -54.449726)
			(xy 30.50313 -54.450228) (xy 30.589659 -54.458246) (xy 30.675079 -54.474214) (xy 30.758661 -54.497995)
			(xy 30.839693 -54.529387) (xy 30.917482 -54.568121) (xy 30.991366 -54.613868) (xy 31.060713 -54.666237)
			(xy 31.124933 -54.724781) (xy 31.183477 -54.789001) (xy 31.235846 -54.858348) (xy 31.281593 -54.932232)
			(xy 31.320327 -55.010021) (xy 31.351719 -55.091053) (xy 31.3755 -55.174635) (xy 31.391468 -55.260055)
			(xy 31.399486 -55.346584) (xy 31.399486 -55.433484) (xy 34.599874 -55.433484) (xy 34.599874 -55.346584)
			(xy 34.607892 -55.260055) (xy 34.62386 -55.174635) (xy 34.647641 -55.091053) (xy 34.679033 -55.010021)
			(xy 34.717767 -54.932232) (xy 34.763514 -54.858348) (xy 34.815883 -54.789001) (xy 34.874427 -54.724781)
			(xy 34.938647 -54.666237) (xy 35.007994 -54.613868) (xy 35.081878 -54.568121) (xy 35.159667 -54.529387)
			(xy 35.240699 -54.497995) (xy 35.324281 -54.474214) (xy 35.409701 -54.458246) (xy 35.49623 -54.450228)
			(xy 35.53968 -54.449726) (xy 35.58313 -54.450228) (xy 35.669659 -54.458246) (xy 35.755079 -54.474214)
			(xy 35.838661 -54.497995) (xy 35.919693 -54.529387) (xy 35.997482 -54.568121) (xy 36.071366 -54.613868)
			(xy 36.140713 -54.666237) (xy 36.204933 -54.724781) (xy 36.263477 -54.789001) (xy 36.315846 -54.858348)
			(xy 36.361593 -54.932232) (xy 36.400327 -55.010021) (xy 36.431719 -55.091053) (xy 36.4555 -55.174635)
			(xy 36.471468 -55.260055) (xy 36.479486 -55.346584) (xy 36.479486 -55.433484) (xy 36.471468 -55.520013)
			(xy 36.4555 -55.605433) (xy 36.431719 -55.689015) (xy 36.400327 -55.770047) (xy 36.361593 -55.847836)
			(xy 36.315846 -55.92172) (xy 36.263477 -55.991067) (xy 36.204933 -56.055287) (xy 36.140713 -56.113831)
			(xy 36.071366 -56.1662) (xy 35.997482 -56.211947) (xy 35.919693 -56.250681) (xy 35.838661 -56.282073)
			(xy 35.755079 -56.305854) (xy 35.669659 -56.321822) (xy 35.58313 -56.32984) (xy 35.49623 -56.32984)
			(xy 35.409701 -56.321822) (xy 35.324281 -56.305854) (xy 35.240699 -56.282073) (xy 35.159667 -56.250681)
			(xy 35.081878 -56.211947) (xy 35.007994 -56.1662) (xy 34.938647 -56.113831) (xy 34.874427 -56.055287)
			(xy 34.815883 -55.991067) (xy 34.763514 -55.92172) (xy 34.717767 -55.847836) (xy 34.679033 -55.770047)
			(xy 34.647641 -55.689015) (xy 34.62386 -55.605433) (xy 34.607892 -55.520013) (xy 34.599874 -55.433484)
			(xy 31.399486 -55.433484) (xy 31.391468 -55.520013) (xy 31.3755 -55.605433) (xy 31.351719 -55.689015)
			(xy 31.320327 -55.770047) (xy 31.281593 -55.847836) (xy 31.235846 -55.92172) (xy 31.183477 -55.991067)
			(xy 31.124933 -56.055287) (xy 31.060713 -56.113831) (xy 30.991366 -56.1662) (xy 30.917482 -56.211947)
			(xy 30.839693 -56.250681) (xy 30.758661 -56.282073) (xy 30.675079 -56.305854) (xy 30.589659 -56.321822)
			(xy 30.50313 -56.32984) (xy 30.41623 -56.32984) (xy 30.329701 -56.321822) (xy 30.244281 -56.305854)
			(xy 30.160699 -56.282073) (xy 30.079667 -56.250681) (xy 30.001878 -56.211947) (xy 29.927994 -56.1662)
			(xy 29.858647 -56.113831) (xy 29.794427 -56.055287) (xy 29.735883 -55.991067) (xy 29.683514 -55.92172)
			(xy 29.637767 -55.847836) (xy 29.599033 -55.770047) (xy 29.567641 -55.689015) (xy 29.54386 -55.605433)
			(xy 29.527892 -55.520013) (xy 29.519874 -55.433484) (xy 18.471959 -55.433484) (xy 19.376757 -56.338317)
			(xy 63.580764 -56.338317) (xy 63.580764 -56.266995) (xy 63.58875 -56.196121) (xy 63.60462 -56.126586)
			(xy 63.628177 -56.059266) (xy 63.659122 -55.995007) (xy 63.697068 -55.934616) (xy 63.741537 -55.878854)
			(xy 63.79197 -55.828421) (xy 63.847732 -55.783952) (xy 63.908123 -55.746006) (xy 63.972382 -55.715061)
			(xy 64.039702 -55.691504) (xy 64.109237 -55.675634) (xy 64.180111 -55.667648) (xy 64.215772 -55.667148)
			(xy 64.251433 -55.667648) (xy 64.322307 -55.675634) (xy 64.391842 -55.691504) (xy 64.459162 -55.715061)
			(xy 64.523421 -55.746006) (xy 64.583812 -55.783952) (xy 64.639574 -55.828421) (xy 64.690007 -55.878854)
			(xy 64.734476 -55.934616) (xy 64.772422 -55.995007) (xy 64.803367 -56.059266) (xy 64.826924 -56.126586)
			(xy 64.842794 -56.196121) (xy 64.85078 -56.266995) (xy 64.85078 -56.338317) (xy 66.572376 -56.338317)
			(xy 66.572376 -56.266995) (xy 66.580362 -56.196121) (xy 66.596232 -56.126586) (xy 66.619789 -56.059266)
			(xy 66.650734 -55.995007) (xy 66.68868 -55.934616) (xy 66.733149 -55.878854) (xy 66.783582 -55.828421)
			(xy 66.839344 -55.783952) (xy 66.899735 -55.746006) (xy 66.963994 -55.715061) (xy 67.031314 -55.691504)
			(xy 67.100849 -55.675634) (xy 67.171723 -55.667648) (xy 67.207384 -55.667148) (xy 67.243045 -55.667648)
			(xy 67.313919 -55.675634) (xy 67.383454 -55.691504) (xy 67.450774 -55.715061) (xy 67.515033 -55.746006)
			(xy 67.575424 -55.783952) (xy 67.631186 -55.828421) (xy 67.681619 -55.878854) (xy 67.726088 -55.934616)
			(xy 67.764034 -55.995007) (xy 67.794979 -56.059266) (xy 67.818536 -56.126586) (xy 67.834406 -56.196121)
			(xy 67.842392 -56.266995) (xy 67.842392 -56.338317) (xy 67.834406 -56.409191) (xy 67.818536 -56.478726)
			(xy 67.794979 -56.546046) (xy 67.764034 -56.610305) (xy 67.726088 -56.670696) (xy 67.681619 -56.726458)
			(xy 67.631186 -56.776891) (xy 67.575424 -56.82136) (xy 67.515033 -56.859306) (xy 67.450774 -56.890251)
			(xy 67.383454 -56.913808) (xy 67.313919 -56.929678) (xy 67.243045 -56.937664) (xy 67.171723 -56.937664)
			(xy 67.100849 -56.929678) (xy 67.031314 -56.913808) (xy 66.963994 -56.890251) (xy 66.899735 -56.859306)
			(xy 66.839344 -56.82136) (xy 66.783582 -56.776891) (xy 66.733149 -56.726458) (xy 66.68868 -56.670696)
			(xy 66.650734 -56.610305) (xy 66.619789 -56.546046) (xy 66.596232 -56.478726) (xy 66.580362 -56.409191)
			(xy 66.572376 -56.338317) (xy 64.85078 -56.338317) (xy 64.842794 -56.409191) (xy 64.826924 -56.478726)
			(xy 64.803367 -56.546046) (xy 64.772422 -56.610305) (xy 64.734476 -56.670696) (xy 64.690007 -56.726458)
			(xy 64.639574 -56.776891) (xy 64.583812 -56.82136) (xy 64.523421 -56.859306) (xy 64.459162 -56.890251)
			(xy 64.391842 -56.913808) (xy 64.322307 -56.929678) (xy 64.251433 -56.937664) (xy 64.180111 -56.937664)
			(xy 64.109237 -56.929678) (xy 64.039702 -56.913808) (xy 63.972382 -56.890251) (xy 63.908123 -56.859306)
			(xy 63.847732 -56.82136) (xy 63.79197 -56.776891) (xy 63.741537 -56.726458) (xy 63.697068 -56.670696)
			(xy 63.659122 -56.610305) (xy 63.628177 -56.546046) (xy 63.60462 -56.478726) (xy 63.58875 -56.409191)
			(xy 63.580764 -56.338317) (xy 19.376757 -56.338317) (xy 19.678396 -56.639968) (xy 19.678396 -57.973484)
			(xy 29.519874 -57.973484) (xy 29.519874 -57.886584) (xy 29.527892 -57.800055) (xy 29.54386 -57.714635)
			(xy 29.567641 -57.631053) (xy 29.599033 -57.550021) (xy 29.637767 -57.472232) (xy 29.683514 -57.398348)
			(xy 29.735883 -57.329001) (xy 29.794427 -57.264781) (xy 29.858647 -57.206237) (xy 29.927994 -57.153868)
			(xy 30.001878 -57.108121) (xy 30.079667 -57.069387) (xy 30.160699 -57.037995) (xy 30.244281 -57.014214)
			(xy 30.329701 -56.998246) (xy 30.41623 -56.990228) (xy 30.45968 -56.989726) (xy 30.50313 -56.990228)
			(xy 30.589659 -56.998246) (xy 30.675079 -57.014214) (xy 30.758661 -57.037995) (xy 30.839693 -57.069387)
			(xy 30.917482 -57.108121) (xy 30.991366 -57.153868) (xy 31.060713 -57.206237) (xy 31.124933 -57.264781)
			(xy 31.183477 -57.329001) (xy 31.235846 -57.398348) (xy 31.281593 -57.472232) (xy 31.320327 -57.550021)
			(xy 31.351719 -57.631053) (xy 31.3755 -57.714635) (xy 31.391468 -57.800055) (xy 31.399486 -57.886584)
			(xy 31.399486 -57.973484) (xy 34.599874 -57.973484) (xy 34.599874 -57.886584) (xy 34.607892 -57.800055)
			(xy 34.62386 -57.714635) (xy 34.647641 -57.631053) (xy 34.679033 -57.550021) (xy 34.717767 -57.472232)
			(xy 34.763514 -57.398348) (xy 34.815883 -57.329001) (xy 34.874427 -57.264781) (xy 34.938647 -57.206237)
			(xy 35.007994 -57.153868) (xy 35.081878 -57.108121) (xy 35.159667 -57.069387) (xy 35.240699 -57.037995)
			(xy 35.324281 -57.014214) (xy 35.409701 -56.998246) (xy 35.49623 -56.990228) (xy 35.53968 -56.989726)
			(xy 35.58313 -56.990228) (xy 35.669659 -56.998246) (xy 35.755079 -57.014214) (xy 35.838661 -57.037995)
			(xy 35.919693 -57.069387) (xy 35.997482 -57.108121) (xy 36.071366 -57.153868) (xy 36.140713 -57.206237)
			(xy 36.204933 -57.264781) (xy 36.263477 -57.329001) (xy 36.315846 -57.398348) (xy 36.361593 -57.472232)
			(xy 36.400327 -57.550021) (xy 36.431719 -57.631053) (xy 36.4555 -57.714635) (xy 36.471468 -57.800055)
			(xy 36.479486 -57.886584) (xy 36.479486 -57.973484) (xy 36.471468 -58.060013) (xy 36.4555 -58.145433)
			(xy 36.431719 -58.229015) (xy 36.400327 -58.310047) (xy 36.361593 -58.387836) (xy 36.315846 -58.46172)
			(xy 36.263477 -58.531067) (xy 36.204933 -58.595287) (xy 36.140713 -58.653831) (xy 36.071366 -58.7062)
			(xy 35.997482 -58.751947) (xy 35.919693 -58.790681) (xy 35.838661 -58.822073) (xy 35.755079 -58.845854)
			(xy 35.669659 -58.861822) (xy 35.58313 -58.86984) (xy 35.49623 -58.86984) (xy 35.409701 -58.861822)
			(xy 35.324281 -58.845854) (xy 35.240699 -58.822073) (xy 35.159667 -58.790681) (xy 35.081878 -58.751947)
			(xy 35.007994 -58.7062) (xy 34.938647 -58.653831) (xy 34.874427 -58.595287) (xy 34.815883 -58.531067)
			(xy 34.763514 -58.46172) (xy 34.717767 -58.387836) (xy 34.679033 -58.310047) (xy 34.647641 -58.229015)
			(xy 34.62386 -58.145433) (xy 34.607892 -58.060013) (xy 34.599874 -57.973484) (xy 31.399486 -57.973484)
			(xy 31.391468 -58.060013) (xy 31.3755 -58.145433) (xy 31.351719 -58.229015) (xy 31.320327 -58.310047)
			(xy 31.281593 -58.387836) (xy 31.235846 -58.46172) (xy 31.183477 -58.531067) (xy 31.124933 -58.595287)
			(xy 31.060713 -58.653831) (xy 30.991366 -58.7062) (xy 30.917482 -58.751947) (xy 30.839693 -58.790681)
			(xy 30.758661 -58.822073) (xy 30.675079 -58.845854) (xy 30.589659 -58.861822) (xy 30.50313 -58.86984)
			(xy 30.41623 -58.86984) (xy 30.329701 -58.861822) (xy 30.244281 -58.845854) (xy 30.160699 -58.822073)
			(xy 30.079667 -58.790681) (xy 30.001878 -58.751947) (xy 29.927994 -58.7062) (xy 29.858647 -58.653831)
			(xy 29.794427 -58.595287) (xy 29.735883 -58.531067) (xy 29.683514 -58.46172) (xy 29.637767 -58.387836)
			(xy 29.599033 -58.310047) (xy 29.567641 -58.229015) (xy 29.54386 -58.145433) (xy 29.527892 -58.060013)
			(xy 29.519874 -57.973484) (xy 19.678396 -57.973484) (xy 19.678396 -59.009127) (xy 63.580764 -59.009127)
			(xy 63.580764 -58.937805) (xy 63.58875 -58.866931) (xy 63.60462 -58.797396) (xy 63.628177 -58.730076)
			(xy 63.659122 -58.665817) (xy 63.697068 -58.605426) (xy 63.741537 -58.549664) (xy 63.79197 -58.499231)
			(xy 63.847732 -58.454762) (xy 63.908123 -58.416816) (xy 63.972382 -58.385871) (xy 64.039702 -58.362314)
			(xy 64.109237 -58.346444) (xy 64.180111 -58.338458) (xy 64.215772 -58.337958) (xy 64.251433 -58.338458)
			(xy 64.322307 -58.346444) (xy 64.391842 -58.362314) (xy 64.459162 -58.385871) (xy 64.523421 -58.416816)
			(xy 64.583812 -58.454762) (xy 64.639574 -58.499231) (xy 64.690007 -58.549664) (xy 64.734476 -58.605426)
			(xy 64.772422 -58.665817) (xy 64.803367 -58.730076) (xy 64.826924 -58.797396) (xy 64.842794 -58.866931)
			(xy 64.85078 -58.937805) (xy 64.85078 -59.009127) (xy 66.572376 -59.009127) (xy 66.572376 -58.937805)
			(xy 66.580362 -58.866931) (xy 66.596232 -58.797396) (xy 66.619789 -58.730076) (xy 66.650734 -58.665817)
			(xy 66.68868 -58.605426) (xy 66.733149 -58.549664) (xy 66.783582 -58.499231) (xy 66.839344 -58.454762)
			(xy 66.899735 -58.416816) (xy 66.963994 -58.385871) (xy 67.031314 -58.362314) (xy 67.100849 -58.346444)
			(xy 67.171723 -58.338458) (xy 67.207384 -58.337958) (xy 67.243045 -58.338458) (xy 67.313919 -58.346444)
			(xy 67.383454 -58.362314) (xy 67.450774 -58.385871) (xy 67.515033 -58.416816) (xy 67.575424 -58.454762)
			(xy 67.631186 -58.499231) (xy 67.681619 -58.549664) (xy 67.726088 -58.605426) (xy 67.764034 -58.665817)
			(xy 67.794979 -58.730076) (xy 67.818536 -58.797396) (xy 67.834406 -58.866931) (xy 67.842392 -58.937805)
			(xy 67.842392 -59.009127) (xy 67.834406 -59.080001) (xy 67.818536 -59.149536) (xy 67.794979 -59.216856)
			(xy 67.764034 -59.281115) (xy 67.726088 -59.341506) (xy 67.681619 -59.397268) (xy 67.631186 -59.447701)
			(xy 67.575424 -59.49217) (xy 67.515033 -59.530116) (xy 67.450774 -59.561061) (xy 67.383454 -59.584618)
			(xy 67.313919 -59.600488) (xy 67.243045 -59.608474) (xy 67.171723 -59.608474) (xy 67.100849 -59.600488)
			(xy 67.031314 -59.584618) (xy 66.963994 -59.561061) (xy 66.899735 -59.530116) (xy 66.839344 -59.49217)
			(xy 66.783582 -59.447701) (xy 66.733149 -59.397268) (xy 66.68868 -59.341506) (xy 66.650734 -59.281115)
			(xy 66.619789 -59.216856) (xy 66.596232 -59.149536) (xy 66.580362 -59.080001) (xy 66.572376 -59.009127)
			(xy 64.85078 -59.009127) (xy 64.842794 -59.080001) (xy 64.826924 -59.149536) (xy 64.803367 -59.216856)
			(xy 64.772422 -59.281115) (xy 64.734476 -59.341506) (xy 64.690007 -59.397268) (xy 64.639574 -59.447701)
			(xy 64.583812 -59.49217) (xy 64.523421 -59.530116) (xy 64.459162 -59.561061) (xy 64.391842 -59.584618)
			(xy 64.322307 -59.600488) (xy 64.251433 -59.608474) (xy 64.180111 -59.608474) (xy 64.109237 -59.600488)
			(xy 64.039702 -59.584618) (xy 63.972382 -59.561061) (xy 63.908123 -59.530116) (xy 63.847732 -59.49217)
			(xy 63.79197 -59.447701) (xy 63.741537 -59.397268) (xy 63.697068 -59.341506) (xy 63.659122 -59.281115)
			(xy 63.628177 -59.216856) (xy 63.60462 -59.149536) (xy 63.58875 -59.080001) (xy 63.580764 -59.009127)
			(xy 19.678396 -59.009127) (xy 19.678396 -60.513484) (xy 29.519874 -60.513484) (xy 29.519874 -60.426584)
			(xy 29.527892 -60.340055) (xy 29.54386 -60.254635) (xy 29.567641 -60.171053) (xy 29.599033 -60.090021)
			(xy 29.637767 -60.012232) (xy 29.683514 -59.938348) (xy 29.735883 -59.869001) (xy 29.794427 -59.804781)
			(xy 29.858647 -59.746237) (xy 29.927994 -59.693868) (xy 30.001878 -59.648121) (xy 30.079667 -59.609387)
			(xy 30.160699 -59.577995) (xy 30.244281 -59.554214) (xy 30.329701 -59.538246) (xy 30.41623 -59.530228)
			(xy 30.45968 -59.529726) (xy 30.50313 -59.530228) (xy 30.589659 -59.538246) (xy 30.675079 -59.554214)
			(xy 30.758661 -59.577995) (xy 30.839693 -59.609387) (xy 30.917482 -59.648121) (xy 30.991366 -59.693868)
			(xy 31.060713 -59.746237) (xy 31.124933 -59.804781) (xy 31.183477 -59.869001) (xy 31.235846 -59.938348)
			(xy 31.281593 -60.012232) (xy 31.320327 -60.090021) (xy 31.351719 -60.171053) (xy 31.3755 -60.254635)
			(xy 31.391468 -60.340055) (xy 31.399486 -60.426584) (xy 31.399486 -60.513484) (xy 34.599874 -60.513484)
			(xy 34.599874 -60.426584) (xy 34.607892 -60.340055) (xy 34.62386 -60.254635) (xy 34.647641 -60.171053)
			(xy 34.679033 -60.090021) (xy 34.717767 -60.012232) (xy 34.763514 -59.938348) (xy 34.815883 -59.869001)
			(xy 34.874427 -59.804781) (xy 34.938647 -59.746237) (xy 35.007994 -59.693868) (xy 35.081878 -59.648121)
			(xy 35.159667 -59.609387) (xy 35.240699 -59.577995) (xy 35.324281 -59.554214) (xy 35.409701 -59.538246)
			(xy 35.49623 -59.530228) (xy 35.53968 -59.529726) (xy 35.58313 -59.530228) (xy 35.669659 -59.538246)
			(xy 35.755079 -59.554214) (xy 35.838661 -59.577995) (xy 35.919693 -59.609387) (xy 35.997482 -59.648121)
			(xy 36.071366 -59.693868) (xy 36.140713 -59.746237) (xy 36.204933 -59.804781) (xy 36.263477 -59.869001)
			(xy 36.315846 -59.938348) (xy 36.361593 -60.012232) (xy 36.400327 -60.090021) (xy 36.431719 -60.171053)
			(xy 36.4555 -60.254635) (xy 36.471468 -60.340055) (xy 36.479486 -60.426584) (xy 36.479486 -60.513484)
			(xy 36.471468 -60.600013) (xy 36.4555 -60.685433) (xy 36.431719 -60.769015) (xy 36.400327 -60.850047)
			(xy 36.361593 -60.927836) (xy 36.315846 -61.00172) (xy 36.263477 -61.071067) (xy 36.204933 -61.135287)
			(xy 36.140713 -61.193831) (xy 36.071366 -61.2462) (xy 35.997482 -61.291947) (xy 35.919693 -61.330681)
			(xy 35.838661 -61.362073) (xy 35.755079 -61.385854) (xy 35.669659 -61.401822) (xy 35.58313 -61.40984)
			(xy 35.49623 -61.40984) (xy 35.409701 -61.401822) (xy 35.324281 -61.385854) (xy 35.240699 -61.362073)
			(xy 35.159667 -61.330681) (xy 35.081878 -61.291947) (xy 35.007994 -61.2462) (xy 34.938647 -61.193831)
			(xy 34.874427 -61.135287) (xy 34.815883 -61.071067) (xy 34.763514 -61.00172) (xy 34.717767 -60.927836)
			(xy 34.679033 -60.850047) (xy 34.647641 -60.769015) (xy 34.62386 -60.685433) (xy 34.607892 -60.600013)
			(xy 34.599874 -60.513484) (xy 31.399486 -60.513484) (xy 31.391468 -60.600013) (xy 31.3755 -60.685433)
			(xy 31.351719 -60.769015) (xy 31.320327 -60.850047) (xy 31.281593 -60.927836) (xy 31.235846 -61.00172)
			(xy 31.183477 -61.071067) (xy 31.124933 -61.135287) (xy 31.060713 -61.193831) (xy 30.991366 -61.2462)
			(xy 30.917482 -61.291947) (xy 30.839693 -61.330681) (xy 30.758661 -61.362073) (xy 30.675079 -61.385854)
			(xy 30.589659 -61.401822) (xy 30.50313 -61.40984) (xy 30.41623 -61.40984) (xy 30.329701 -61.401822)
			(xy 30.244281 -61.385854) (xy 30.160699 -61.362073) (xy 30.079667 -61.330681) (xy 30.001878 -61.291947)
			(xy 29.927994 -61.2462) (xy 29.858647 -61.193831) (xy 29.794427 -61.135287) (xy 29.735883 -61.071067)
			(xy 29.683514 -61.00172) (xy 29.637767 -60.927836) (xy 29.599033 -60.850047) (xy 29.567641 -60.769015)
			(xy 29.54386 -60.685433) (xy 29.527892 -60.600013) (xy 29.519874 -60.513484) (xy 19.678396 -60.513484)
			(xy 19.678396 -61.677397) (xy 63.580764 -61.677397) (xy 63.580764 -61.606075) (xy 63.58875 -61.535201)
			(xy 63.60462 -61.465666) (xy 63.628177 -61.398346) (xy 63.659122 -61.334087) (xy 63.697068 -61.273696)
			(xy 63.741537 -61.217934) (xy 63.79197 -61.167501) (xy 63.847732 -61.123032) (xy 63.908123 -61.085086)
			(xy 63.972382 -61.054141) (xy 64.039702 -61.030584) (xy 64.109237 -61.014714) (xy 64.180111 -61.006728)
			(xy 64.215772 -61.006228) (xy 64.251433 -61.006728) (xy 64.322307 -61.014714) (xy 64.391842 -61.030584)
			(xy 64.459162 -61.054141) (xy 64.523421 -61.085086) (xy 64.583812 -61.123032) (xy 64.639574 -61.167501)
			(xy 64.690007 -61.217934) (xy 64.734476 -61.273696) (xy 64.772422 -61.334087) (xy 64.803367 -61.398346)
			(xy 64.826924 -61.465666) (xy 64.842794 -61.535201) (xy 64.85078 -61.606075) (xy 64.85078 -61.677397)
			(xy 66.572376 -61.677397) (xy 66.572376 -61.606075) (xy 66.580362 -61.535201) (xy 66.596232 -61.465666)
			(xy 66.619789 -61.398346) (xy 66.650734 -61.334087) (xy 66.68868 -61.273696) (xy 66.733149 -61.217934)
			(xy 66.783582 -61.167501) (xy 66.839344 -61.123032) (xy 66.899735 -61.085086) (xy 66.963994 -61.054141)
			(xy 67.031314 -61.030584) (xy 67.100849 -61.014714) (xy 67.171723 -61.006728) (xy 67.207384 -61.006228)
			(xy 67.243045 -61.006728) (xy 67.313919 -61.014714) (xy 67.383454 -61.030584) (xy 67.450774 -61.054141)
			(xy 67.515033 -61.085086) (xy 67.575424 -61.123032) (xy 67.631186 -61.167501) (xy 67.681619 -61.217934)
			(xy 67.726088 -61.273696) (xy 67.764034 -61.334087) (xy 67.794979 -61.398346) (xy 67.818536 -61.465666)
			(xy 67.834406 -61.535201) (xy 67.842392 -61.606075) (xy 67.842392 -61.677397) (xy 67.834406 -61.748271)
			(xy 67.818536 -61.817806) (xy 67.794979 -61.885126) (xy 67.764034 -61.949385) (xy 67.726088 -62.009776)
			(xy 67.681619 -62.065538) (xy 67.631186 -62.115971) (xy 67.575424 -62.16044) (xy 67.515033 -62.198386)
			(xy 67.450774 -62.229331) (xy 67.383454 -62.252888) (xy 67.313919 -62.268758) (xy 67.243045 -62.276744)
			(xy 67.171723 -62.276744) (xy 67.100849 -62.268758) (xy 67.031314 -62.252888) (xy 66.963994 -62.229331)
			(xy 66.899735 -62.198386) (xy 66.839344 -62.16044) (xy 66.783582 -62.115971) (xy 66.733149 -62.065538)
			(xy 66.68868 -62.009776) (xy 66.650734 -61.949385) (xy 66.619789 -61.885126) (xy 66.596232 -61.817806)
			(xy 66.580362 -61.748271) (xy 66.572376 -61.677397) (xy 64.85078 -61.677397) (xy 64.842794 -61.748271)
			(xy 64.826924 -61.817806) (xy 64.803367 -61.885126) (xy 64.772422 -61.949385) (xy 64.734476 -62.009776)
			(xy 64.690007 -62.065538) (xy 64.639574 -62.115971) (xy 64.583812 -62.16044) (xy 64.523421 -62.198386)
			(xy 64.459162 -62.229331) (xy 64.391842 -62.252888) (xy 64.322307 -62.268758) (xy 64.251433 -62.276744)
			(xy 64.180111 -62.276744) (xy 64.109237 -62.268758) (xy 64.039702 -62.252888) (xy 63.972382 -62.229331)
			(xy 63.908123 -62.198386) (xy 63.847732 -62.16044) (xy 63.79197 -62.115971) (xy 63.741537 -62.065538)
			(xy 63.697068 -62.009776) (xy 63.659122 -61.949385) (xy 63.628177 -61.885126) (xy 63.60462 -61.817806)
			(xy 63.58875 -61.748271) (xy 63.580764 -61.677397) (xy 19.678396 -61.677397) (xy 19.678396 -63.053484)
			(xy 29.519874 -63.053484) (xy 29.519874 -62.966584) (xy 29.527892 -62.880055) (xy 29.54386 -62.794635)
			(xy 29.567641 -62.711053) (xy 29.599033 -62.630021) (xy 29.637767 -62.552232) (xy 29.683514 -62.478348)
			(xy 29.735883 -62.409001) (xy 29.794427 -62.344781) (xy 29.858647 -62.286237) (xy 29.927994 -62.233868)
			(xy 30.001878 -62.188121) (xy 30.079667 -62.149387) (xy 30.160699 -62.117995) (xy 30.244281 -62.094214)
			(xy 30.329701 -62.078246) (xy 30.41623 -62.070228) (xy 30.45968 -62.069726) (xy 30.50313 -62.070228)
			(xy 30.589659 -62.078246) (xy 30.675079 -62.094214) (xy 30.758661 -62.117995) (xy 30.839693 -62.149387)
			(xy 30.917482 -62.188121) (xy 30.991366 -62.233868) (xy 31.060713 -62.286237) (xy 31.124933 -62.344781)
			(xy 31.183477 -62.409001) (xy 31.235846 -62.478348) (xy 31.281593 -62.552232) (xy 31.320327 -62.630021)
			(xy 31.351719 -62.711053) (xy 31.3755 -62.794635) (xy 31.391468 -62.880055) (xy 31.399486 -62.966584)
			(xy 31.399486 -63.053484) (xy 34.599874 -63.053484) (xy 34.599874 -62.966584) (xy 34.607892 -62.880055)
			(xy 34.62386 -62.794635) (xy 34.647641 -62.711053) (xy 34.679033 -62.630021) (xy 34.717767 -62.552232)
			(xy 34.763514 -62.478348) (xy 34.815883 -62.409001) (xy 34.874427 -62.344781) (xy 34.938647 -62.286237)
			(xy 35.007994 -62.233868) (xy 35.081878 -62.188121) (xy 35.159667 -62.149387) (xy 35.240699 -62.117995)
			(xy 35.324281 -62.094214) (xy 35.409701 -62.078246) (xy 35.49623 -62.070228) (xy 35.53968 -62.069726)
			(xy 35.58313 -62.070228) (xy 35.669659 -62.078246) (xy 35.755079 -62.094214) (xy 35.838661 -62.117995)
			(xy 35.919693 -62.149387) (xy 35.997482 -62.188121) (xy 36.071366 -62.233868) (xy 36.140713 -62.286237)
			(xy 36.204933 -62.344781) (xy 36.263477 -62.409001) (xy 36.315846 -62.478348) (xy 36.361593 -62.552232)
			(xy 36.400327 -62.630021) (xy 36.431719 -62.711053) (xy 36.4555 -62.794635) (xy 36.471468 -62.880055)
			(xy 36.475431 -62.922827) (xy 51.025288 -62.922827) (xy 51.025288 -62.841717) (xy 51.033238 -62.760998)
			(xy 51.049061 -62.681447) (xy 51.072606 -62.603831) (xy 51.103645 -62.528895) (xy 51.14188 -62.457363)
			(xy 51.186942 -62.389923) (xy 51.238397 -62.327224) (xy 51.29575 -62.269871) (xy 51.358449 -62.218416)
			(xy 51.425889 -62.173354) (xy 51.497421 -62.135119) (xy 51.572357 -62.10408) (xy 51.649973 -62.080535)
			(xy 51.729524 -62.064712) (xy 51.810243 -62.056762) (xy 51.850798 -62.056264) (xy 51.891353 -62.056762)
			(xy 51.972072 -62.064712) (xy 52.051623 -62.080535) (xy 52.129239 -62.10408) (xy 52.204175 -62.135119)
			(xy 52.275707 -62.173354) (xy 52.343147 -62.218416) (xy 52.405846 -62.269871) (xy 52.463199 -62.327224)
			(xy 52.514654 -62.389923) (xy 52.559716 -62.457363) (xy 52.597951 -62.528895) (xy 52.62899 -62.603831)
			(xy 52.652535 -62.681447) (xy 52.668358 -62.760998) (xy 52.676308 -62.841717) (xy 52.676308 -62.922827)
			(xy 52.668358 -63.003546) (xy 52.652535 -63.083097) (xy 52.62899 -63.160713) (xy 52.597951 -63.235649)
			(xy 52.559716 -63.307181) (xy 52.514654 -63.374621) (xy 52.463199 -63.43732) (xy 52.405846 -63.494673)
			(xy 52.343147 -63.546128) (xy 52.275707 -63.59119) (xy 52.204175 -63.629425) (xy 52.129239 -63.660464)
			(xy 52.051623 -63.684009) (xy 51.972072 -63.699832) (xy 51.891353 -63.707782) (xy 51.810243 -63.707782)
			(xy 51.729524 -63.699832) (xy 51.649973 -63.684009) (xy 51.572357 -63.660464) (xy 51.497421 -63.629425)
			(xy 51.425889 -63.59119) (xy 51.358449 -63.546128) (xy 51.29575 -63.494673) (xy 51.238397 -63.43732)
			(xy 51.186942 -63.374621) (xy 51.14188 -63.307181) (xy 51.103645 -63.235649) (xy 51.072606 -63.160713)
			(xy 51.049061 -63.083097) (xy 51.033238 -63.003546) (xy 51.025288 -62.922827) (xy 36.475431 -62.922827)
			(xy 36.479486 -62.966584) (xy 36.479486 -63.053484) (xy 36.471468 -63.140013) (xy 36.4555 -63.225433)
			(xy 36.431719 -63.309015) (xy 36.400327 -63.390047) (xy 36.361593 -63.467836) (xy 36.315846 -63.54172)
			(xy 36.263477 -63.611067) (xy 36.204933 -63.675287) (xy 36.140713 -63.733831) (xy 36.071366 -63.7862)
			(xy 35.997482 -63.831947) (xy 35.919693 -63.870681) (xy 35.838661 -63.902073) (xy 35.755079 -63.925854)
			(xy 35.669659 -63.941822) (xy 35.58313 -63.94984) (xy 35.49623 -63.94984) (xy 35.409701 -63.941822)
			(xy 35.324281 -63.925854) (xy 35.240699 -63.902073) (xy 35.159667 -63.870681) (xy 35.081878 -63.831947)
			(xy 35.007994 -63.7862) (xy 34.938647 -63.733831) (xy 34.874427 -63.675287) (xy 34.815883 -63.611067)
			(xy 34.763514 -63.54172) (xy 34.717767 -63.467836) (xy 34.679033 -63.390047) (xy 34.647641 -63.309015)
			(xy 34.62386 -63.225433) (xy 34.607892 -63.140013) (xy 34.599874 -63.053484) (xy 31.399486 -63.053484)
			(xy 31.391468 -63.140013) (xy 31.3755 -63.225433) (xy 31.351719 -63.309015) (xy 31.320327 -63.390047)
			(xy 31.281593 -63.467836) (xy 31.235846 -63.54172) (xy 31.183477 -63.611067) (xy 31.124933 -63.675287)
			(xy 31.060713 -63.733831) (xy 30.991366 -63.7862) (xy 30.917482 -63.831947) (xy 30.839693 -63.870681)
			(xy 30.758661 -63.902073) (xy 30.675079 -63.925854) (xy 30.589659 -63.941822) (xy 30.50313 -63.94984)
			(xy 30.41623 -63.94984) (xy 30.329701 -63.941822) (xy 30.244281 -63.925854) (xy 30.160699 -63.902073)
			(xy 30.079667 -63.870681) (xy 30.001878 -63.831947) (xy 29.927994 -63.7862) (xy 29.858647 -63.733831)
			(xy 29.794427 -63.675287) (xy 29.735883 -63.611067) (xy 29.683514 -63.54172) (xy 29.637767 -63.467836)
			(xy 29.599033 -63.390047) (xy 29.567641 -63.309015) (xy 29.54386 -63.225433) (xy 29.527892 -63.140013)
			(xy 29.519874 -63.053484) (xy 19.678396 -63.053484) (xy 19.678396 -64.048995) (xy 63.580764 -64.048995)
			(xy 63.580764 -63.977673) (xy 63.58875 -63.906799) (xy 63.60462 -63.837264) (xy 63.628177 -63.769944)
			(xy 63.659122 -63.705685) (xy 63.697068 -63.645294) (xy 63.741537 -63.589532) (xy 63.79197 -63.539099)
			(xy 63.847732 -63.49463) (xy 63.908123 -63.456684) (xy 63.972382 -63.425739) (xy 64.039702 -63.402182)
			(xy 64.109237 -63.386312) (xy 64.180111 -63.378326) (xy 64.215772 -63.377826) (xy 64.251433 -63.378326)
			(xy 64.322307 -63.386312) (xy 64.391842 -63.402182) (xy 64.459162 -63.425739) (xy 64.523421 -63.456684)
			(xy 64.583812 -63.49463) (xy 64.639574 -63.539099) (xy 64.690007 -63.589532) (xy 64.734476 -63.645294)
			(xy 64.772422 -63.705685) (xy 64.803367 -63.769944) (xy 64.826924 -63.837264) (xy 64.842794 -63.906799)
			(xy 64.85078 -63.977673) (xy 64.85078 -64.048995) (xy 66.572376 -64.048995) (xy 66.572376 -63.977673)
			(xy 66.580362 -63.906799) (xy 66.596232 -63.837264) (xy 66.619789 -63.769944) (xy 66.650734 -63.705685)
			(xy 66.68868 -63.645294) (xy 66.733149 -63.589532) (xy 66.783582 -63.539099) (xy 66.839344 -63.49463)
			(xy 66.899735 -63.456684) (xy 66.963994 -63.425739) (xy 67.031314 -63.402182) (xy 67.100849 -63.386312)
			(xy 67.171723 -63.378326) (xy 67.207384 -63.377826) (xy 67.243045 -63.378326) (xy 67.313919 -63.386312)
			(xy 67.383454 -63.402182) (xy 67.450774 -63.425739) (xy 67.515033 -63.456684) (xy 67.575424 -63.49463)
			(xy 67.631186 -63.539099) (xy 67.681619 -63.589532) (xy 67.726088 -63.645294) (xy 67.764034 -63.705685)
			(xy 67.794979 -63.769944) (xy 67.818536 -63.837264) (xy 67.834406 -63.906799) (xy 67.842392 -63.977673)
			(xy 67.842392 -64.048995) (xy 67.834406 -64.119869) (xy 67.818536 -64.189404) (xy 67.794979 -64.256724)
			(xy 67.764034 -64.320983) (xy 67.726088 -64.381374) (xy 67.681619 -64.437136) (xy 67.631186 -64.487569)
			(xy 67.575424 -64.532038) (xy 67.515033 -64.569984) (xy 67.450774 -64.600929) (xy 67.383454 -64.624486)
			(xy 67.313919 -64.640356) (xy 67.243045 -64.648342) (xy 67.171723 -64.648342) (xy 67.100849 -64.640356)
			(xy 67.031314 -64.624486) (xy 66.963994 -64.600929) (xy 66.899735 -64.569984) (xy 66.839344 -64.532038)
			(xy 66.783582 -64.487569) (xy 66.733149 -64.437136) (xy 66.68868 -64.381374) (xy 66.650734 -64.320983)
			(xy 66.619789 -64.256724) (xy 66.596232 -64.189404) (xy 66.580362 -64.119869) (xy 66.572376 -64.048995)
			(xy 64.85078 -64.048995) (xy 64.842794 -64.119869) (xy 64.826924 -64.189404) (xy 64.803367 -64.256724)
			(xy 64.772422 -64.320983) (xy 64.734476 -64.381374) (xy 64.690007 -64.437136) (xy 64.639574 -64.487569)
			(xy 64.583812 -64.532038) (xy 64.523421 -64.569984) (xy 64.459162 -64.600929) (xy 64.391842 -64.624486)
			(xy 64.322307 -64.640356) (xy 64.251433 -64.648342) (xy 64.180111 -64.648342) (xy 64.109237 -64.640356)
			(xy 64.039702 -64.624486) (xy 63.972382 -64.600929) (xy 63.908123 -64.569984) (xy 63.847732 -64.532038)
			(xy 63.79197 -64.487569) (xy 63.741537 -64.437136) (xy 63.697068 -64.381374) (xy 63.659122 -64.320983)
			(xy 63.628177 -64.256724) (xy 63.60462 -64.189404) (xy 63.58875 -64.119869) (xy 63.580764 -64.048995)
			(xy 19.678396 -64.048995) (xy 19.678396 -65.593484) (xy 29.519874 -65.593484) (xy 29.519874 -65.506584)
			(xy 29.527892 -65.420055) (xy 29.54386 -65.334635) (xy 29.567641 -65.251053) (xy 29.599033 -65.170021)
			(xy 29.637767 -65.092232) (xy 29.683514 -65.018348) (xy 29.735883 -64.949001) (xy 29.794427 -64.884781)
			(xy 29.858647 -64.826237) (xy 29.927994 -64.773868) (xy 30.001878 -64.728121) (xy 30.079667 -64.689387)
			(xy 30.160699 -64.657995) (xy 30.244281 -64.634214) (xy 30.329701 -64.618246) (xy 30.41623 -64.610228)
			(xy 30.45968 -64.609726) (xy 30.50313 -64.610228) (xy 30.589659 -64.618246) (xy 30.675079 -64.634214)
			(xy 30.758661 -64.657995) (xy 30.839693 -64.689387) (xy 30.917482 -64.728121) (xy 30.991366 -64.773868)
			(xy 31.060713 -64.826237) (xy 31.124933 -64.884781) (xy 31.183477 -64.949001) (xy 31.235846 -65.018348)
			(xy 31.281593 -65.092232) (xy 31.320327 -65.170021) (xy 31.351719 -65.251053) (xy 31.3755 -65.334635)
			(xy 31.391468 -65.420055) (xy 31.399486 -65.506584) (xy 31.399486 -65.593484) (xy 34.599874 -65.593484)
			(xy 34.599874 -65.506584) (xy 34.607892 -65.420055) (xy 34.62386 -65.334635) (xy 34.647641 -65.251053)
			(xy 34.679033 -65.170021) (xy 34.717767 -65.092232) (xy 34.763514 -65.018348) (xy 34.815883 -64.949001)
			(xy 34.874427 -64.884781) (xy 34.938647 -64.826237) (xy 35.007994 -64.773868) (xy 35.081878 -64.728121)
			(xy 35.159667 -64.689387) (xy 35.240699 -64.657995) (xy 35.324281 -64.634214) (xy 35.409701 -64.618246)
			(xy 35.49623 -64.610228) (xy 35.53968 -64.609726) (xy 35.58313 -64.610228) (xy 35.669659 -64.618246)
			(xy 35.755079 -64.634214) (xy 35.838661 -64.657995) (xy 35.919693 -64.689387) (xy 35.997482 -64.728121)
			(xy 36.071366 -64.773868) (xy 36.140713 -64.826237) (xy 36.204933 -64.884781) (xy 36.263477 -64.949001)
			(xy 36.315846 -65.018348) (xy 36.361593 -65.092232) (xy 36.400327 -65.170021) (xy 36.431719 -65.251053)
			(xy 36.4555 -65.334635) (xy 36.471468 -65.420055) (xy 36.479486 -65.506584) (xy 36.479486 -65.593484)
			(xy 36.471468 -65.680013) (xy 36.4555 -65.765433) (xy 36.431719 -65.849015) (xy 36.400327 -65.930047)
			(xy 36.361593 -66.007836) (xy 36.359072 -66.011907) (xy 63.580764 -66.011907) (xy 63.580764 -65.940585)
			(xy 63.58875 -65.869711) (xy 63.60462 -65.800176) (xy 63.628177 -65.732856) (xy 63.659122 -65.668597)
			(xy 63.697068 -65.608206) (xy 63.741537 -65.552444) (xy 63.79197 -65.502011) (xy 63.847732 -65.457542)
			(xy 63.908123 -65.419596) (xy 63.972382 -65.388651) (xy 64.039702 -65.365094) (xy 64.109237 -65.349224)
			(xy 64.180111 -65.341238) (xy 64.215772 -65.340738) (xy 64.251433 -65.341238) (xy 64.322307 -65.349224)
			(xy 64.391842 -65.365094) (xy 64.459162 -65.388651) (xy 64.523421 -65.419596) (xy 64.583812 -65.457542)
			(xy 64.639574 -65.502011) (xy 64.690007 -65.552444) (xy 64.734476 -65.608206) (xy 64.772422 -65.668597)
			(xy 64.803367 -65.732856) (xy 64.826924 -65.800176) (xy 64.842794 -65.869711) (xy 64.85078 -65.940585)
			(xy 64.85078 -66.011907) (xy 66.572376 -66.011907) (xy 66.572376 -65.940585) (xy 66.580362 -65.869711)
			(xy 66.596232 -65.800176) (xy 66.619789 -65.732856) (xy 66.650734 -65.668597) (xy 66.68868 -65.608206)
			(xy 66.733149 -65.552444) (xy 66.783582 -65.502011) (xy 66.839344 -65.457542) (xy 66.899735 -65.419596)
			(xy 66.963994 -65.388651) (xy 67.031314 -65.365094) (xy 67.100849 -65.349224) (xy 67.171723 -65.341238)
			(xy 67.207384 -65.340738) (xy 67.243045 -65.341238) (xy 67.313919 -65.349224) (xy 67.383454 -65.365094)
			(xy 67.450774 -65.388651) (xy 67.515033 -65.419596) (xy 67.575424 -65.457542) (xy 67.631186 -65.502011)
			(xy 67.681619 -65.552444) (xy 67.726088 -65.608206) (xy 67.764034 -65.668597) (xy 67.794979 -65.732856)
			(xy 67.818536 -65.800176) (xy 67.834406 -65.869711) (xy 67.842392 -65.940585) (xy 67.842392 -66.011907)
			(xy 67.834406 -66.082781) (xy 67.818536 -66.152316) (xy 67.794979 -66.219636) (xy 67.764034 -66.283895)
			(xy 67.726088 -66.344286) (xy 67.681619 -66.400048) (xy 67.631186 -66.450481) (xy 67.575424 -66.49495)
			(xy 67.515033 -66.532896) (xy 67.450774 -66.563841) (xy 67.383454 -66.587398) (xy 67.313919 -66.603268)
			(xy 67.243045 -66.611254) (xy 67.171723 -66.611254) (xy 67.100849 -66.603268) (xy 67.031314 -66.587398)
			(xy 66.963994 -66.563841) (xy 66.899735 -66.532896) (xy 66.839344 -66.49495) (xy 66.783582 -66.450481)
			(xy 66.733149 -66.400048) (xy 66.68868 -66.344286) (xy 66.650734 -66.283895) (xy 66.619789 -66.219636)
			(xy 66.596232 -66.152316) (xy 66.580362 -66.082781) (xy 66.572376 -66.011907) (xy 64.85078 -66.011907)
			(xy 64.842794 -66.082781) (xy 64.826924 -66.152316) (xy 64.803367 -66.219636) (xy 64.772422 -66.283895)
			(xy 64.734476 -66.344286) (xy 64.690007 -66.400048) (xy 64.639574 -66.450481) (xy 64.583812 -66.49495)
			(xy 64.523421 -66.532896) (xy 64.459162 -66.563841) (xy 64.391842 -66.587398) (xy 64.322307 -66.603268)
			(xy 64.251433 -66.611254) (xy 64.180111 -66.611254) (xy 64.109237 -66.603268) (xy 64.039702 -66.587398)
			(xy 63.972382 -66.563841) (xy 63.908123 -66.532896) (xy 63.847732 -66.49495) (xy 63.79197 -66.450481)
			(xy 63.741537 -66.400048) (xy 63.697068 -66.344286) (xy 63.659122 -66.283895) (xy 63.628177 -66.219636)
			(xy 63.60462 -66.152316) (xy 63.58875 -66.082781) (xy 63.580764 -66.011907) (xy 36.359072 -66.011907)
			(xy 36.315846 -66.08172) (xy 36.263477 -66.151067) (xy 36.204933 -66.215287) (xy 36.140713 -66.273831)
			(xy 36.071366 -66.3262) (xy 35.997482 -66.371947) (xy 35.919693 -66.410681) (xy 35.838661 -66.442073)
			(xy 35.755079 -66.465854) (xy 35.669659 -66.481822) (xy 35.58313 -66.48984) (xy 35.49623 -66.48984)
			(xy 35.409701 -66.481822) (xy 35.324281 -66.465854) (xy 35.240699 -66.442073) (xy 35.159667 -66.410681)
			(xy 35.081878 -66.371947) (xy 35.007994 -66.3262) (xy 34.938647 -66.273831) (xy 34.874427 -66.215287)
			(xy 34.815883 -66.151067) (xy 34.763514 -66.08172) (xy 34.717767 -66.007836) (xy 34.679033 -65.930047)
			(xy 34.647641 -65.849015) (xy 34.62386 -65.765433) (xy 34.607892 -65.680013) (xy 34.599874 -65.593484)
			(xy 31.399486 -65.593484) (xy 31.391468 -65.680013) (xy 31.3755 -65.765433) (xy 31.351719 -65.849015)
			(xy 31.320327 -65.930047) (xy 31.281593 -66.007836) (xy 31.235846 -66.08172) (xy 31.183477 -66.151067)
			(xy 31.124933 -66.215287) (xy 31.060713 -66.273831) (xy 30.991366 -66.3262) (xy 30.917482 -66.371947)
			(xy 30.839693 -66.410681) (xy 30.758661 -66.442073) (xy 30.675079 -66.465854) (xy 30.589659 -66.481822)
			(xy 30.50313 -66.48984) (xy 30.41623 -66.48984) (xy 30.329701 -66.481822) (xy 30.244281 -66.465854)
			(xy 30.160699 -66.442073) (xy 30.079667 -66.410681) (xy 30.001878 -66.371947) (xy 29.927994 -66.3262)
			(xy 29.858647 -66.273831) (xy 29.794427 -66.215287) (xy 29.735883 -66.151067) (xy 29.683514 -66.08172)
			(xy 29.637767 -66.007836) (xy 29.599033 -65.930047) (xy 29.567641 -65.849015) (xy 29.54386 -65.765433)
			(xy 29.527892 -65.680013) (xy 29.519874 -65.593484) (xy 19.678396 -65.593484) (xy 19.678396 -68.133484)
			(xy 29.519874 -68.133484) (xy 29.519874 -68.046584) (xy 29.527892 -67.960055) (xy 29.54386 -67.874635)
			(xy 29.567641 -67.791053) (xy 29.599033 -67.710021) (xy 29.637767 -67.632232) (xy 29.683514 -67.558348)
			(xy 29.735883 -67.489001) (xy 29.794427 -67.424781) (xy 29.858647 -67.366237) (xy 29.927994 -67.313868)
			(xy 30.001878 -67.268121) (xy 30.079667 -67.229387) (xy 30.160699 -67.197995) (xy 30.244281 -67.174214)
			(xy 30.329701 -67.158246) (xy 30.41623 -67.150228) (xy 30.45968 -67.149726) (xy 30.50313 -67.150228)
			(xy 30.589659 -67.158246) (xy 30.675079 -67.174214) (xy 30.758661 -67.197995) (xy 30.839693 -67.229387)
			(xy 30.917482 -67.268121) (xy 30.991366 -67.313868) (xy 31.060713 -67.366237) (xy 31.124933 -67.424781)
			(xy 31.183477 -67.489001) (xy 31.235846 -67.558348) (xy 31.281593 -67.632232) (xy 31.320327 -67.710021)
			(xy 31.351719 -67.791053) (xy 31.3755 -67.874635) (xy 31.391468 -67.960055) (xy 31.399486 -68.046584)
			(xy 31.399486 -68.133484) (xy 34.599874 -68.133484) (xy 34.599874 -68.046584) (xy 34.607892 -67.960055)
			(xy 34.62386 -67.874635) (xy 34.647641 -67.791053) (xy 34.679033 -67.710021) (xy 34.717767 -67.632232)
			(xy 34.763514 -67.558348) (xy 34.815883 -67.489001) (xy 34.874427 -67.424781) (xy 34.938647 -67.366237)
			(xy 35.007994 -67.313868) (xy 35.081878 -67.268121) (xy 35.159667 -67.229387) (xy 35.240699 -67.197995)
			(xy 35.324281 -67.174214) (xy 35.409701 -67.158246) (xy 35.49623 -67.150228) (xy 35.53968 -67.149726)
			(xy 35.58313 -67.150228) (xy 35.669659 -67.158246) (xy 35.755079 -67.174214) (xy 35.838661 -67.197995)
			(xy 35.919693 -67.229387) (xy 35.997482 -67.268121) (xy 36.071366 -67.313868) (xy 36.140713 -67.366237)
			(xy 36.204933 -67.424781) (xy 36.263477 -67.489001) (xy 36.305421 -67.544543) (xy 41.522642 -67.544543)
			(xy 41.522642 -67.473221) (xy 41.530628 -67.402347) (xy 41.546498 -67.332812) (xy 41.570055 -67.265492)
			(xy 41.601 -67.201233) (xy 41.638946 -67.140842) (xy 41.683415 -67.08508) (xy 41.733848 -67.034647)
			(xy 41.78961 -66.990178) (xy 41.850001 -66.952232) (xy 41.91426 -66.921287) (xy 41.98158 -66.89773)
			(xy 42.051115 -66.88186) (xy 42.121989 -66.873874) (xy 42.15765 -66.873374) (xy 42.193311 -66.873874)
			(xy 42.264185 -66.88186) (xy 42.33372 -66.89773) (xy 42.40104 -66.921287) (xy 42.465299 -66.952232)
			(xy 42.52569 -66.990178) (xy 42.581452 -67.034647) (xy 42.631885 -67.08508) (xy 42.676354 -67.140842)
			(xy 42.7143 -67.201233) (xy 42.745245 -67.265492) (xy 42.768802 -67.332812) (xy 42.784672 -67.402347)
			(xy 42.792658 -67.473221) (xy 42.792658 -67.544543) (xy 42.784672 -67.615417) (xy 42.768802 -67.684952)
			(xy 42.745245 -67.752272) (xy 42.7143 -67.816531) (xy 42.676354 -67.876922) (xy 42.631885 -67.932684)
			(xy 42.581452 -67.983117) (xy 42.52569 -68.027586) (xy 42.465299 -68.065532) (xy 42.40104 -68.096477)
			(xy 42.33372 -68.120034) (xy 42.264185 -68.135904) (xy 42.193311 -68.14389) (xy 42.121989 -68.14389)
			(xy 42.051115 -68.135904) (xy 41.98158 -68.120034) (xy 41.91426 -68.096477) (xy 41.850001 -68.065532)
			(xy 41.78961 -68.027586) (xy 41.733848 -67.983117) (xy 41.683415 -67.932684) (xy 41.638946 -67.876922)
			(xy 41.601 -67.816531) (xy 41.570055 -67.752272) (xy 41.546498 -67.684952) (xy 41.530628 -67.615417)
			(xy 41.522642 -67.544543) (xy 36.305421 -67.544543) (xy 36.315846 -67.558348) (xy 36.361593 -67.632232)
			(xy 36.400327 -67.710021) (xy 36.431719 -67.791053) (xy 36.4555 -67.874635) (xy 36.471468 -67.960055)
			(xy 36.479486 -68.046584) (xy 36.479486 -68.133484) (xy 36.477454 -68.155413) (xy 63.580764 -68.155413)
			(xy 63.580764 -68.084091) (xy 63.58875 -68.013217) (xy 63.60462 -67.943682) (xy 63.628177 -67.876362)
			(xy 63.659122 -67.812103) (xy 63.697068 -67.751712) (xy 63.741537 -67.69595) (xy 63.79197 -67.645517)
			(xy 63.847732 -67.601048) (xy 63.908123 -67.563102) (xy 63.972382 -67.532157) (xy 64.039702 -67.5086)
			(xy 64.109237 -67.49273) (xy 64.180111 -67.484744) (xy 64.215772 -67.484244) (xy 64.251433 -67.484744)
			(xy 64.322307 -67.49273) (xy 64.391842 -67.5086) (xy 64.459162 -67.532157) (xy 64.523421 -67.563102)
			(xy 64.583812 -67.601048) (xy 64.639574 -67.645517) (xy 64.690007 -67.69595) (xy 64.734476 -67.751712)
			(xy 64.772422 -67.812103) (xy 64.803367 -67.876362) (xy 64.826924 -67.943682) (xy 64.842794 -68.013217)
			(xy 64.85078 -68.084091) (xy 64.85078 -68.155413) (xy 66.572376 -68.155413) (xy 66.572376 -68.084091)
			(xy 66.580362 -68.013217) (xy 66.596232 -67.943682) (xy 66.619789 -67.876362) (xy 66.650734 -67.812103)
			(xy 66.68868 -67.751712) (xy 66.733149 -67.69595) (xy 66.783582 -67.645517) (xy 66.839344 -67.601048)
			(xy 66.899735 -67.563102) (xy 66.963994 -67.532157) (xy 67.031314 -67.5086) (xy 67.100849 -67.49273)
			(xy 67.171723 -67.484744) (xy 67.207384 -67.484244) (xy 67.243045 -67.484744) (xy 67.313919 -67.49273)
			(xy 67.383454 -67.5086) (xy 67.450774 -67.532157) (xy 67.515033 -67.563102) (xy 67.575424 -67.601048)
			(xy 67.631186 -67.645517) (xy 67.681619 -67.69595) (xy 67.726088 -67.751712) (xy 67.764034 -67.812103)
			(xy 67.794979 -67.876362) (xy 67.818536 -67.943682) (xy 67.834406 -68.013217) (xy 67.842392 -68.084091)
			(xy 67.842392 -68.155413) (xy 67.834406 -68.226287) (xy 67.818536 -68.295822) (xy 67.794979 -68.363142)
			(xy 67.764034 -68.427401) (xy 67.726088 -68.487792) (xy 67.681619 -68.543554) (xy 67.631186 -68.593987)
			(xy 67.575424 -68.638456) (xy 67.515033 -68.676402) (xy 67.450774 -68.707347) (xy 67.383454 -68.730904)
			(xy 67.313919 -68.746774) (xy 67.243045 -68.75476) (xy 67.171723 -68.75476) (xy 67.100849 -68.746774)
			(xy 67.031314 -68.730904) (xy 66.963994 -68.707347) (xy 66.899735 -68.676402) (xy 66.839344 -68.638456)
			(xy 66.783582 -68.593987) (xy 66.733149 -68.543554) (xy 66.68868 -68.487792) (xy 66.650734 -68.427401)
			(xy 66.619789 -68.363142) (xy 66.596232 -68.295822) (xy 66.580362 -68.226287) (xy 66.572376 -68.155413)
			(xy 64.85078 -68.155413) (xy 64.842794 -68.226287) (xy 64.826924 -68.295822) (xy 64.803367 -68.363142)
			(xy 64.772422 -68.427401) (xy 64.734476 -68.487792) (xy 64.690007 -68.543554) (xy 64.639574 -68.593987)
			(xy 64.583812 -68.638456) (xy 64.523421 -68.676402) (xy 64.459162 -68.707347) (xy 64.391842 -68.730904)
			(xy 64.322307 -68.746774) (xy 64.251433 -68.75476) (xy 64.180111 -68.75476) (xy 64.109237 -68.746774)
			(xy 64.039702 -68.730904) (xy 63.972382 -68.707347) (xy 63.908123 -68.676402) (xy 63.847732 -68.638456)
			(xy 63.79197 -68.593987) (xy 63.741537 -68.543554) (xy 63.697068 -68.487792) (xy 63.659122 -68.427401)
			(xy 63.628177 -68.363142) (xy 63.60462 -68.295822) (xy 63.58875 -68.226287) (xy 63.580764 -68.155413)
			(xy 36.477454 -68.155413) (xy 36.471468 -68.220013) (xy 36.4555 -68.305433) (xy 36.431719 -68.389015)
			(xy 36.400327 -68.470047) (xy 36.361593 -68.547836) (xy 36.315846 -68.62172) (xy 36.263477 -68.691067)
			(xy 36.204933 -68.755287) (xy 36.140713 -68.813831) (xy 36.071366 -68.8662) (xy 35.997482 -68.911947)
			(xy 35.919693 -68.950681) (xy 35.838661 -68.982073) (xy 35.755079 -69.005854) (xy 35.669659 -69.021822)
			(xy 35.58313 -69.02984) (xy 35.49623 -69.02984) (xy 35.409701 -69.021822) (xy 35.324281 -69.005854)
			(xy 35.240699 -68.982073) (xy 35.159667 -68.950681) (xy 35.081878 -68.911947) (xy 35.007994 -68.8662)
			(xy 34.938647 -68.813831) (xy 34.874427 -68.755287) (xy 34.815883 -68.691067) (xy 34.763514 -68.62172)
			(xy 34.717767 -68.547836) (xy 34.679033 -68.470047) (xy 34.647641 -68.389015) (xy 34.62386 -68.305433)
			(xy 34.607892 -68.220013) (xy 34.599874 -68.133484) (xy 31.399486 -68.133484) (xy 31.391468 -68.220013)
			(xy 31.3755 -68.305433) (xy 31.351719 -68.389015) (xy 31.320327 -68.470047) (xy 31.281593 -68.547836)
			(xy 31.235846 -68.62172) (xy 31.183477 -68.691067) (xy 31.124933 -68.755287) (xy 31.060713 -68.813831)
			(xy 30.991366 -68.8662) (xy 30.917482 -68.911947) (xy 30.839693 -68.950681) (xy 30.758661 -68.982073)
			(xy 30.675079 -69.005854) (xy 30.589659 -69.021822) (xy 30.50313 -69.02984) (xy 30.41623 -69.02984)
			(xy 30.329701 -69.021822) (xy 30.244281 -69.005854) (xy 30.160699 -68.982073) (xy 30.079667 -68.950681)
			(xy 30.001878 -68.911947) (xy 29.927994 -68.8662) (xy 29.858647 -68.813831) (xy 29.794427 -68.755287)
			(xy 29.735883 -68.691067) (xy 29.683514 -68.62172) (xy 29.637767 -68.547836) (xy 29.599033 -68.470047)
			(xy 29.567641 -68.389015) (xy 29.54386 -68.305433) (xy 29.527892 -68.220013) (xy 29.519874 -68.133484)
			(xy 19.678396 -68.133484) (xy 19.678396 -70.673484) (xy 29.519874 -70.673484) (xy 29.519874 -70.586584)
			(xy 29.527892 -70.500055) (xy 29.54386 -70.414635) (xy 29.567641 -70.331053) (xy 29.599033 -70.250021)
			(xy 29.637767 -70.172232) (xy 29.683514 -70.098348) (xy 29.735883 -70.029001) (xy 29.794427 -69.964781)
			(xy 29.858647 -69.906237) (xy 29.927994 -69.853868) (xy 30.001878 -69.808121) (xy 30.079667 -69.769387)
			(xy 30.160699 -69.737995) (xy 30.244281 -69.714214) (xy 30.329701 -69.698246) (xy 30.41623 -69.690228)
			(xy 30.45968 -69.689726) (xy 30.50313 -69.690228) (xy 30.589659 -69.698246) (xy 30.675079 -69.714214)
			(xy 30.758661 -69.737995) (xy 30.839693 -69.769387) (xy 30.917482 -69.808121) (xy 30.991366 -69.853868)
			(xy 31.060713 -69.906237) (xy 31.124933 -69.964781) (xy 31.183477 -70.029001) (xy 31.235846 -70.098348)
			(xy 31.281593 -70.172232) (xy 31.320327 -70.250021) (xy 31.351719 -70.331053) (xy 31.3755 -70.414635)
			(xy 31.391468 -70.500055) (xy 31.399486 -70.586584) (xy 31.399486 -70.673484) (xy 34.599874 -70.673484)
			(xy 34.599874 -70.586584) (xy 34.607892 -70.500055) (xy 34.62386 -70.414635) (xy 34.647641 -70.331053)
			(xy 34.679033 -70.250021) (xy 34.717767 -70.172232) (xy 34.763514 -70.098348) (xy 34.815883 -70.029001)
			(xy 34.874427 -69.964781) (xy 34.938647 -69.906237) (xy 35.007994 -69.853868) (xy 35.081878 -69.808121)
			(xy 35.159667 -69.769387) (xy 35.240699 -69.737995) (xy 35.324281 -69.714214) (xy 35.409701 -69.698246)
			(xy 35.49623 -69.690228) (xy 35.53968 -69.689726) (xy 35.58313 -69.690228) (xy 35.669659 -69.698246)
			(xy 35.755079 -69.714214) (xy 35.838661 -69.737995) (xy 35.919693 -69.769387) (xy 35.997482 -69.808121)
			(xy 36.071366 -69.853868) (xy 36.140713 -69.906237) (xy 36.204933 -69.964781) (xy 36.263477 -70.029001)
			(xy 36.315846 -70.098348) (xy 36.361593 -70.172232) (xy 36.383065 -70.215353) (xy 41.522642 -70.215353)
			(xy 41.522642 -70.144031) (xy 41.530628 -70.073157) (xy 41.546498 -70.003622) (xy 41.570055 -69.936302)
			(xy 41.601 -69.872043) (xy 41.638946 -69.811652) (xy 41.683415 -69.75589) (xy 41.733848 -69.705457)
			(xy 41.78961 -69.660988) (xy 41.850001 -69.623042) (xy 41.91426 -69.592097) (xy 41.98158 -69.56854)
			(xy 42.051115 -69.55267) (xy 42.121989 -69.544684) (xy 42.15765 -69.544184) (xy 42.193311 -69.544684)
			(xy 42.264185 -69.55267) (xy 42.33372 -69.56854) (xy 42.40104 -69.592097) (xy 42.465299 -69.623042)
			(xy 42.52569 -69.660988) (xy 42.581452 -69.705457) (xy 42.631885 -69.75589) (xy 42.676354 -69.811652)
			(xy 42.7143 -69.872043) (xy 42.745245 -69.936302) (xy 42.768802 -70.003622) (xy 42.784672 -70.073157)
			(xy 42.792658 -70.144031) (xy 42.792658 -70.215353) (xy 42.784672 -70.286227) (xy 42.768802 -70.355762)
			(xy 42.745245 -70.423082) (xy 42.7143 -70.487341) (xy 42.676354 -70.547732) (xy 42.631885 -70.603494)
			(xy 42.581452 -70.653927) (xy 42.52569 -70.698396) (xy 42.465299 -70.736342) (xy 42.40104 -70.767287)
			(xy 42.33372 -70.790844) (xy 42.264185 -70.806714) (xy 42.193311 -70.8147) (xy 42.121989 -70.8147)
			(xy 42.051115 -70.806714) (xy 41.98158 -70.790844) (xy 41.91426 -70.767287) (xy 41.850001 -70.736342)
			(xy 41.78961 -70.698396) (xy 41.733848 -70.653927) (xy 41.683415 -70.603494) (xy 41.638946 -70.547732)
			(xy 41.601 -70.487341) (xy 41.570055 -70.423082) (xy 41.546498 -70.355762) (xy 41.530628 -70.286227)
			(xy 41.522642 -70.215353) (xy 36.383065 -70.215353) (xy 36.400327 -70.250021) (xy 36.431719 -70.331053)
			(xy 36.4555 -70.414635) (xy 36.471468 -70.500055) (xy 36.479486 -70.586584) (xy 36.479486 -70.673484)
			(xy 36.471468 -70.760013) (xy 36.4555 -70.845433) (xy 36.431719 -70.929015) (xy 36.400327 -71.010047)
			(xy 36.361593 -71.087836) (xy 36.315846 -71.16172) (xy 36.263477 -71.231067) (xy 36.204933 -71.295287)
			(xy 36.140713 -71.353831) (xy 36.071366 -71.4062) (xy 35.997482 -71.451947) (xy 35.919693 -71.490681)
			(xy 35.838661 -71.522073) (xy 35.755079 -71.545854) (xy 35.669659 -71.561822) (xy 35.58313 -71.56984)
			(xy 35.49623 -71.56984) (xy 35.409701 -71.561822) (xy 35.324281 -71.545854) (xy 35.240699 -71.522073)
			(xy 35.159667 -71.490681) (xy 35.081878 -71.451947) (xy 35.007994 -71.4062) (xy 34.938647 -71.353831)
			(xy 34.874427 -71.295287) (xy 34.815883 -71.231067) (xy 34.763514 -71.16172) (xy 34.717767 -71.087836)
			(xy 34.679033 -71.010047) (xy 34.647641 -70.929015) (xy 34.62386 -70.845433) (xy 34.607892 -70.760013)
			(xy 34.599874 -70.673484) (xy 31.399486 -70.673484) (xy 31.391468 -70.760013) (xy 31.3755 -70.845433)
			(xy 31.351719 -70.929015) (xy 31.320327 -71.010047) (xy 31.281593 -71.087836) (xy 31.235846 -71.16172)
			(xy 31.183477 -71.231067) (xy 31.124933 -71.295287) (xy 31.060713 -71.353831) (xy 30.991366 -71.4062)
			(xy 30.917482 -71.451947) (xy 30.839693 -71.490681) (xy 30.758661 -71.522073) (xy 30.675079 -71.545854)
			(xy 30.589659 -71.561822) (xy 30.50313 -71.56984) (xy 30.41623 -71.56984) (xy 30.329701 -71.561822)
			(xy 30.244281 -71.545854) (xy 30.160699 -71.522073) (xy 30.079667 -71.490681) (xy 30.001878 -71.451947)
			(xy 29.927994 -71.4062) (xy 29.858647 -71.353831) (xy 29.794427 -71.295287) (xy 29.735883 -71.231067)
			(xy 29.683514 -71.16172) (xy 29.637767 -71.087836) (xy 29.599033 -71.010047) (xy 29.567641 -70.929015)
			(xy 29.54386 -70.845433) (xy 29.527892 -70.760013) (xy 29.519874 -70.673484) (xy 19.678396 -70.673484)
			(xy 19.678396 -72.524366) (xy 18.989278 -73.213484) (xy 29.519874 -73.213484) (xy 29.519874 -73.126584)
			(xy 29.527892 -73.040055) (xy 29.54386 -72.954635) (xy 29.567641 -72.871053) (xy 29.599033 -72.790021)
			(xy 29.637767 -72.712232) (xy 29.683514 -72.638348) (xy 29.735883 -72.569001) (xy 29.794427 -72.504781)
			(xy 29.858647 -72.446237) (xy 29.927994 -72.393868) (xy 30.001878 -72.348121) (xy 30.079667 -72.309387)
			(xy 30.160699 -72.277995) (xy 30.244281 -72.254214) (xy 30.329701 -72.238246) (xy 30.41623 -72.230228)
			(xy 30.45968 -72.229726) (xy 30.50313 -72.230228) (xy 30.589659 -72.238246) (xy 30.675079 -72.254214)
			(xy 30.758661 -72.277995) (xy 30.839693 -72.309387) (xy 30.917482 -72.348121) (xy 30.991366 -72.393868)
			(xy 31.060713 -72.446237) (xy 31.124933 -72.504781) (xy 31.183477 -72.569001) (xy 31.235846 -72.638348)
			(xy 31.281593 -72.712232) (xy 31.320327 -72.790021) (xy 31.351719 -72.871053) (xy 31.3755 -72.954635)
			(xy 31.391468 -73.040055) (xy 31.399486 -73.126584) (xy 31.399486 -73.213484) (xy 34.599874 -73.213484)
			(xy 34.599874 -73.126584) (xy 34.607892 -73.040055) (xy 34.62386 -72.954635) (xy 34.647641 -72.871053)
			(xy 34.679033 -72.790021) (xy 34.717767 -72.712232) (xy 34.763514 -72.638348) (xy 34.815883 -72.569001)
			(xy 34.874427 -72.504781) (xy 34.938647 -72.446237) (xy 35.007994 -72.393868) (xy 35.081878 -72.348121)
			(xy 35.159667 -72.309387) (xy 35.240699 -72.277995) (xy 35.324281 -72.254214) (xy 35.409701 -72.238246)
			(xy 35.49623 -72.230228) (xy 35.53968 -72.229726) (xy 35.58313 -72.230228) (xy 35.669659 -72.238246)
			(xy 35.755079 -72.254214) (xy 35.838661 -72.277995) (xy 35.919693 -72.309387) (xy 35.997482 -72.348121)
			(xy 36.071366 -72.393868) (xy 36.140713 -72.446237) (xy 36.204933 -72.504781) (xy 36.263477 -72.569001)
			(xy 36.315846 -72.638348) (xy 36.361593 -72.712232) (xy 36.400327 -72.790021) (xy 36.431719 -72.871053)
			(xy 36.435295 -72.883623) (xy 41.522642 -72.883623) (xy 41.522642 -72.812301) (xy 41.530628 -72.741427)
			(xy 41.546498 -72.671892) (xy 41.570055 -72.604572) (xy 41.601 -72.540313) (xy 41.638946 -72.479922)
			(xy 41.683415 -72.42416) (xy 41.733848 -72.373727) (xy 41.78961 -72.329258) (xy 41.850001 -72.291312)
			(xy 41.91426 -72.260367) (xy 41.98158 -72.23681) (xy 42.051115 -72.22094) (xy 42.121989 -72.212954)
			(xy 42.15765 -72.212454) (xy 42.193311 -72.212954) (xy 42.264185 -72.22094) (xy 42.33372 -72.23681)
			(xy 42.40104 -72.260367) (xy 42.465299 -72.291312) (xy 42.52569 -72.329258) (xy 42.581452 -72.373727)
			(xy 42.631885 -72.42416) (xy 42.676354 -72.479922) (xy 42.7143 -72.540313) (xy 42.745245 -72.604572)
			(xy 42.768802 -72.671892) (xy 42.784672 -72.741427) (xy 42.792658 -72.812301) (xy 42.792658 -72.883623)
			(xy 42.784672 -72.954497) (xy 42.768802 -73.024032) (xy 42.745245 -73.091352) (xy 42.7143 -73.155611)
			(xy 42.676354 -73.216002) (xy 42.631885 -73.271764) (xy 42.581452 -73.322197) (xy 42.52569 -73.366666)
			(xy 42.465299 -73.404612) (xy 42.40104 -73.435557) (xy 42.33372 -73.459114) (xy 42.264185 -73.474984)
			(xy 42.193311 -73.48297) (xy 42.121989 -73.48297) (xy 42.051115 -73.474984) (xy 41.98158 -73.459114)
			(xy 41.91426 -73.435557) (xy 41.850001 -73.404612) (xy 41.78961 -73.366666) (xy 41.733848 -73.322197)
			(xy 41.683415 -73.271764) (xy 41.638946 -73.216002) (xy 41.601 -73.155611) (xy 41.570055 -73.091352)
			(xy 41.546498 -73.024032) (xy 41.530628 -72.954497) (xy 41.522642 -72.883623) (xy 36.435295 -72.883623)
			(xy 36.4555 -72.954635) (xy 36.471468 -73.040055) (xy 36.479486 -73.126584) (xy 36.479486 -73.213484)
			(xy 36.471468 -73.300013) (xy 36.4555 -73.385433) (xy 36.431719 -73.469015) (xy 36.400327 -73.550047)
			(xy 36.361593 -73.627836) (xy 36.315846 -73.70172) (xy 36.263477 -73.771067) (xy 36.204933 -73.835287)
			(xy 36.140713 -73.893831) (xy 36.071366 -73.9462) (xy 35.997482 -73.991947) (xy 35.919693 -74.030681)
			(xy 35.838661 -74.062073) (xy 35.755079 -74.085854) (xy 35.669659 -74.101822) (xy 35.58313 -74.10984)
			(xy 35.49623 -74.10984) (xy 35.409701 -74.101822) (xy 35.324281 -74.085854) (xy 35.240699 -74.062073)
			(xy 35.159667 -74.030681) (xy 35.081878 -73.991947) (xy 35.007994 -73.9462) (xy 34.938647 -73.893831)
			(xy 34.874427 -73.835287) (xy 34.815883 -73.771067) (xy 34.763514 -73.70172) (xy 34.717767 -73.627836)
			(xy 34.679033 -73.550047) (xy 34.647641 -73.469015) (xy 34.62386 -73.385433) (xy 34.607892 -73.300013)
			(xy 34.599874 -73.213484) (xy 31.399486 -73.213484) (xy 31.391468 -73.300013) (xy 31.3755 -73.385433)
			(xy 31.351719 -73.469015) (xy 31.320327 -73.550047) (xy 31.281593 -73.627836) (xy 31.235846 -73.70172)
			(xy 31.183477 -73.771067) (xy 31.124933 -73.835287) (xy 31.060713 -73.893831) (xy 30.991366 -73.9462)
			(xy 30.917482 -73.991947) (xy 30.839693 -74.030681) (xy 30.758661 -74.062073) (xy 30.675079 -74.085854)
			(xy 30.589659 -74.101822) (xy 30.50313 -74.10984) (xy 30.41623 -74.10984) (xy 30.329701 -74.101822)
			(xy 30.244281 -74.085854) (xy 30.160699 -74.062073) (xy 30.079667 -74.030681) (xy 30.001878 -73.991947)
			(xy 29.927994 -73.9462) (xy 29.858647 -73.893831) (xy 29.794427 -73.835287) (xy 29.735883 -73.771067)
			(xy 29.683514 -73.70172) (xy 29.637767 -73.627836) (xy 29.599033 -73.550047) (xy 29.567641 -73.469015)
			(xy 29.54386 -73.385433) (xy 29.527892 -73.300013) (xy 29.519874 -73.213484) (xy 18.989278 -73.213484)
			(xy 16.449278 -75.753484) (xy 29.519874 -75.753484) (xy 29.519874 -75.666584) (xy 29.527892 -75.580055)
			(xy 29.54386 -75.494635) (xy 29.567641 -75.411053) (xy 29.599033 -75.330021) (xy 29.637767 -75.252232)
			(xy 29.683514 -75.178348) (xy 29.735883 -75.109001) (xy 29.794427 -75.044781) (xy 29.858647 -74.986237)
			(xy 29.927994 -74.933868) (xy 30.001878 -74.888121) (xy 30.079667 -74.849387) (xy 30.160699 -74.817995)
			(xy 30.244281 -74.794214) (xy 30.329701 -74.778246) (xy 30.41623 -74.770228) (xy 30.45968 -74.769726)
			(xy 30.50313 -74.770228) (xy 30.589659 -74.778246) (xy 30.675079 -74.794214) (xy 30.758661 -74.817995)
			(xy 30.839693 -74.849387) (xy 30.917482 -74.888121) (xy 30.991366 -74.933868) (xy 31.060713 -74.986237)
			(xy 31.124933 -75.044781) (xy 31.183477 -75.109001) (xy 31.235846 -75.178348) (xy 31.281593 -75.252232)
			(xy 31.320327 -75.330021) (xy 31.351719 -75.411053) (xy 31.3755 -75.494635) (xy 31.391468 -75.580055)
			(xy 31.399486 -75.666584) (xy 31.399486 -75.753484) (xy 34.599874 -75.753484) (xy 34.599874 -75.666584)
			(xy 34.607892 -75.580055) (xy 34.62386 -75.494635) (xy 34.647641 -75.411053) (xy 34.679033 -75.330021)
			(xy 34.717767 -75.252232) (xy 34.763514 -75.178348) (xy 34.815883 -75.109001) (xy 34.874427 -75.044781)
			(xy 34.938647 -74.986237) (xy 35.007994 -74.933868) (xy 35.081878 -74.888121) (xy 35.159667 -74.849387)
			(xy 35.240699 -74.817995) (xy 35.324281 -74.794214) (xy 35.409701 -74.778246) (xy 35.49623 -74.770228)
			(xy 35.53968 -74.769726) (xy 35.58313 -74.770228) (xy 35.669659 -74.778246) (xy 35.755079 -74.794214)
			(xy 35.838661 -74.817995) (xy 35.919693 -74.849387) (xy 35.997482 -74.888121) (xy 36.071366 -74.933868)
			(xy 36.140713 -74.986237) (xy 36.204933 -75.044781) (xy 36.263477 -75.109001) (xy 36.315846 -75.178348)
			(xy 36.361593 -75.252232) (xy 36.363081 -75.255221) (xy 41.522642 -75.255221) (xy 41.522642 -75.183899)
			(xy 41.530628 -75.113025) (xy 41.546498 -75.04349) (xy 41.570055 -74.97617) (xy 41.601 -74.911911)
			(xy 41.638946 -74.85152) (xy 41.683415 -74.795758) (xy 41.733848 -74.745325) (xy 41.78961 -74.700856)
			(xy 41.850001 -74.66291) (xy 41.91426 -74.631965) (xy 41.98158 -74.608408) (xy 42.051115 -74.592538)
			(xy 42.121989 -74.584552) (xy 42.15765 -74.584052) (xy 42.193311 -74.584552) (xy 42.264185 -74.592538)
			(xy 42.33372 -74.608408) (xy 42.40104 -74.631965) (xy 42.465299 -74.66291) (xy 42.52569 -74.700856)
			(xy 42.581452 -74.745325) (xy 42.631885 -74.795758) (xy 42.676354 -74.85152) (xy 42.7143 -74.911911)
			(xy 42.745245 -74.97617) (xy 42.768802 -75.04349) (xy 42.784672 -75.113025) (xy 42.792658 -75.183899)
			(xy 42.792658 -75.255221) (xy 42.784672 -75.326095) (xy 42.768802 -75.39563) (xy 42.745245 -75.46295)
			(xy 42.7143 -75.527209) (xy 42.676354 -75.5876) (xy 42.631885 -75.643362) (xy 42.581452 -75.693795)
			(xy 42.52569 -75.738264) (xy 42.465299 -75.77621) (xy 42.40104 -75.807155) (xy 42.33372 -75.830712)
			(xy 42.264185 -75.846582) (xy 42.193311 -75.854568) (xy 42.121989 -75.854568) (xy 42.051115 -75.846582)
			(xy 41.98158 -75.830712) (xy 41.91426 -75.807155) (xy 41.850001 -75.77621) (xy 41.78961 -75.738264)
			(xy 41.733848 -75.693795) (xy 41.683415 -75.643362) (xy 41.638946 -75.5876) (xy 41.601 -75.527209)
			(xy 41.570055 -75.46295) (xy 41.546498 -75.39563) (xy 41.530628 -75.326095) (xy 41.522642 -75.255221)
			(xy 36.363081 -75.255221) (xy 36.400327 -75.330021) (xy 36.431719 -75.411053) (xy 36.4555 -75.494635)
			(xy 36.471468 -75.580055) (xy 36.479486 -75.666584) (xy 36.479486 -75.753484) (xy 36.471468 -75.840013)
			(xy 36.4555 -75.925433) (xy 36.431719 -76.009015) (xy 36.400327 -76.090047) (xy 36.361593 -76.167836)
			(xy 36.315846 -76.24172) (xy 36.263477 -76.311067) (xy 36.204933 -76.375287) (xy 36.140713 -76.433831)
			(xy 36.071366 -76.4862) (xy 35.997482 -76.531947) (xy 35.919693 -76.570681) (xy 35.838661 -76.602073)
			(xy 35.755079 -76.625854) (xy 35.669659 -76.641822) (xy 35.58313 -76.64984) (xy 35.49623 -76.64984)
			(xy 35.409701 -76.641822) (xy 35.324281 -76.625854) (xy 35.240699 -76.602073) (xy 35.159667 -76.570681)
			(xy 35.081878 -76.531947) (xy 35.007994 -76.4862) (xy 34.938647 -76.433831) (xy 34.874427 -76.375287)
			(xy 34.815883 -76.311067) (xy 34.763514 -76.24172) (xy 34.717767 -76.167836) (xy 34.679033 -76.090047)
			(xy 34.647641 -76.009015) (xy 34.62386 -75.925433) (xy 34.607892 -75.840013) (xy 34.599874 -75.753484)
			(xy 31.399486 -75.753484) (xy 31.391468 -75.840013) (xy 31.3755 -75.925433) (xy 31.351719 -76.009015)
			(xy 31.320327 -76.090047) (xy 31.281593 -76.167836) (xy 31.235846 -76.24172) (xy 31.183477 -76.311067)
			(xy 31.124933 -76.375287) (xy 31.060713 -76.433831) (xy 30.991366 -76.4862) (xy 30.917482 -76.531947)
			(xy 30.839693 -76.570681) (xy 30.758661 -76.602073) (xy 30.675079 -76.625854) (xy 30.589659 -76.641822)
			(xy 30.50313 -76.64984) (xy 30.41623 -76.64984) (xy 30.329701 -76.641822) (xy 30.244281 -76.625854)
			(xy 30.160699 -76.602073) (xy 30.079667 -76.570681) (xy 30.001878 -76.531947) (xy 29.927994 -76.4862)
			(xy 29.858647 -76.433831) (xy 29.794427 -76.375287) (xy 29.735883 -76.311067) (xy 29.683514 -76.24172)
			(xy 29.637767 -76.167836) (xy 29.599033 -76.090047) (xy 29.567641 -76.009015) (xy 29.54386 -75.925433)
			(xy 29.527892 -75.840013) (xy 29.519874 -75.753484) (xy 16.449278 -75.753484) (xy 14.984629 -77.218133)
			(xy 41.522642 -77.218133) (xy 41.522642 -77.146811) (xy 41.530628 -77.075937) (xy 41.546498 -77.006402)
			(xy 41.570055 -76.939082) (xy 41.601 -76.874823) (xy 41.638946 -76.814432) (xy 41.683415 -76.75867)
			(xy 41.733848 -76.708237) (xy 41.78961 -76.663768) (xy 41.850001 -76.625822) (xy 41.91426 -76.594877)
			(xy 41.98158 -76.57132) (xy 42.051115 -76.55545) (xy 42.121989 -76.547464) (xy 42.15765 -76.546964)
			(xy 42.193311 -76.547464) (xy 42.264185 -76.55545) (xy 42.33372 -76.57132) (xy 42.40104 -76.594877)
			(xy 42.465299 -76.625822) (xy 42.52569 -76.663768) (xy 42.581452 -76.708237) (xy 42.631885 -76.75867)
			(xy 42.676354 -76.814432) (xy 42.7143 -76.874823) (xy 42.745245 -76.939082) (xy 42.768802 -77.006402)
			(xy 42.784672 -77.075937) (xy 42.792658 -77.146811) (xy 42.792658 -77.218133) (xy 42.784672 -77.289007)
			(xy 42.768802 -77.358542) (xy 42.745245 -77.425862) (xy 42.7143 -77.490121) (xy 42.676354 -77.550512)
			(xy 42.631885 -77.606274) (xy 42.581452 -77.656707) (xy 42.52569 -77.701176) (xy 42.465299 -77.739122)
			(xy 42.40104 -77.770067) (xy 42.33372 -77.793624) (xy 42.264185 -77.809494) (xy 42.193311 -77.81748)
			(xy 42.121989 -77.81748) (xy 42.051115 -77.809494) (xy 41.98158 -77.793624) (xy 41.91426 -77.770067)
			(xy 41.850001 -77.739122) (xy 41.78961 -77.701176) (xy 41.733848 -77.656707) (xy 41.683415 -77.606274)
			(xy 41.638946 -77.550512) (xy 41.601 -77.490121) (xy 41.570055 -77.425862) (xy 41.546498 -77.358542)
			(xy 41.530628 -77.289007) (xy 41.522642 -77.218133) (xy 14.984629 -77.218133) (xy 13.909278 -78.293484)
			(xy 29.519874 -78.293484) (xy 29.519874 -78.206584) (xy 29.527892 -78.120055) (xy 29.54386 -78.034635)
			(xy 29.567641 -77.951053) (xy 29.599033 -77.870021) (xy 29.637767 -77.792232) (xy 29.683514 -77.718348)
			(xy 29.735883 -77.649001) (xy 29.794427 -77.584781) (xy 29.858647 -77.526237) (xy 29.927994 -77.473868)
			(xy 30.001878 -77.428121) (xy 30.079667 -77.389387) (xy 30.160699 -77.357995) (xy 30.244281 -77.334214)
			(xy 30.329701 -77.318246) (xy 30.41623 -77.310228) (xy 30.45968 -77.309726) (xy 30.50313 -77.310228)
			(xy 30.589659 -77.318246) (xy 30.675079 -77.334214) (xy 30.758661 -77.357995) (xy 30.839693 -77.389387)
			(xy 30.917482 -77.428121) (xy 30.991366 -77.473868) (xy 31.060713 -77.526237) (xy 31.124933 -77.584781)
			(xy 31.183477 -77.649001) (xy 31.235846 -77.718348) (xy 31.281593 -77.792232) (xy 31.320327 -77.870021)
			(xy 31.351719 -77.951053) (xy 31.3755 -78.034635) (xy 31.391468 -78.120055) (xy 31.399486 -78.206584)
			(xy 31.399486 -78.293484) (xy 34.599874 -78.293484) (xy 34.599874 -78.206584) (xy 34.607892 -78.120055)
			(xy 34.62386 -78.034635) (xy 34.647641 -77.951053) (xy 34.679033 -77.870021) (xy 34.717767 -77.792232)
			(xy 34.763514 -77.718348) (xy 34.815883 -77.649001) (xy 34.874427 -77.584781) (xy 34.938647 -77.526237)
			(xy 35.007994 -77.473868) (xy 35.081878 -77.428121) (xy 35.159667 -77.389387) (xy 35.240699 -77.357995)
			(xy 35.324281 -77.334214) (xy 35.409701 -77.318246) (xy 35.49623 -77.310228) (xy 35.53968 -77.309726)
			(xy 35.58313 -77.310228) (xy 35.669659 -77.318246) (xy 35.755079 -77.334214) (xy 35.838661 -77.357995)
			(xy 35.919693 -77.389387) (xy 35.997482 -77.428121) (xy 36.071366 -77.473868) (xy 36.140713 -77.526237)
			(xy 36.204933 -77.584781) (xy 36.263477 -77.649001) (xy 36.315846 -77.718348) (xy 36.361593 -77.792232)
			(xy 36.400327 -77.870021) (xy 36.431719 -77.951053) (xy 36.4555 -78.034635) (xy 36.471468 -78.120055)
			(xy 36.479486 -78.206584) (xy 36.479486 -78.293484) (xy 36.471468 -78.380013) (xy 36.4555 -78.465433)
			(xy 36.431719 -78.549015) (xy 36.400327 -78.630047) (xy 36.361593 -78.707836) (xy 36.315846 -78.78172)
			(xy 36.263477 -78.851067) (xy 36.204933 -78.915287) (xy 36.140713 -78.973831) (xy 36.071366 -79.0262)
			(xy 35.997482 -79.071947) (xy 35.919693 -79.110681) (xy 35.838661 -79.142073) (xy 35.755079 -79.165854)
			(xy 35.669659 -79.181822) (xy 35.58313 -79.18984) (xy 35.49623 -79.18984) (xy 35.409701 -79.181822)
			(xy 35.324281 -79.165854) (xy 35.240699 -79.142073) (xy 35.159667 -79.110681) (xy 35.081878 -79.071947)
			(xy 35.007994 -79.0262) (xy 34.938647 -78.973831) (xy 34.874427 -78.915287) (xy 34.815883 -78.851067)
			(xy 34.763514 -78.78172) (xy 34.717767 -78.707836) (xy 34.679033 -78.630047) (xy 34.647641 -78.549015)
			(xy 34.62386 -78.465433) (xy 34.607892 -78.380013) (xy 34.599874 -78.293484) (xy 31.399486 -78.293484)
			(xy 31.391468 -78.380013) (xy 31.3755 -78.465433) (xy 31.351719 -78.549015) (xy 31.320327 -78.630047)
			(xy 31.281593 -78.707836) (xy 31.235846 -78.78172) (xy 31.183477 -78.851067) (xy 31.124933 -78.915287)
			(xy 31.060713 -78.973831) (xy 30.991366 -79.0262) (xy 30.917482 -79.071947) (xy 30.839693 -79.110681)
			(xy 30.758661 -79.142073) (xy 30.675079 -79.165854) (xy 30.589659 -79.181822) (xy 30.50313 -79.18984)
			(xy 30.41623 -79.18984) (xy 30.329701 -79.181822) (xy 30.244281 -79.165854) (xy 30.160699 -79.142073)
			(xy 30.079667 -79.110681) (xy 30.001878 -79.071947) (xy 29.927994 -79.0262) (xy 29.858647 -78.973831)
			(xy 29.794427 -78.915287) (xy 29.735883 -78.851067) (xy 29.683514 -78.78172) (xy 29.637767 -78.707836)
			(xy 29.599033 -78.630047) (xy 29.567641 -78.549015) (xy 29.54386 -78.465433) (xy 29.527892 -78.380013)
			(xy 29.519874 -78.293484) (xy 13.909278 -78.293484) (xy 12.841123 -79.361639) (xy 41.522642 -79.361639)
			(xy 41.522642 -79.290317) (xy 41.530628 -79.219443) (xy 41.546498 -79.149908) (xy 41.570055 -79.082588)
			(xy 41.601 -79.018329) (xy 41.638946 -78.957938) (xy 41.683415 -78.902176) (xy 41.733848 -78.851743)
			(xy 41.78961 -78.807274) (xy 41.850001 -78.769328) (xy 41.91426 -78.738383) (xy 41.98158 -78.714826)
			(xy 42.051115 -78.698956) (xy 42.121989 -78.69097) (xy 42.15765 -78.69047) (xy 42.193311 -78.69097)
			(xy 42.264185 -78.698956) (xy 42.33372 -78.714826) (xy 42.40104 -78.738383) (xy 42.465299 -78.769328)
			(xy 42.52569 -78.807274) (xy 42.581452 -78.851743) (xy 42.631885 -78.902176) (xy 42.676354 -78.957938)
			(xy 42.7143 -79.018329) (xy 42.745245 -79.082588) (xy 42.768802 -79.149908) (xy 42.784672 -79.219443)
			(xy 42.792658 -79.290317) (xy 42.792658 -79.361639) (xy 42.784672 -79.432513) (xy 42.768802 -79.502048)
			(xy 42.745245 -79.569368) (xy 42.7143 -79.633627) (xy 42.676354 -79.694018) (xy 42.631885 -79.74978)
			(xy 42.581452 -79.800213) (xy 42.52569 -79.844682) (xy 42.465299 -79.882628) (xy 42.40104 -79.913573)
			(xy 42.33372 -79.93713) (xy 42.264185 -79.953) (xy 42.193311 -79.960986) (xy 42.121989 -79.960986)
			(xy 42.051115 -79.953) (xy 41.98158 -79.93713) (xy 41.91426 -79.913573) (xy 41.850001 -79.882628)
			(xy 41.78961 -79.844682) (xy 41.733848 -79.800213) (xy 41.683415 -79.74978) (xy 41.638946 -79.694018)
			(xy 41.601 -79.633627) (xy 41.570055 -79.569368) (xy 41.546498 -79.502048) (xy 41.530628 -79.432513)
			(xy 41.522642 -79.361639) (xy 12.841123 -79.361639) (xy 12.65174 -79.551022) (xy 12.65174 -80.833484)
			(xy 29.519874 -80.833484) (xy 29.519874 -80.746584) (xy 29.527892 -80.660055) (xy 29.54386 -80.574635)
			(xy 29.567641 -80.491053) (xy 29.599033 -80.410021) (xy 29.637767 -80.332232) (xy 29.683514 -80.258348)
			(xy 29.735883 -80.189001) (xy 29.794427 -80.124781) (xy 29.858647 -80.066237) (xy 29.927994 -80.013868)
			(xy 30.001878 -79.968121) (xy 30.079667 -79.929387) (xy 30.160699 -79.897995) (xy 30.244281 -79.874214)
			(xy 30.329701 -79.858246) (xy 30.41623 -79.850228) (xy 30.45968 -79.849726) (xy 30.50313 -79.850228)
			(xy 30.589659 -79.858246) (xy 30.675079 -79.874214) (xy 30.758661 -79.897995) (xy 30.839693 -79.929387)
			(xy 30.917482 -79.968121) (xy 30.991366 -80.013868) (xy 31.060713 -80.066237) (xy 31.124933 -80.124781)
			(xy 31.183477 -80.189001) (xy 31.235846 -80.258348) (xy 31.281593 -80.332232) (xy 31.320327 -80.410021)
			(xy 31.351719 -80.491053) (xy 31.3755 -80.574635) (xy 31.391468 -80.660055) (xy 31.399486 -80.746584)
			(xy 31.399486 -80.833484) (xy 34.599874 -80.833484) (xy 34.599874 -80.746584) (xy 34.607892 -80.660055)
			(xy 34.62386 -80.574635) (xy 34.647641 -80.491053) (xy 34.679033 -80.410021) (xy 34.717767 -80.332232)
			(xy 34.763514 -80.258348) (xy 34.815883 -80.189001) (xy 34.874427 -80.124781) (xy 34.938647 -80.066237)
			(xy 35.007994 -80.013868) (xy 35.081878 -79.968121) (xy 35.159667 -79.929387) (xy 35.240699 -79.897995)
			(xy 35.324281 -79.874214) (xy 35.409701 -79.858246) (xy 35.49623 -79.850228) (xy 35.53968 -79.849726)
			(xy 35.58313 -79.850228) (xy 35.669659 -79.858246) (xy 35.755079 -79.874214) (xy 35.838661 -79.897995)
			(xy 35.919693 -79.929387) (xy 35.997482 -79.968121) (xy 36.071366 -80.013868) (xy 36.140713 -80.066237)
			(xy 36.204933 -80.124781) (xy 36.263477 -80.189001) (xy 36.315846 -80.258348) (xy 36.361593 -80.332232)
			(xy 36.400327 -80.410021) (xy 36.431719 -80.491053) (xy 36.4555 -80.574635) (xy 36.471468 -80.660055)
			(xy 36.479486 -80.746584) (xy 36.479486 -80.833484) (xy 36.471468 -80.920013) (xy 36.4555 -81.005433)
			(xy 36.431719 -81.089015) (xy 36.400327 -81.170047) (xy 36.361593 -81.247836) (xy 36.315846 -81.32172)
			(xy 36.263477 -81.391067) (xy 36.204933 -81.455287) (xy 36.140713 -81.513831) (xy 36.071366 -81.5662)
			(xy 35.997482 -81.611947) (xy 35.919693 -81.650681) (xy 35.838661 -81.682073) (xy 35.755079 -81.705854)
			(xy 35.669659 -81.721822) (xy 35.58313 -81.72984) (xy 35.49623 -81.72984) (xy 35.409701 -81.721822)
			(xy 35.324281 -81.705854) (xy 35.240699 -81.682073) (xy 35.159667 -81.650681) (xy 35.081878 -81.611947)
			(xy 35.007994 -81.5662) (xy 34.938647 -81.513831) (xy 34.874427 -81.455287) (xy 34.815883 -81.391067)
			(xy 34.763514 -81.32172) (xy 34.717767 -81.247836) (xy 34.679033 -81.170047) (xy 34.647641 -81.089015)
			(xy 34.62386 -81.005433) (xy 34.607892 -80.920013) (xy 34.599874 -80.833484) (xy 31.399486 -80.833484)
			(xy 31.391468 -80.920013) (xy 31.3755 -81.005433) (xy 31.351719 -81.089015) (xy 31.320327 -81.170047)
			(xy 31.281593 -81.247836) (xy 31.235846 -81.32172) (xy 31.183477 -81.391067) (xy 31.124933 -81.455287)
			(xy 31.060713 -81.513831) (xy 30.991366 -81.5662) (xy 30.917482 -81.611947) (xy 30.839693 -81.650681)
			(xy 30.758661 -81.682073) (xy 30.675079 -81.705854) (xy 30.589659 -81.721822) (xy 30.50313 -81.72984)
			(xy 30.41623 -81.72984) (xy 30.329701 -81.721822) (xy 30.244281 -81.705854) (xy 30.160699 -81.682073)
			(xy 30.079667 -81.650681) (xy 30.001878 -81.611947) (xy 29.927994 -81.5662) (xy 29.858647 -81.513831)
			(xy 29.794427 -81.455287) (xy 29.735883 -81.391067) (xy 29.683514 -81.32172) (xy 29.637767 -81.247836)
			(xy 29.599033 -81.170047) (xy 29.567641 -81.089015) (xy 29.54386 -81.005433) (xy 29.527892 -80.920013)
			(xy 29.519874 -80.833484) (xy 12.65174 -80.833484) (xy 12.65174 -83.373484) (xy 29.519874 -83.373484)
			(xy 29.519874 -83.286584) (xy 29.527892 -83.200055) (xy 29.54386 -83.114635) (xy 29.567641 -83.031053)
			(xy 29.599033 -82.950021) (xy 29.637767 -82.872232) (xy 29.683514 -82.798348) (xy 29.735883 -82.729001)
			(xy 29.794427 -82.664781) (xy 29.858647 -82.606237) (xy 29.927994 -82.553868) (xy 30.001878 -82.508121)
			(xy 30.079667 -82.469387) (xy 30.160699 -82.437995) (xy 30.244281 -82.414214) (xy 30.329701 -82.398246)
			(xy 30.41623 -82.390228) (xy 30.45968 -82.389726) (xy 30.50313 -82.390228) (xy 30.589659 -82.398246)
			(xy 30.675079 -82.414214) (xy 30.758661 -82.437995) (xy 30.839693 -82.469387) (xy 30.917482 -82.508121)
			(xy 30.991366 -82.553868) (xy 31.060713 -82.606237) (xy 31.124933 -82.664781) (xy 31.183477 -82.729001)
			(xy 31.235846 -82.798348) (xy 31.281593 -82.872232) (xy 31.320327 -82.950021) (xy 31.351719 -83.031053)
			(xy 31.3755 -83.114635) (xy 31.391468 -83.200055) (xy 31.399486 -83.286584) (xy 31.399486 -83.373484)
			(xy 34.599874 -83.373484) (xy 34.599874 -83.286584) (xy 34.607892 -83.200055) (xy 34.62386 -83.114635)
			(xy 34.647641 -83.031053) (xy 34.679033 -82.950021) (xy 34.717767 -82.872232) (xy 34.763514 -82.798348)
			(xy 34.815883 -82.729001) (xy 34.874427 -82.664781) (xy 34.938647 -82.606237) (xy 35.007994 -82.553868)
			(xy 35.081878 -82.508121) (xy 35.159667 -82.469387) (xy 35.240699 -82.437995) (xy 35.324281 -82.414214)
			(xy 35.409701 -82.398246) (xy 35.49623 -82.390228) (xy 35.53968 -82.389726) (xy 35.58313 -82.390228)
			(xy 35.669659 -82.398246) (xy 35.755079 -82.414214) (xy 35.838661 -82.437995) (xy 35.919693 -82.469387)
			(xy 35.997482 -82.508121) (xy 36.071366 -82.553868) (xy 36.140713 -82.606237) (xy 36.204933 -82.664781)
			(xy 36.263477 -82.729001) (xy 36.315846 -82.798348) (xy 36.361593 -82.872232) (xy 36.400327 -82.950021)
			(xy 36.431719 -83.031053) (xy 36.4555 -83.114635) (xy 36.471468 -83.200055) (xy 36.479486 -83.286584)
			(xy 36.479486 -83.373484) (xy 36.471468 -83.460013) (xy 36.4555 -83.545433) (xy 36.431719 -83.629015)
			(xy 36.400327 -83.710047) (xy 36.361593 -83.787836) (xy 36.315846 -83.86172) (xy 36.263477 -83.931067)
			(xy 36.204933 -83.995287) (xy 36.140713 -84.053831) (xy 36.071366 -84.1062) (xy 35.997482 -84.151947)
			(xy 35.919693 -84.190681) (xy 35.838661 -84.222073) (xy 35.755079 -84.245854) (xy 35.669659 -84.261822)
			(xy 35.58313 -84.26984) (xy 35.49623 -84.26984) (xy 35.409701 -84.261822) (xy 35.324281 -84.245854)
			(xy 35.240699 -84.222073) (xy 35.159667 -84.190681) (xy 35.081878 -84.151947) (xy 35.007994 -84.1062)
			(xy 34.938647 -84.053831) (xy 34.874427 -83.995287) (xy 34.815883 -83.931067) (xy 34.763514 -83.86172)
			(xy 34.717767 -83.787836) (xy 34.679033 -83.710047) (xy 34.647641 -83.629015) (xy 34.62386 -83.545433)
			(xy 34.607892 -83.460013) (xy 34.599874 -83.373484) (xy 31.399486 -83.373484) (xy 31.391468 -83.460013)
			(xy 31.3755 -83.545433) (xy 31.351719 -83.629015) (xy 31.320327 -83.710047) (xy 31.281593 -83.787836)
			(xy 31.235846 -83.86172) (xy 31.183477 -83.931067) (xy 31.124933 -83.995287) (xy 31.060713 -84.053831)
			(xy 30.991366 -84.1062) (xy 30.917482 -84.151947) (xy 30.839693 -84.190681) (xy 30.758661 -84.222073)
			(xy 30.675079 -84.245854) (xy 30.589659 -84.261822) (xy 30.50313 -84.26984) (xy 30.41623 -84.26984)
			(xy 30.329701 -84.261822) (xy 30.244281 -84.245854) (xy 30.160699 -84.222073) (xy 30.079667 -84.190681)
			(xy 30.001878 -84.151947) (xy 29.927994 -84.1062) (xy 29.858647 -84.053831) (xy 29.794427 -83.995287)
			(xy 29.735883 -83.931067) (xy 29.683514 -83.86172) (xy 29.637767 -83.787836) (xy 29.599033 -83.710047)
			(xy 29.567641 -83.629015) (xy 29.54386 -83.545433) (xy 29.527892 -83.460013) (xy 29.519874 -83.373484)
			(xy 12.65174 -83.373484) (xy 12.65174 -97.732342) (xy 12.65224 -97.754344) (xy 12.659792 -97.797693)
			(xy 12.674699 -97.839094) (xy 12.696514 -97.877308) (xy 12.724585 -97.911193) (xy 12.758074 -97.939737)
			(xy 12.795979 -97.962085) (xy 12.837167 -97.97757) (xy 12.880406 -97.98573) (xy 12.924405 -97.986319)
			(xy 12.967847 -97.97932) (xy 13.009435 -97.964943) (xy 13.047925 -97.943618) (xy 13.082166 -97.915981)
			(xy 13.097002 -97.899728) (xy 13.140003 -97.851366) (xy 13.231125 -97.759456) (xy 13.327777 -97.673379)
			(xy 13.429586 -97.593468) (xy 13.536159 -97.520032) (xy 13.647085 -97.453353) (xy 13.761937 -97.393689)
			(xy 13.880272 -97.341269) (xy 14.001632 -97.296297) (xy 14.12555 -97.258946) (xy 14.251547 -97.229359)
			(xy 14.379139 -97.207651) (xy 14.507831 -97.193906) (xy 14.637129 -97.188176) (xy 14.766533 -97.190484)
			(xy 14.895545 -97.200821) (xy 15.023666 -97.219146) (xy 15.150402 -97.24539) (xy 15.275264 -97.279451)
			(xy 15.397771 -97.321197) (xy 15.517451 -97.370468) (xy 15.633841 -97.427074) (xy 15.746492 -97.490795)
			(xy 15.85497 -97.561387) (xy 15.958857 -97.638577) (xy 16.057752 -97.722068) (xy 16.151273 -97.811536)
			(xy 16.239059 -97.906638) (xy 16.320772 -98.007006) (xy 16.396098 -98.112252) (xy 16.464744 -98.221972)
			(xy 16.526446 -98.335742) (xy 16.580967 -98.453123) (xy 16.628096 -98.573662) (xy 16.667651 -98.696894)
			(xy 16.69948 -98.822344) (xy 16.723459 -98.949528) (xy 16.739497 -99.077955) (xy 16.747531 -99.207131)
			(xy 16.747531 -99.336555) (xy 16.739496 -99.465731) (xy 16.723458 -99.594158) (xy 16.699478 -99.721342)
			(xy 16.667649 -99.846792) (xy 16.628094 -99.970024) (xy 16.580965 -100.090563) (xy 16.526444 -100.207943)
			(xy 16.464741 -100.321713) (xy 16.396094 -100.431433) (xy 16.320769 -100.536679) (xy 16.239055 -100.637047)
			(xy 16.151268 -100.732148) (xy 16.057747 -100.821616) (xy 15.958852 -100.905106) (xy 15.854965 -100.982296)
			(xy 15.746487 -101.052888) (xy 15.633835 -101.116609) (xy 15.517445 -101.173214) (xy 15.397766 -101.222485)
			(xy 15.275258 -101.264231) (xy 15.150396 -101.298291) (xy 15.02366 -101.324535) (xy 14.895539 -101.34286)
			(xy 14.766527 -101.353196) (xy 14.637123 -101.355504) (xy 14.507825 -101.349774) (xy 14.379133 -101.336028)
			(xy 14.251541 -101.31432) (xy 14.125544 -101.284733) (xy 14.001626 -101.247381) (xy 13.880266 -101.202408)
			(xy 13.761932 -101.149989) (xy 13.64708 -101.090324) (xy 13.536154 -101.023645) (xy 13.429581 -100.950208)
			(xy 13.327772 -100.870297) (xy 13.231121 -100.78422) (xy 13.139999 -100.692309) (xy 13.097002 -100.643944)
			(xy 13.082207 -100.627661) (xy 13.04795 -100.600056) (xy 13.009453 -100.578761) (xy 12.967865 -100.564409)
			(xy 12.924428 -100.557429) (xy 12.880437 -100.558031) (xy 12.837207 -100.566195) (xy 12.796027 -100.581678)
			(xy 12.758126 -100.604018) (xy 12.724637 -100.632548) (xy 12.696558 -100.666417) (xy 12.674727 -100.704613)
			(xy 12.659797 -100.745997) (xy 12.652212 -100.789333) (xy 12.65174 -100.81133) (xy 12.65174 -100.999036)
			(xy 16.9672 -105.314496) (xy 16.9672 -110.089188) (xy 14.159738 -112.896904) (xy 14.144461 -112.912838)
			(xy 14.11911 -112.948969) (xy 14.100385 -112.988938) (xy 14.088848 -113.031542) (xy 14.084847 -113.075498)
			(xy 14.088502 -113.119485) (xy 14.099703 -113.162178) (xy 14.118113 -113.202293) (xy 14.143179 -113.238623)
			(xy 14.174145 -113.270075) (xy 14.210081 -113.295703) (xy 14.249905 -113.314735) (xy 14.292419 -113.326599)
			(xy 14.336343 -113.330938) (xy 14.380356 -113.327621) (xy 14.423134 -113.316749) (xy 14.443456 -113.30813)
			(xy 14.53578 -113.267121) (xy 14.723066 -113.191327) (xy 14.913128 -113.122789) (xy 15.105684 -113.061609)
			(xy 15.30045 -113.007877) (xy 15.497138 -112.961674) (xy 15.695457 -112.923066) (xy 15.895113 -112.892112)
			(xy 16.095812 -112.868857) (xy 16.297257 -112.853335) (xy 16.499149 -112.84557) (xy 16.60017 -112.845088)
			(xy 16.70335 -112.845595) (xy 16.909551 -112.853696) (xy 17.115275 -112.869887) (xy 17.320205 -112.894142)
			(xy 17.524025 -112.926424) (xy 17.72642 -112.966683) (xy 17.927079 -113.014857) (xy 18.125691 -113.070871)
			(xy 18.321951 -113.13464) (xy 18.515557 -113.206065) (xy 18.706209 -113.285035) (xy 18.893613 -113.37143)
			(xy 19.077482 -113.465116) (xy 19.25753 -113.565948) (xy 19.433481 -113.673771) (xy 19.605064 -113.788418)
			(xy 19.772012 -113.909714) (xy 19.934071 -114.03747) (xy 20.090988 -114.171491) (xy 20.242523 -114.311568)
			(xy 20.388442 -114.457487) (xy 20.528519 -114.609022) (xy 20.66254 -114.765939) (xy 20.790296 -114.927998)
			(xy 20.911592 -115.094946) (xy 21.026239 -115.266529) (xy 21.134062 -115.44248) (xy 21.234894 -115.622528)
			(xy 21.32858 -115.806397) (xy 21.414975 -115.993801) (xy 21.493945 -116.184453) (xy 21.56537 -116.378059)
			(xy 21.629139 -116.574319) (xy 21.685153 -116.772931) (xy 21.733327 -116.97359) (xy 21.773586 -117.175985)
			(xy 21.805868 -117.379805) (xy 21.830123 -117.584735) (xy 21.846314 -117.790459) (xy 21.854415 -117.99666)
			(xy 21.854922 -118.09984) (xy 21.854415 -118.202734) (xy 21.846356 -118.408364) (xy 21.830253 -118.613521)
			(xy 21.80613 -118.817891) (xy 21.774024 -119.021159) (xy 21.733985 -119.223014) (xy 21.686074 -119.423147)
			(xy 21.630364 -119.621251) (xy 21.56694 -119.817022) (xy 21.495901 -120.01016) (xy 21.417355 -120.200368)
			(xy 21.331422 -120.387355) (xy 21.238234 -120.570835) (xy 21.137934 -120.750526) (xy 21.030676 -120.926152)
			(xy 20.916625 -121.097444) (xy 20.795954 -121.264139) (xy 20.66885 -121.425982) (xy 20.535507 -121.582725)
			(xy 20.396129 -121.734128) (xy 20.250931 -121.879957) (xy 20.100135 -122.01999) (xy 19.943972 -122.154012)
			(xy 19.782682 -122.281817) (xy 19.616511 -122.40321) (xy 19.445715 -122.518003) (xy 19.270556 -122.626022)
			(xy 19.091303 -122.727101) (xy 18.908229 -122.821083) (xy 18.721616 -122.907827) (xy 18.53175 -122.987198)
			(xy 18.338923 -123.059074) (xy 18.143429 -123.123346) (xy 17.945569 -123.179915) (xy 17.745645 -123.228694)
			(xy 17.543965 -123.269609) (xy 17.340838 -123.302596) (xy 17.136576 -123.327605) (xy 16.93149 -123.344598)
			(xy 16.725897 -123.353549) (xy 16.520111 -123.354444) (xy 16.314447 -123.347281) (xy 16.109222 -123.332072)
			(xy 15.90475 -123.30884) (xy 15.701343 -123.27762) (xy 15.499316 -123.238461) (xy 15.298976 -123.191422)
			(xy 15.100631 -123.136575) (xy 14.904586 -123.074006) (xy 14.807692 -123.039378) (xy 14.785987 -123.03203)
			(xy 14.740809 -123.024384) (xy 14.694992 -123.024963) (xy 14.650022 -123.033746) (xy 14.607355 -123.050451)
			(xy 14.568375 -123.074534) (xy 14.534344 -123.105216) (xy 14.506366 -123.141503) (xy 14.485348 -123.182217)
			(xy 14.471969 -123.226041) (xy 14.466665 -123.271553) (xy 14.469607 -123.317279) (xy 14.4807 -123.361736)
			(xy 14.499584 -123.403484) (xy 14.525647 -123.441169) (xy 14.5415 -123.457716) (xy 17.583404 -126.49962)
			(xy 19.140932 -126.49962) (xy 23.983188 -131.34213) (xy 23.999824 -131.358102) (xy 24.03777 -131.384303)
			(xy 24.07982 -131.403232) (xy 24.124594 -131.414267) (xy 24.170624 -131.417047) (xy 24.2164 -131.411481)
			(xy 24.260423 -131.397752) (xy 24.301247 -131.376309) (xy 24.337536 -131.347855) (xy 24.368098 -131.313323)
			(xy 24.391933 -131.273847) (xy 24.408257 -131.23072) (xy 24.416537 -131.185355) (xy 24.41702 -131.162298)
			(xy 24.41702 -116.667026) (xy 18.556224 -110.80623) (xy 18.556224 -92.880688) (xy 24.643334 -86.793324)
			(xy 50.899314 -86.793324) (xy 52.159408 -85.53323) (xy 52.17543 -85.516518) (xy 52.201706 -85.478406)
			(xy 52.220643 -85.436165) (xy 52.231616 -85.391193) (xy 52.234262 -85.344977) (xy 52.228492 -85.299046)
			(xy 52.214499 -85.254919) (xy 52.192744 -85.214058) (xy 52.163947 -85.177813) (xy 52.129062 -85.147384)
			(xy 52.089242 -85.123777) (xy 52.045804 -85.107773) (xy 52.000186 -85.099902) (xy 51.977036 -85.099652)
			(xy 51.936276 -85.09962) (xy 51.855073 -85.092519) (xy 51.774964 -85.077455) (xy 51.696728 -85.054573)
			(xy 51.621127 -85.024098) (xy 51.548894 -84.986324) (xy 51.480733 -84.94162) (xy 51.417306 -84.89042)
			(xy 51.35923 -84.833222) (xy 51.307071 -84.770583) (xy 51.261334 -84.70311) (xy 51.222465 -84.631461)
			(xy 51.190842 -84.556332) (xy 51.166772 -84.478454) (xy 51.150489 -84.398583) (xy 51.142152 -84.317498)
			(xy 51.141842 -84.235985) (xy 51.149562 -84.154838) (xy 51.165236 -84.074847) (xy 51.188713 -83.996787)
			(xy 51.219763 -83.92142) (xy 51.258086 -83.849477) (xy 51.303308 -83.781658) (xy 51.354989 -83.718624)
			(xy 51.412628 -83.660985) (xy 51.475663 -83.609304) (xy 51.543482 -83.564083) (xy 51.615425 -83.525761)
			(xy 51.690793 -83.494711) (xy 51.768852 -83.471235) (xy 51.848844 -83.455561) (xy 51.929991 -83.447842)
			(xy 52.011504 -83.448153) (xy 52.092589 -83.45649) (xy 52.17246 -83.472773) (xy 52.250338 -83.496844)
			(xy 52.325466 -83.528468) (xy 52.397115 -83.567337) (xy 52.464587 -83.613074) (xy 52.527227 -83.665235)
			(xy 52.584424 -83.723311) (xy 52.635624 -83.786738) (xy 52.680327 -83.854899) (xy 52.7181 -83.927132)
			(xy 52.748575 -84.002734) (xy 52.771456 -84.08097) (xy 52.78652 -84.161079) (xy 52.79362 -84.242282)
			(xy 52.793646 -84.283042) (xy 52.793854 -84.30619) (xy 52.801741 -84.3518) (xy 52.817757 -84.395229)
			(xy 52.841372 -84.43504) (xy 52.871805 -84.469916) (xy 52.908051 -84.498705) (xy 52.94891 -84.520455)
			(xy 52.993033 -84.534446) (xy 53.03896 -84.540217) (xy 53.085172 -84.537576) (xy 53.130142 -84.52661)
			(xy 53.172383 -84.507682) (xy 53.210498 -84.481419) (xy 53.227224 -84.465414) (xy 80.61198 -57.080912)
			(xy 81.161128 -57.080912) (xy 81.18983 -57.06491) (xy 81.208775 -57.054709) (xy 81.248495 -57.038159)
			(xy 81.269078 -57.03189) (xy 81.300574 -57.023) (xy 83.43646 -54.887114) (xy 83.43646 -50.216562)
			(xy 85.847174 -47.805848) (xy 92.537788 -47.805848) (xy 93.53804 -48.8061) (xy 93.53804 -50.36312)
			(xy 92.858082 -51.042824) (xy 92.657168 -51.042824) (xy 92.633906 -51.043318) (xy 92.588158 -51.051773)
			(xy 92.544713 -51.068413) (xy 92.505023 -51.092683) (xy 92.470412 -51.123772) (xy 92.442038 -51.16064)
			(xy 92.420848 -51.202057) (xy 92.40755 -51.246639) (xy 92.402589 -51.292896) (xy 92.406129 -51.339284)
			(xy 92.418054 -51.384253) (xy 92.437963 -51.4263) (xy 92.465194 -51.464022) (xy 92.481654 -51.480466)
			(xy 92.508499 -51.506954) (xy 92.557204 -51.564534) (xy 92.599546 -51.626942) (xy 92.63505 -51.693478)
			(xy 92.663319 -51.763395) (xy 92.684036 -51.83591) (xy 92.696968 -51.91021) (xy 92.70197 -51.98546)
			(xy 92.698986 -52.060817) (xy 92.688049 -52.135436) (xy 92.669283 -52.20848) (xy 92.642897 -52.27913)
			(xy 92.609187 -52.346593) (xy 92.568532 -52.410113) (xy 92.521388 -52.468977) (xy 92.468283 -52.522526)
			(xy 92.409813 -52.570159) (xy 92.346633 -52.61134) (xy 92.279453 -52.64561) (xy 92.209025 -52.672583)
			(xy 92.177392 -52.680991) (xy 93.154757 -52.680991) (xy 93.160779 -52.564808) (xy 93.174802 -52.449317)
			(xy 93.19676 -52.335069) (xy 93.226547 -52.222608) (xy 93.264022 -52.11247) (xy 93.309007 -52.00518)
			(xy 93.361286 -51.901249) (xy 93.420611 -51.801173) (xy 93.486699 -51.705427) (xy 93.559235 -51.61447)
			(xy 93.637874 -51.528734) (xy 93.72224 -51.448627) (xy 93.811932 -51.374531) (xy 93.906522 -51.306801)
			(xy 94.00556 -51.245757) (xy 94.108573 -51.191692) (xy 94.21507 -51.144862) (xy 94.324545 -51.105491)
			(xy 94.436475 -51.073767) (xy 94.550327 -51.049841) (xy 94.665559 -51.033827) (xy 94.781621 -51.0258)
			(xy 94.83979 -51.025298) (xy 94.897959 -51.0258) (xy 95.014021 -51.033827) (xy 95.129253 -51.049841)
			(xy 95.243105 -51.073767) (xy 95.355035 -51.105491) (xy 95.46451 -51.144862) (xy 95.571007 -51.191692)
			(xy 95.67402 -51.245757) (xy 95.773058 -51.306801) (xy 95.867648 -51.374531) (xy 95.95734 -51.448627)
			(xy 96.041706 -51.528734) (xy 96.120345 -51.61447) (xy 96.192881 -51.705427) (xy 96.258969 -51.801173)
			(xy 96.318294 -51.901249) (xy 96.370573 -52.00518) (xy 96.415558 -52.11247) (xy 96.453033 -52.222608)
			(xy 96.48282 -52.335069) (xy 96.504778 -52.449317) (xy 96.518801 -52.564808) (xy 96.524823 -52.680991)
			(xy 96.522815 -52.797313) (xy 96.512786 -52.913219) (xy 96.494785 -53.028156) (xy 96.468897 -53.141579)
			(xy 96.435246 -53.252944) (xy 96.393992 -53.361723) (xy 96.345331 -53.467397) (xy 96.289495 -53.569461)
			(xy 96.226752 -53.66743) (xy 96.157398 -53.760837) (xy 96.081766 -53.849237) (xy 96.000215 -53.932208)
			(xy 95.913134 -54.009355) (xy 95.820938 -54.08031) (xy 95.724066 -54.144736) (xy 95.622981 -54.202325)
			(xy 95.518163 -54.252802) (xy 95.410112 -54.295928) (xy 95.299344 -54.331497) (xy 95.186385 -54.359339)
			(xy 95.071775 -54.379321) (xy 94.95606 -54.391348) (xy 94.83979 -54.395364) (xy 94.72352 -54.391348)
			(xy 94.607805 -54.379321) (xy 94.493195 -54.359339) (xy 94.380236 -54.331497) (xy 94.269468 -54.295928)
			(xy 94.161417 -54.252802) (xy 94.056599 -54.202325) (xy 93.955514 -54.144736) (xy 93.858642 -54.08031)
			(xy 93.766446 -54.009355) (xy 93.679365 -53.932208) (xy 93.597814 -53.849237) (xy 93.522182 -53.760837)
			(xy 93.452828 -53.66743) (xy 93.390085 -53.569461) (xy 93.334249 -53.467397) (xy 93.285588 -53.361723)
			(xy 93.244334 -53.252944) (xy 93.210683 -53.141579) (xy 93.184795 -53.028156) (xy 93.166794 -52.913219)
			(xy 93.156765 -52.797313) (xy 93.154757 -52.680991) (xy 92.177392 -52.680991) (xy 92.13614 -52.691956)
			(xy 92.061614 -52.703513) (xy 91.986285 -52.707124) (xy 91.910996 -52.702749) (xy 91.836591 -52.690436)
			(xy 91.763906 -52.670323) (xy 91.693756 -52.642637) (xy 91.626927 -52.607687) (xy 91.564169 -52.565865)
			(xy 91.506185 -52.517642) (xy 91.453627 -52.463557) (xy 91.407083 -52.404217) (xy 91.38666 -52.372514)
			(xy 91.377745 -52.359104) (xy 91.35439 -52.336947) (xy 91.32623 -52.321345) (xy 91.295061 -52.313291)
			(xy 91.278964 -52.312824) (xy 90.879168 -52.312824) (xy 90.862486 -52.313344) (xy 90.830265 -52.321997)
			(xy 90.801386 -52.338704) (xy 90.789252 -52.350162) (xy 90.787982 -52.351432) (xy 90.776608 -52.363584)
			(xy 90.76002 -52.392429) (xy 90.751437 -52.424578) (xy 90.751441 -52.457852) (xy 90.760031 -52.489998)
			(xy 90.776626 -52.518839) (xy 90.787982 -52.53101) (xy 90.815668 -52.558696) (xy 90.854022 -52.566062)
			(xy 90.890972 -52.57364) (xy 90.963133 -52.595607) (xy 91.032567 -52.625083) (xy 91.098495 -52.661735)
			(xy 91.160177 -52.705154) (xy 91.216922 -52.754853) (xy 91.268093 -52.810273) (xy 91.313116 -52.870794)
			(xy 91.351487 -52.935736) (xy 91.382776 -53.004373) (xy 91.406631 -53.075933) (xy 91.422784 -53.149614)
			(xy 91.431055 -53.22459) (xy 91.431352 -53.300021) (xy 91.42367 -53.37506) (xy 91.408096 -53.448866)
			(xy 91.384804 -53.520611) (xy 91.354056 -53.589491) (xy 91.316196 -53.654733) (xy 91.271649 -53.715606)
			(xy 91.220915 -53.771427) (xy 91.164563 -53.821569) (xy 91.103224 -53.865472) (xy 91.037586 -53.902641)
			(xy 90.968386 -53.932661) (xy 90.896399 -53.955195) (xy 90.822433 -53.96999) (xy 90.747317 -53.97688)
			(xy 90.671893 -53.975789) (xy 90.597008 -53.966727) (xy 90.560144 -53.958744) (xy 90.52814 -53.951378)
			(xy 90.464894 -53.969412) (xy 87.713058 -56.721248) (xy 87.697141 -56.737934) (xy 87.670941 -56.775874)
			(xy 87.652012 -56.817916) (xy 87.640975 -56.862682) (xy 87.638192 -56.908705) (xy 87.643754 -56.954476)
			(xy 87.657479 -56.998493) (xy 87.678917 -57.039313) (xy 87.707364 -57.075598) (xy 87.741889 -57.106158)
			(xy 87.781358 -57.129991) (xy 87.824479 -57.146315) (xy 87.869836 -57.154596) (xy 87.89289 -57.15508)
			(xy 93.35389 -57.15508) (xy 99.309936 -51.199034) (xy 99.309936 -21.645372) (xy 99.309356 -21.628758)
			(xy 99.300773 -21.596658) (xy 99.284195 -21.567861) (xy 99.272852 -21.55571) (xy 96.144588 -18.4277)
			(xy 96.128265 -18.41222) (xy 96.091366 -18.386505) (xy 96.050515 -18.367688) (xy 96.00699 -18.356357)
			(xy 95.96215 -18.352866) (xy 95.917396 -18.357325) (xy 95.874126 -18.369594) (xy 95.833692 -18.38929)
			(xy 95.797357 -18.415797) (xy 95.766257 -18.448287) (xy 95.741363 -18.485746) (xy 95.723454 -18.527002)
			(xy 95.713088 -18.570767) (xy 95.710589 -18.615673) (xy 95.716036 -18.660318) (xy 95.722186 -18.681954)
			(xy 95.749689 -18.773158) (xy 95.797929 -18.957468) (xy 95.838363 -19.143647) (xy 95.87092 -19.331363)
			(xy 95.895541 -19.520284) (xy 95.912183 -19.710074) (xy 95.920817 -19.900397) (xy 95.921426 -20.090915)
			(xy 95.91401 -20.281289) (xy 95.898583 -20.471182) (xy 95.875171 -20.660257) (xy 95.843816 -20.848178)
			(xy 95.804574 -21.034611) (xy 95.757514 -21.219226) (xy 95.70272 -21.401695) (xy 95.640289 -21.581694)
			(xy 95.570332 -21.758904) (xy 95.492973 -21.93301) (xy 95.408349 -22.103703) (xy 95.316611 -22.270681)
			(xy 95.217922 -22.433646) (xy 95.112455 -22.59231) (xy 95.0004 -22.746391) (xy 94.881954 -22.895616)
			(xy 94.757328 -23.039719) (xy 94.626744 -23.178445) (xy 94.490432 -23.311548) (xy 94.348634 -23.438791)
			(xy 94.201603 -23.559949) (xy 94.0496 -23.674807) (xy 93.892893 -23.78316) (xy 93.731762 -23.884817)
			(xy 93.566492 -23.979597) (xy 93.397377 -24.067331) (xy 93.224716 -24.147865) (xy 93.048817 -24.221055)
			(xy 92.869991 -24.286771) (xy 92.688556 -24.344896) (xy 92.504833 -24.395328) (xy 92.31915 -24.437978)
			(xy 92.131834 -24.472768) (xy 91.94322 -24.499638) (xy 91.753641 -24.518539) (xy 91.563435 -24.529439)
			(xy 91.372938 -24.532318) (xy 91.182489 -24.52717) (xy 90.992426 -24.514006) (xy 90.803085 -24.492847)
			(xy 90.614805 -24.463733) (xy 90.427917 -24.426714) (xy 90.242755 -24.381857) (xy 90.059646 -24.32924)
			(xy 89.878916 -24.268957) (xy 89.700885 -24.201116) (xy 89.52587 -24.125836) (xy 89.354181 -24.043252)
			(xy 89.186122 -23.953509) (xy 89.021993 -23.856768) (xy 88.862084 -23.753199) (xy 88.706679 -23.642987)
			(xy 88.556055 -23.526327) (xy 88.410477 -23.403426) (xy 88.270206 -23.274503) (xy 88.135489 -23.139786)
			(xy 88.006565 -22.999515) (xy 87.883665 -22.853937) (xy 87.767005 -22.703313) (xy 87.656792 -22.547908)
			(xy 87.553224 -22.387999) (xy 87.456482 -22.22387) (xy 87.366739 -22.055811) (xy 87.284155 -21.884122)
			(xy 87.208875 -21.709107) (xy 87.141034 -21.531077) (xy 87.080751 -21.350347) (xy 87.028134 -21.167238)
			(xy 86.983276 -20.982075) (xy 86.946257 -20.795188) (xy 86.917143 -20.606907) (xy 86.895985 -20.417567)
			(xy 86.88282 -20.227504) (xy 86.877672 -20.037055) (xy 86.880551 -19.846558) (xy 86.891451 -19.656351)
			(xy 86.910352 -19.466772) (xy 86.937222 -19.278158) (xy 86.972012 -19.090843) (xy 87.014661 -18.905159)
			(xy 87.065093 -18.721437) (xy 87.123218 -18.540001) (xy 87.188934 -18.361175) (xy 87.262124 -18.185276)
			(xy 87.342658 -18.012615) (xy 87.430392 -17.8435) (xy 87.525172 -17.67823) (xy 87.626828 -17.517099)
			(xy 87.735182 -17.360392) (xy 87.850039 -17.208389) (xy 87.971197 -17.061358) (xy 88.09844 -16.91956)
			(xy 88.231543 -16.783248) (xy 88.370269 -16.652663) (xy 88.514372 -16.528037) (xy 88.663597 -16.409591)
			(xy 88.817678 -16.297536) (xy 88.976342 -16.19207) (xy 89.139307 -16.09338) (xy 89.306284 -16.001642)
			(xy 89.476978 -15.917018) (xy 89.651084 -15.839659) (xy 89.828293 -15.769702) (xy 90.008293 -15.707271)
			(xy 90.190762 -15.652477) (xy 90.375377 -15.605417) (xy 90.56181 -15.566174) (xy 90.749731 -15.534819)
			(xy 90.938805 -15.511407) (xy 91.128698 -15.49598) (xy 91.319073 -15.488564) (xy 91.50959 -15.489173)
			(xy 91.699913 -15.497807) (xy 91.889704 -15.514449) (xy 92.078625 -15.53907) (xy 92.266341 -15.571626)
			(xy 92.452519 -15.612061) (xy 92.636829 -15.660301) (xy 92.728034 -15.687802) (xy 92.749657 -15.694002)
			(xy 92.79431 -15.699433) (xy 92.839221 -15.696921) (xy 92.882989 -15.686542) (xy 92.924247 -15.668623)
			(xy 92.961707 -15.643721) (xy 92.994199 -15.612616) (xy 93.020709 -15.576276) (xy 93.04041 -15.535838)
			(xy 93.052685 -15.492564) (xy 93.057153 -15.447805) (xy 93.053673 -15.402959) (xy 93.042354 -15.359425)
			(xy 93.02355 -15.318563) (xy 92.997847 -15.281648) (xy 92.982288 -15.2654) (xy 91.34856 -13.631672)
			(xy 91.317064 -13.622782) (xy 91.290693 -13.61471) (xy 91.240436 -13.592004) (xy 91.19397 -13.562301)
			(xy 91.152263 -13.526219) (xy 91.116184 -13.48451) (xy 91.086484 -13.438042) (xy 91.063781 -13.387783)
			(xy 91.055698 -13.361416) (xy 91.046808 -13.32992) (xy 89.197434 -11.480292) (xy 89.185295 -11.46893)
			(xy 89.156499 -11.452332) (xy 89.124391 -11.443745) (xy 89.107772 -11.443208) (xy 87.818722 -11.443208)
			(xy 85.894926 -9.519412) (xy 85.83168 -9.501378) (xy 85.799676 -9.508744) (xy 85.762881 -9.516715)
			(xy 85.688139 -9.525777) (xy 85.612857 -9.526898) (xy 85.537877 -9.520068) (xy 85.464037 -9.505361)
			(xy 85.392162 -9.482943) (xy 85.323055 -9.453064) (xy 85.257488 -9.416057) (xy 85.196192 -9.372336)
			(xy 85.139855 -9.32239) (xy 85.089103 -9.266776) (xy 85.044505 -9.206116) (xy 85.006559 -9.141088)
			(xy 84.975689 -9.072417) (xy 84.952239 -9.000872) (xy 84.936472 -8.927251) (xy 84.928564 -8.852378)
			(xy 84.928603 -8.777088) (xy 84.936589 -8.702222) (xy 84.952432 -8.628618) (xy 84.975955 -8.557097)
			(xy 85.006896 -8.488459) (xy 85.044909 -8.423469) (xy 85.08957 -8.362856) (xy 85.140379 -8.307294)
			(xy 85.196768 -8.257406) (xy 85.258108 -8.213749) (xy 85.323714 -8.176809) (xy 85.392852 -8.147001)
			(xy 85.46475 -8.124657) (xy 85.538605 -8.110027) (xy 85.613592 -8.103274) (xy 85.688872 -8.104473)
			(xy 85.763606 -8.113612) (xy 85.836957 -8.130588) (xy 85.908107 -8.155211) (xy 85.97626 -8.187207)
			(xy 86.040656 -8.226217) (xy 86.100574 -8.271806) (xy 86.155346 -8.323466) (xy 86.204358 -8.380617)
			(xy 86.247065 -8.442623) (xy 86.282989 -8.508791) (xy 86.311727 -8.57838) (xy 86.33296 -8.650614)
			(xy 86.340188 -8.687562) (xy 86.348316 -8.732774) (xy 86.418928 -8.791702) (xy 86.465156 -8.791702)
			(xy 86.481809 -8.791167) (xy 86.513981 -8.782556) (xy 86.542828 -8.765911) (xy 86.566383 -8.742365)
			(xy 86.583039 -8.713524) (xy 86.591661 -8.681354) (xy 86.592156 -8.664702) (xy 86.592156 -8.256016)
			(xy 86.591693 -8.23992) (xy 86.583635 -8.208753) (xy 86.568028 -8.180598) (xy 86.545867 -8.157248)
			(xy 86.532466 -8.14832) (xy 86.500287 -8.127684) (xy 86.440198 -8.080419) (xy 86.385521 -8.026986)
			(xy 86.336888 -7.967999) (xy 86.294857 -7.90414) (xy 86.259914 -7.836142) (xy 86.232461 -7.764791)
			(xy 86.212815 -7.690908) (xy 86.201202 -7.615345) (xy 86.197756 -7.538973) (xy 86.202516 -7.462671)
			(xy 86.215427 -7.387318) (xy 86.236342 -7.313785) (xy 86.265018 -7.242916) (xy 86.301126 -7.17553)
			(xy 86.344249 -7.112403) (xy 86.393891 -7.054262) (xy 86.449479 -7.001778) (xy 86.510372 -6.955554)
			(xy 86.57587 -6.916124) (xy 86.645216 -6.883942) (xy 86.717613 -6.859379) (xy 86.792226 -6.842718)
			(xy 86.830154 -6.837934) (xy 86.878414 -6.8326) (xy 86.942676 -6.760464) (xy 86.942676 -5.789676)
			(xy 86.878414 -5.71754) (xy 86.830154 -5.712206) (xy 86.79305 -5.707486) (xy 86.720011 -5.691355)
			(xy 86.649067 -5.667651) (xy 86.581 -5.636637) (xy 86.516562 -5.598655) (xy 86.456464 -5.554123)
			(xy 86.401367 -5.503533) (xy 86.351882 -5.447443) (xy 86.308552 -5.386472) (xy 86.271856 -5.321293)
			(xy 86.2422 -5.252624) (xy 86.21991 -5.181223) (xy 86.205232 -5.107878) (xy 86.198328 -5.033398)
			(xy 86.199275 -4.958605) (xy 86.208061 -4.884324) (xy 86.22459 -4.811374) (xy 86.24868 -4.74056)
			(xy 86.280064 -4.672663) (xy 86.318397 -4.608433) (xy 86.363256 -4.548578) (xy 86.414145 -4.493759)
			(xy 86.470504 -4.444579) (xy 86.53171 -4.401582) (xy 86.597088 -4.365243) (xy 86.665918 -4.335961)
			(xy 86.737439 -4.31406) (xy 86.810863 -4.299782) (xy 86.885379 -4.293284) (xy 86.960166 -4.294638)
			(xy 87.034398 -4.303829) (xy 87.107257 -4.320755) (xy 87.177939 -4.34523) (xy 87.245663 -4.376984)
			(xy 87.309684 -4.415667) (xy 87.369293 -4.460851) (xy 87.423835 -4.512038) (xy 87.472707 -4.568664)
			(xy 87.515369 -4.630103) (xy 87.551352 -4.695679) (xy 87.566246 -4.729988) (xy 87.575424 -4.750698)
			(xy 87.600052 -4.788713) (xy 87.631026 -4.821763) (xy 87.667366 -4.848802) (xy 87.707921 -4.868975)
			(xy 87.751409 -4.881643) (xy 87.796454 -4.886405) (xy 87.84163 -4.883112) (xy 87.885507 -4.871866)
			(xy 87.926698 -4.853025) (xy 87.963899 -4.827183) (xy 87.980266 -4.811522) (xy 88.104472 -4.687316)
			(xy 88.738964 -4.687316) (xy 88.755057 -4.686811) (xy 88.786219 -4.678762) (xy 88.814374 -4.663167)
			(xy 88.837728 -4.64102) (xy 88.84666 -4.627626) (xy 88.866881 -4.596158) (xy 88.912989 -4.537253)
			(xy 88.96502 -4.483509) (xy 89.022402 -4.435519) (xy 89.084501 -4.393813) (xy 89.150631 -4.358849)
			(xy 89.220064 -4.331014) (xy 89.292034 -4.310615) (xy 89.365745 -4.297878) (xy 89.440387 -4.292942)
			(xy 89.515134 -4.295861) (xy 89.589163 -4.306605) (xy 89.661657 -4.325053) (xy 89.731816 -4.351004)
			(xy 89.798866 -4.38417) (xy 89.862068 -4.424185) (xy 89.920724 -4.470609) (xy 89.974188 -4.522928)
			(xy 90.021869 -4.580567) (xy 90.063241 -4.642889) (xy 90.097849 -4.709206) (xy 90.125311 -4.778787)
			(xy 90.145323 -4.850865) (xy 90.157664 -4.924644) (xy 90.161398 -4.986111) (xy 91.277949 -4.986111)
			(xy 91.283998 -4.910541) (xy 91.298045 -4.836043) (xy 91.319931 -4.76346) (xy 91.349408 -4.693614)
			(xy 91.386143 -4.627297) (xy 91.429718 -4.565261) (xy 91.47964 -4.508208) (xy 91.535344 -4.456784)
			(xy 91.596199 -4.411573) (xy 91.661514 -4.373086) (xy 91.73055 -4.34176) (xy 91.802525 -4.31795)
			(xy 91.876623 -4.301925) (xy 91.952004 -4.293866) (xy 91.98991 -4.293362) (xy 92.027816 -4.293866)
			(xy 92.103197 -4.301925) (xy 92.177295 -4.31795) (xy 92.24927 -4.34176) (xy 92.318306 -4.373086)
			(xy 92.383621 -4.411573) (xy 92.444476 -4.456784) (xy 92.50018 -4.508208) (xy 92.550102 -4.565261)
			(xy 92.593677 -4.627297) (xy 92.630412 -4.693614) (xy 92.659889 -4.76346) (xy 92.681775 -4.836043)
			(xy 92.695822 -4.910541) (xy 92.701871 -4.986111) (xy 92.699852 -5.061895) (xy 92.68979 -5.137035)
			(xy 92.671798 -5.21068) (xy 92.64608 -5.281996) (xy 92.612928 -5.350173) (xy 92.572716 -5.414441)
			(xy 92.525901 -5.47407) (xy 92.473013 -5.528386) (xy 92.414651 -5.576772) (xy 92.351476 -5.61868)
			(xy 92.284205 -5.653636) (xy 92.2136 -5.681243) (xy 92.140459 -5.701189) (xy 92.065614 -5.713248)
			(xy 91.98991 -5.717283) (xy 91.914206 -5.713248) (xy 91.839361 -5.701189) (xy 91.76622 -5.681243)
			(xy 91.695615 -5.653636) (xy 91.628344 -5.61868) (xy 91.565169 -5.576772) (xy 91.506807 -5.528386)
			(xy 91.453919 -5.47407) (xy 91.407104 -5.414441) (xy 91.366892 -5.350173) (xy 91.33374 -5.281996)
			(xy 91.308022 -5.21068) (xy 91.29003 -5.137035) (xy 91.279968 -5.061895) (xy 91.277949 -4.986111)
			(xy 90.161398 -4.986111) (xy 90.1622 -4.999311) (xy 90.158879 -5.074042) (xy 90.147738 -5.148012)
			(xy 90.1289 -5.220406) (xy 90.102574 -5.290424) (xy 90.069048 -5.357295) (xy 90.028694 -5.420281)
			(xy 89.981956 -5.478687) (xy 89.92935 -5.531869) (xy 89.871456 -5.57924) (xy 89.808913 -5.620278)
			(xy 89.742411 -5.654529) (xy 89.70772 -5.668518) (xy 89.68648 -5.677203) (xy 89.647388 -5.701234)
			(xy 89.613245 -5.731892) (xy 89.58516 -5.768182) (xy 89.564047 -5.808924) (xy 89.550592 -5.852794)
			(xy 89.545231 -5.898368) (xy 89.548139 -5.944163) (xy 89.559221 -5.988692) (xy 89.578117 -6.030509)
			(xy 89.604214 -6.068253) (xy 89.62009 -6.084824) (xy 89.640156 -6.10489) (xy 89.656695 -6.120796)
			(xy 89.69444 -6.146884) (xy 89.736257 -6.165772) (xy 89.780784 -6.176845) (xy 89.826576 -6.179745)
			(xy 89.872145 -6.174376) (xy 89.91601 -6.160914) (xy 89.956745 -6.139795) (xy 89.993026 -6.111707)
			(xy 90.023676 -6.077561) (xy 90.047697 -6.038467) (xy 90.056462 -6.01726) (xy 90.070794 -5.981842)
			(xy 90.105943 -5.913997) (xy 90.148157 -5.850308) (xy 90.19695 -5.791507) (xy 90.251761 -5.738271)
			(xy 90.31196 -5.691213) (xy 90.376853 -5.650874) (xy 90.445694 -5.617719) (xy 90.51769 -5.592129)
			(xy 90.592013 -5.574398) (xy 90.667808 -5.56473) (xy 90.744203 -5.563238) (xy 90.820317 -5.569937)
			(xy 90.895276 -5.584751) (xy 90.968217 -5.607509) (xy 91.038301 -5.63795) (xy 91.10472 -5.675724)
			(xy 91.166711 -5.720394) (xy 91.22356 -5.771448) (xy 91.274613 -5.828298) (xy 91.319283 -5.89029)
			(xy 91.357055 -5.956709) (xy 91.387495 -6.026793) (xy 91.410252 -6.099735) (xy 91.425065 -6.174694)
			(xy 91.431763 -6.250809) (xy 91.430269 -6.327203) (xy 91.4206 -6.402998) (xy 91.402868 -6.477321)
			(xy 91.377277 -6.549317) (xy 91.34412 -6.618157) (xy 91.30378 -6.683049) (xy 91.256721 -6.743247)
			(xy 91.203485 -6.798058) (xy 91.144683 -6.84685) (xy 91.080993 -6.889063) (xy 91.013148 -6.92421)
			(xy 90.97772 -6.938518) (xy 90.95648 -6.947203) (xy 90.917388 -6.971234) (xy 90.883245 -7.001892)
			(xy 90.85516 -7.038182) (xy 90.834047 -7.078924) (xy 90.820592 -7.122794) (xy 90.815231 -7.168368)
			(xy 90.818139 -7.214163) (xy 90.829221 -7.258692) (xy 90.848117 -7.300509) (xy 90.874214 -7.338253)
			(xy 90.89009 -7.354824) (xy 90.910156 -7.37489) (xy 90.926695 -7.390796) (xy 90.96444 -7.416884)
			(xy 91.006257 -7.435772) (xy 91.050784 -7.446845) (xy 91.096576 -7.449745) (xy 91.142145 -7.444376)
			(xy 91.18601 -7.430914) (xy 91.226745 -7.409795) (xy 91.263026 -7.381707) (xy 91.293676 -7.347561)
			(xy 91.317697 -7.308467) (xy 91.326462 -7.28726) (xy 91.340794 -7.251842) (xy 91.375943 -7.183997)
			(xy 91.418157 -7.120308) (xy 91.46695 -7.061507) (xy 91.521761 -7.008271) (xy 91.58196 -6.961213)
			(xy 91.646853 -6.920874) (xy 91.715694 -6.887719) (xy 91.78769 -6.862129) (xy 91.862013 -6.844398)
			(xy 91.937808 -6.83473) (xy 92.014203 -6.833238) (xy 92.090317 -6.839937) (xy 92.165276 -6.854751)
			(xy 92.238217 -6.877509) (xy 92.308301 -6.90795) (xy 92.37472 -6.945724) (xy 92.436711 -6.990394)
			(xy 92.49356 -7.041448) (xy 92.544613 -7.098298) (xy 92.589283 -7.16029) (xy 92.627055 -7.226709)
			(xy 92.657495 -7.296793) (xy 92.680252 -7.369735) (xy 92.695065 -7.444694) (xy 92.701763 -7.520809)
			(xy 92.700269 -7.597203) (xy 92.6906 -7.672998) (xy 92.672868 -7.747321) (xy 92.647277 -7.819317)
			(xy 92.61412 -7.888157) (xy 92.57378 -7.953049) (xy 92.526721 -8.013247) (xy 92.473485 -8.068058)
			(xy 92.414683 -8.11685) (xy 92.350993 -8.159063) (xy 92.283148 -8.19421) (xy 92.24772 -8.208518)
			(xy 92.22648 -8.217203) (xy 92.204051 -8.230991) (xy 93.154757 -8.230991) (xy 93.160779 -8.114808)
			(xy 93.174802 -7.999317) (xy 93.19676 -7.885069) (xy 93.226547 -7.772608) (xy 93.264022 -7.66247)
			(xy 93.309007 -7.55518) (xy 93.361286 -7.451249) (xy 93.420611 -7.351173) (xy 93.486699 -7.255427)
			(xy 93.559235 -7.16447) (xy 93.637874 -7.078734) (xy 93.72224 -6.998627) (xy 93.811932 -6.924531)
			(xy 93.906522 -6.856801) (xy 94.00556 -6.795757) (xy 94.108573 -6.741692) (xy 94.21507 -6.694862)
			(xy 94.324545 -6.655491) (xy 94.436475 -6.623767) (xy 94.550327 -6.599841) (xy 94.665559 -6.583827)
			(xy 94.781621 -6.5758) (xy 94.83979 -6.575298) (xy 94.897959 -6.5758) (xy 95.014021 -6.583827) (xy 95.129253 -6.599841)
			(xy 95.243105 -6.623767) (xy 95.355035 -6.655491) (xy 95.46451 -6.694862) (xy 95.571007 -6.741692)
			(xy 95.67402 -6.795757) (xy 95.773058 -6.856801) (xy 95.867648 -6.924531) (xy 95.95734 -6.998627)
			(xy 96.041706 -7.078734) (xy 96.120345 -7.16447) (xy 96.192881 -7.255427) (xy 96.258969 -7.351173)
			(xy 96.318294 -7.451249) (xy 96.370573 -7.55518) (xy 96.415558 -7.66247) (xy 96.453033 -7.772608)
			(xy 96.48282 -7.885069) (xy 96.504778 -7.999317) (xy 96.518801 -8.114808) (xy 96.524823 -8.230991)
			(xy 96.522815 -8.347313) (xy 96.512786 -8.463219) (xy 96.494785 -8.578156) (xy 96.468897 -8.691579)
			(xy 96.435246 -8.802944) (xy 96.393992 -8.911723) (xy 96.345331 -9.017397) (xy 96.289495 -9.119461)
			(xy 96.226752 -9.21743) (xy 96.157398 -9.310837) (xy 96.081766 -9.399237) (xy 96.000215 -9.482208)
			(xy 95.913134 -9.559355) (xy 95.820938 -9.63031) (xy 95.724066 -9.694736) (xy 95.622981 -9.752325)
			(xy 95.518163 -9.802802) (xy 95.410112 -9.845928) (xy 95.299344 -9.881497) (xy 95.186385 -9.909339)
			(xy 95.071775 -9.929321) (xy 94.95606 -9.941348) (xy 94.83979 -9.945364) (xy 94.72352 -9.941348)
			(xy 94.607805 -9.929321) (xy 94.493195 -9.909339) (xy 94.380236 -9.881497) (xy 94.269468 -9.845928)
			(xy 94.161417 -9.802802) (xy 94.056599 -9.752325) (xy 93.955514 -9.694736) (xy 93.858642 -9.63031)
			(xy 93.766446 -9.559355) (xy 93.679365 -9.482208) (xy 93.597814 -9.399237) (xy 93.522182 -9.310837)
			(xy 93.452828 -9.21743) (xy 93.390085 -9.119461) (xy 93.334249 -9.017397) (xy 93.285588 -8.911723)
			(xy 93.244334 -8.802944) (xy 93.210683 -8.691579) (xy 93.184795 -8.578156) (xy 93.166794 -8.463219)
			(xy 93.156765 -8.347313) (xy 93.154757 -8.230991) (xy 92.204051 -8.230991) (xy 92.187388 -8.241234)
			(xy 92.153245 -8.271892) (xy 92.12516 -8.308182) (xy 92.104047 -8.348924) (xy 92.090592 -8.392794)
			(xy 92.085231 -8.438368) (xy 92.088139 -8.484163) (xy 92.099221 -8.528692) (xy 92.118117 -8.570509)
			(xy 92.144214 -8.608253) (xy 92.16009 -8.624824) (xy 96.40824 -12.872974) (xy 96.439228 -12.882118)
			(xy 96.465176 -12.890265) (xy 96.514628 -12.912899) (xy 96.560365 -12.942326) (xy 96.601461 -12.977948)
			(xy 96.637082 -13.019045) (xy 96.666507 -13.064783) (xy 96.689139 -13.114236) (xy 96.697292 -13.140182)
			(xy 96.706436 -13.17117) (xy 101.81082 -18.275808) (xy 101.81082 -52.704746) (xy 94.482158 -60.033408)
			(xy 93.723206 -60.033408) (xy 93.700886 -60.033853) (xy 93.656932 -60.041651) (xy 93.615016 -60.057009)
			(xy 93.576429 -60.079453) (xy 93.542356 -60.108293) (xy 93.513845 -60.142643) (xy 93.491775 -60.181446)
			(xy 93.476823 -60.223508) (xy 93.46945 -60.267535) (xy 93.469882 -60.312173) (xy 93.478106 -60.356049)
			(xy 93.493869 -60.397814) (xy 93.516687 -60.436182) (xy 93.545857 -60.469974) (xy 93.580481 -60.498149)
			(xy 93.599762 -60.509404) (xy 93.682419 -60.556076) (xy 93.844259 -60.655314) (xy 94.001792 -60.761256)
			(xy 94.15474 -60.873716) (xy 94.302833 -60.992497) (xy 94.445811 -61.117389) (xy 94.58342 -61.248171)
			(xy 94.71542 -61.384613) (xy 94.841577 -61.526476) (xy 94.961668 -61.673508) (xy 95.075483 -61.82545)
			(xy 95.182821 -61.982036) (xy 95.283492 -62.142989) (xy 95.377319 -62.308025) (xy 95.464137 -62.476853)
			(xy 95.543793 -62.649177) (xy 95.616146 -62.824691) (xy 95.681069 -63.003088) (xy 95.738448 -63.184053)
			(xy 95.78818 -63.367266) (xy 95.83018 -63.552405) (xy 95.864372 -63.739144) (xy 95.890697 -63.927153)
			(xy 95.909108 -64.116101) (xy 95.919572 -64.305656) (xy 95.922072 -64.495482) (xy 95.916602 -64.685247)
			(xy 95.903173 -64.874614) (xy 95.881808 -65.063251) (xy 95.852545 -65.250826) (xy 95.815435 -65.437006)
			(xy 95.770543 -65.621465) (xy 95.71795 -65.803878) (xy 95.657746 -65.983922) (xy 95.59004 -66.161282)
			(xy 95.514949 -66.335643) (xy 95.432607 -66.506699) (xy 95.343158 -66.674148) (xy 95.24676 -66.837696)
			(xy 95.143582 -66.997054) (xy 95.033808 -67.15194) (xy 94.917629 -67.302084) (xy 94.795252 -67.447219)
			(xy 94.666891 -67.587089) (xy 94.532772 -67.72145) (xy 94.393133 -67.850063) (xy 94.248219 -67.972702)
			(xy 94.098285 -68.089151) (xy 93.943596 -68.199204) (xy 93.784425 -68.302668) (xy 93.621051 -68.399361)
			(xy 93.453763 -68.489112) (xy 93.282856 -68.571762) (xy 93.108631 -68.647167) (xy 92.931394 -68.715193)
			(xy 92.751458 -68.775721) (xy 92.569141 -68.828643) (xy 92.384763 -68.873867) (xy 92.198649 -68.911312)
			(xy 92.011128 -68.940914) (xy 91.82253 -68.962619) (xy 91.633187 -68.976389) (xy 91.443432 -68.982201)
			(xy 91.253601 -68.980043) (xy 91.064028 -68.969921) (xy 90.875047 -68.95185) (xy 90.686991 -68.925864)
			(xy 90.500191 -68.892009) (xy 90.314977 -68.850343) (xy 90.131674 -68.80094) (xy 89.950606 -68.743888)
			(xy 89.772093 -68.679287) (xy 89.596448 -68.60725) (xy 89.423981 -68.527905) (xy 89.254996 -68.441391)
			(xy 89.089792 -68.347862) (xy 88.928658 -68.247481) (xy 88.771879 -68.140426) (xy 88.619731 -68.026885)
			(xy 88.472483 -67.907058) (xy 88.330394 -67.781157) (xy 88.193714 -67.649404) (xy 88.062684 -67.51203)
			(xy 87.937535 -67.369278) (xy 87.818487 -67.221399) (xy 87.705751 -67.068654) (xy 87.599525 -66.911312)
			(xy 87.499996 -66.749651) (xy 87.40734 -66.583955) (xy 87.32172 -66.414516) (xy 87.243287 -66.241632)
			(xy 87.172178 -66.065609) (xy 87.10852 -65.886757) (xy 87.052425 -65.705391) (xy 87.003991 -65.52183)
			(xy 86.963303 -65.336399) (xy 86.930434 -65.149422) (xy 86.905441 -64.961232) (xy 86.888369 -64.772158)
			(xy 86.879247 -64.582534) (xy 86.878092 -64.392694) (xy 86.884905 -64.202973) (xy 86.899675 -64.013705)
			(xy 86.922376 -63.825224) (xy 86.952967 -63.637862) (xy 86.991394 -63.451949) (xy 87.037591 -63.267812)
			(xy 87.091475 -63.085777) (xy 87.121746 -62.99581) (xy 87.12859 -62.974085) (xy 87.135448 -62.929065)
			(xy 87.134173 -62.883542) (xy 87.124807 -62.838976) (xy 87.107648 -62.796792) (xy 87.083247 -62.758341)
			(xy 87.052385 -62.724853) (xy 87.016049 -62.697401) (xy 86.975403 -62.676864) (xy 86.931747 -62.663899)
			(xy 86.88648 -62.65892) (xy 86.84105 -62.662088) (xy 86.796912 -62.673301) (xy 86.755479 -62.6922)
			(xy 86.718076 -62.71818) (xy 86.70163 -62.733936) (xy 78.84287 -70.592696) (xy 76.985368 -70.592696)
			(xy 69.278246 -78.299818) (xy 75.014079 -78.299818) (xy 75.018104 -78.144845) (xy 75.030166 -77.990291)
			(xy 75.050235 -77.83657) (xy 75.078255 -77.684099) (xy 75.114151 -77.533287) (xy 75.157827 -77.384542)
			(xy 75.209164 -77.238264) (xy 75.268024 -77.094848) (xy 75.334249 -76.95468) (xy 75.40766 -76.818139)
			(xy 75.488059 -76.685592) (xy 75.575229 -76.557396) (xy 75.668935 -76.433898) (xy 75.768926 -76.31543)
			(xy 75.87493 -76.202312) (xy 75.986663 -76.094848) (xy 76.103823 -75.993328) (xy 76.226094 -75.898026)
			(xy 76.353147 -75.809199) (xy 76.484639 -75.727087) (xy 76.620216 -75.651909) (xy 76.759512 -75.583871)
			(xy 76.902152 -75.523154) (xy 77.047751 -75.469922) (xy 77.195917 -75.424319) (xy 77.34625 -75.386468)
			(xy 77.498345 -75.356471) (xy 77.651792 -75.334409) (xy 77.806177 -75.320341) (xy 77.961085 -75.314305)
			(xy 78.116096 -75.316317) (xy 78.270795 -75.326372) (xy 78.424763 -75.344444) (xy 78.577585 -75.370482)
			(xy 78.72885 -75.404418) (xy 78.87815 -75.446159) (xy 79.025082 -75.495593) (xy 79.16925 -75.552586)
			(xy 79.310265 -75.616986) (xy 79.447748 -75.688618) (xy 79.581328 -75.767289) (xy 79.710644 -75.852788)
			(xy 79.835348 -75.944883) (xy 79.955104 -76.043327) (xy 80.069589 -76.147854) (xy 80.178495 -76.258183)
			(xy 80.281527 -76.374015) (xy 80.378408 -76.495039) (xy 80.468876 -76.620928) (xy 80.552689 -76.751343)
			(xy 80.62962 -76.885933) (xy 80.699461 -77.024334) (xy 80.762025 -77.166174) (xy 80.817142 -77.31107)
			(xy 80.864665 -77.458631) (xy 80.904464 -77.60846) (xy 80.936433 -77.760153) (xy 80.960485 -77.9133)
			(xy 80.976556 -78.06749) (xy 80.984603 -78.222306) (xy 80.985106 -78.299818) (xy 80.984603 -78.37733)
			(xy 80.976556 -78.532146) (xy 80.960485 -78.686336) (xy 80.936433 -78.839483) (xy 80.904464 -78.991176)
			(xy 80.864665 -79.141005) (xy 80.820358 -79.278581) (xy 83.869014 -79.278581) (xy 83.869014 -79.207259)
			(xy 83.877 -79.136385) (xy 83.89287 -79.06685) (xy 83.916427 -78.99953) (xy 83.947372 -78.935271)
			(xy 83.985318 -78.87488) (xy 84.029787 -78.819118) (xy 84.08022 -78.768685) (xy 84.135982 -78.724216)
			(xy 84.196373 -78.68627) (xy 84.260632 -78.655325) (xy 84.327952 -78.631768) (xy 84.397487 -78.615898)
			(xy 84.468361 -78.607912) (xy 84.504022 -78.607412) (xy 84.539683 -78.607912) (xy 84.610557 -78.615898)
			(xy 84.680092 -78.631768) (xy 84.747412 -78.655325) (xy 84.811671 -78.68627) (xy 84.872062 -78.724216)
			(xy 84.927824 -78.768685) (xy 84.978257 -78.819118) (xy 85.022726 -78.87488) (xy 85.060672 -78.935271)
			(xy 85.091617 -78.99953) (xy 85.115174 -79.06685) (xy 85.131044 -79.136385) (xy 85.13903 -79.207259)
			(xy 85.13903 -79.278581) (xy 86.673428 -79.278581) (xy 86.673428 -79.207259) (xy 86.681414 -79.136385)
			(xy 86.697284 -79.06685) (xy 86.720841 -78.99953) (xy 86.751786 -78.935271) (xy 86.789732 -78.87488)
			(xy 86.834201 -78.819118) (xy 86.884634 -78.768685) (xy 86.940396 -78.724216) (xy 87.000787 -78.68627)
			(xy 87.065046 -78.655325) (xy 87.132366 -78.631768) (xy 87.201901 -78.615898) (xy 87.272775 -78.607912)
			(xy 87.308436 -78.607412) (xy 87.344097 -78.607912) (xy 87.414971 -78.615898) (xy 87.484506 -78.631768)
			(xy 87.551826 -78.655325) (xy 87.616085 -78.68627) (xy 87.676476 -78.724216) (xy 87.732238 -78.768685)
			(xy 87.782671 -78.819118) (xy 87.82714 -78.87488) (xy 87.865086 -78.935271) (xy 87.896031 -78.99953)
			(xy 87.919588 -79.06685) (xy 87.935458 -79.136385) (xy 87.943444 -79.207259) (xy 87.943444 -79.278581)
			(xy 87.935458 -79.349455) (xy 87.919588 -79.41899) (xy 87.896031 -79.48631) (xy 87.865086 -79.550569)
			(xy 87.82714 -79.61096) (xy 87.782671 -79.666722) (xy 87.732238 -79.717155) (xy 87.676476 -79.761624)
			(xy 87.616085 -79.79957) (xy 87.551826 -79.830515) (xy 87.484506 -79.854072) (xy 87.414971 -79.869942)
			(xy 87.344097 -79.877928) (xy 87.272775 -79.877928) (xy 87.201901 -79.869942) (xy 87.132366 -79.854072)
			(xy 87.065046 -79.830515) (xy 87.000787 -79.79957) (xy 86.940396 -79.761624) (xy 86.884634 -79.717155)
			(xy 86.834201 -79.666722) (xy 86.789732 -79.61096) (xy 86.751786 -79.550569) (xy 86.720841 -79.48631)
			(xy 86.697284 -79.41899) (xy 86.681414 -79.349455) (xy 86.673428 -79.278581) (xy 85.13903 -79.278581)
			(xy 85.131044 -79.349455) (xy 85.115174 -79.41899) (xy 85.091617 -79.48631) (xy 85.060672 -79.550569)
			(xy 85.022726 -79.61096) (xy 84.978257 -79.666722) (xy 84.927824 -79.717155) (xy 84.872062 -79.761624)
			(xy 84.811671 -79.79957) (xy 84.747412 -79.830515) (xy 84.680092 -79.854072) (xy 84.610557 -79.869942)
			(xy 84.539683 -79.877928) (xy 84.468361 -79.877928) (xy 84.397487 -79.869942) (xy 84.327952 -79.854072)
			(xy 84.260632 -79.830515) (xy 84.196373 -79.79957) (xy 84.135982 -79.761624) (xy 84.08022 -79.717155)
			(xy 84.029787 -79.666722) (xy 83.985318 -79.61096) (xy 83.947372 -79.550569) (xy 83.916427 -79.48631)
			(xy 83.89287 -79.41899) (xy 83.877 -79.349455) (xy 83.869014 -79.278581) (xy 80.820358 -79.278581)
			(xy 80.817142 -79.288566) (xy 80.762025 -79.433462) (xy 80.699461 -79.575302) (xy 80.62962 -79.713703)
			(xy 80.552689 -79.848293) (xy 80.468876 -79.978708) (xy 80.378408 -80.104597) (xy 80.281527 -80.225621)
			(xy 80.178495 -80.341453) (xy 80.069589 -80.451782) (xy 79.955104 -80.556309) (xy 79.835348 -80.654753)
			(xy 79.710644 -80.746848) (xy 79.581328 -80.832347) (xy 79.447748 -80.911018) (xy 79.337045 -80.968697)
			(xy 83.889842 -80.968697) (xy 83.889842 -80.897375) (xy 83.897828 -80.826501) (xy 83.913698 -80.756966)
			(xy 83.937255 -80.689646) (xy 83.9682 -80.625387) (xy 84.006146 -80.564996) (xy 84.050615 -80.509234)
			(xy 84.101048 -80.458801) (xy 84.15681 -80.414332) (xy 84.217201 -80.376386) (xy 84.28146 -80.345441)
			(xy 84.34878 -80.321884) (xy 84.418315 -80.306014) (xy 84.489189 -80.298028) (xy 84.52485 -80.297528)
			(xy 84.560511 -80.298028) (xy 84.631385 -80.306014) (xy 84.70092 -80.321884) (xy 84.76824 -80.345441)
			(xy 84.832499 -80.376386) (xy 84.89289 -80.414332) (xy 84.948652 -80.458801) (xy 84.999085 -80.509234)
			(xy 85.043554 -80.564996) (xy 85.0815 -80.625387) (xy 85.112445 -80.689646) (xy 85.136002 -80.756966)
			(xy 85.151872 -80.826501) (xy 85.159858 -80.897375) (xy 85.159858 -80.968697) (xy 86.694256 -80.968697)
			(xy 86.694256 -80.897375) (xy 86.702242 -80.826501) (xy 86.718112 -80.756966) (xy 86.741669 -80.689646)
			(xy 86.772614 -80.625387) (xy 86.81056 -80.564996) (xy 86.855029 -80.509234) (xy 86.905462 -80.458801)
			(xy 86.961224 -80.414332) (xy 87.021615 -80.376386) (xy 87.085874 -80.345441) (xy 87.153194 -80.321884)
			(xy 87.222729 -80.306014) (xy 87.293603 -80.298028) (xy 87.329264 -80.297528) (xy 87.364925 -80.298028)
			(xy 87.435799 -80.306014) (xy 87.505334 -80.321884) (xy 87.572654 -80.345441) (xy 87.636913 -80.376386)
			(xy 87.697304 -80.414332) (xy 87.753066 -80.458801) (xy 87.803499 -80.509234) (xy 87.847968 -80.564996)
			(xy 87.885914 -80.625387) (xy 87.916859 -80.689646) (xy 87.940416 -80.756966) (xy 87.956286 -80.826501)
			(xy 87.964272 -80.897375) (xy 87.964272 -80.968697) (xy 87.956286 -81.039571) (xy 87.940416 -81.109106)
			(xy 87.916859 -81.176426) (xy 87.885914 -81.240685) (xy 87.847968 -81.301076) (xy 87.803499 -81.356838)
			(xy 87.753066 -81.407271) (xy 87.697304 -81.45174) (xy 87.636913 -81.489686) (xy 87.572654 -81.520631)
			(xy 87.505334 -81.544188) (xy 87.435799 -81.560058) (xy 87.364925 -81.568044) (xy 87.293603 -81.568044)
			(xy 87.222729 -81.560058) (xy 87.153194 -81.544188) (xy 87.085874 -81.520631) (xy 87.021615 -81.489686)
			(xy 86.961224 -81.45174) (xy 86.905462 -81.407271) (xy 86.855029 -81.356838) (xy 86.81056 -81.301076)
			(xy 86.772614 -81.240685) (xy 86.741669 -81.176426) (xy 86.718112 -81.109106) (xy 86.702242 -81.039571)
			(xy 86.694256 -80.968697) (xy 85.159858 -80.968697) (xy 85.151872 -81.039571) (xy 85.136002 -81.109106)
			(xy 85.112445 -81.176426) (xy 85.0815 -81.240685) (xy 85.043554 -81.301076) (xy 84.999085 -81.356838)
			(xy 84.948652 -81.407271) (xy 84.89289 -81.45174) (xy 84.832499 -81.489686) (xy 84.76824 -81.520631)
			(xy 84.70092 -81.544188) (xy 84.631385 -81.560058) (xy 84.560511 -81.568044) (xy 84.489189 -81.568044)
			(xy 84.418315 -81.560058) (xy 84.34878 -81.544188) (xy 84.28146 -81.520631) (xy 84.217201 -81.489686)
			(xy 84.15681 -81.45174) (xy 84.101048 -81.407271) (xy 84.050615 -81.356838) (xy 84.006146 -81.301076)
			(xy 83.9682 -81.240685) (xy 83.937255 -81.176426) (xy 83.913698 -81.109106) (xy 83.897828 -81.039571)
			(xy 83.889842 -80.968697) (xy 79.337045 -80.968697) (xy 79.310265 -80.98265) (xy 79.16925 -81.04705)
			(xy 79.025082 -81.104043) (xy 78.87815 -81.153477) (xy 78.72885 -81.195218) (xy 78.577585 -81.229154)
			(xy 78.424763 -81.255192) (xy 78.270795 -81.273264) (xy 78.116096 -81.283319) (xy 77.961085 -81.285331)
			(xy 77.806177 -81.279295) (xy 77.651792 -81.265227) (xy 77.498345 -81.243165) (xy 77.34625 -81.213168)
			(xy 77.195917 -81.175317) (xy 77.047751 -81.129714) (xy 76.902152 -81.076482) (xy 76.759512 -81.015765)
			(xy 76.620216 -80.947727) (xy 76.484639 -80.872549) (xy 76.353147 -80.790437) (xy 76.226094 -80.70161)
			(xy 76.103823 -80.606308) (xy 75.986663 -80.504788) (xy 75.87493 -80.397324) (xy 75.768926 -80.284206)
			(xy 75.668935 -80.165738) (xy 75.575229 -80.04224) (xy 75.488059 -79.914044) (xy 75.40766 -79.781497)
			(xy 75.334249 -79.644956) (xy 75.268024 -79.504788) (xy 75.209164 -79.361372) (xy 75.157827 -79.215094)
			(xy 75.114151 -79.066349) (xy 75.078255 -78.915537) (xy 75.050235 -78.763066) (xy 75.030166 -78.609345)
			(xy 75.018104 -78.454791) (xy 75.014079 -78.299818) (xy 69.278246 -78.299818) (xy 64.754913 -82.823151)
			(xy 83.889842 -82.823151) (xy 83.889842 -82.751829) (xy 83.897828 -82.680955) (xy 83.913698 -82.61142)
			(xy 83.937255 -82.5441) (xy 83.9682 -82.479841) (xy 84.006146 -82.41945) (xy 84.050615 -82.363688)
			(xy 84.101048 -82.313255) (xy 84.15681 -82.268786) (xy 84.217201 -82.23084) (xy 84.28146 -82.199895)
			(xy 84.34878 -82.176338) (xy 84.418315 -82.160468) (xy 84.489189 -82.152482) (xy 84.52485 -82.151982)
			(xy 84.560511 -82.152482) (xy 84.631385 -82.160468) (xy 84.70092 -82.176338) (xy 84.76824 -82.199895)
			(xy 84.832499 -82.23084) (xy 84.89289 -82.268786) (xy 84.948652 -82.313255) (xy 84.999085 -82.363688)
			(xy 85.043554 -82.41945) (xy 85.0815 -82.479841) (xy 85.112445 -82.5441) (xy 85.136002 -82.61142)
			(xy 85.151872 -82.680955) (xy 85.159858 -82.751829) (xy 85.159858 -82.823151) (xy 86.694256 -82.823151)
			(xy 86.694256 -82.751829) (xy 86.702242 -82.680955) (xy 86.718112 -82.61142) (xy 86.741669 -82.5441)
			(xy 86.772614 -82.479841) (xy 86.81056 -82.41945) (xy 86.855029 -82.363688) (xy 86.905462 -82.313255)
			(xy 86.961224 -82.268786) (xy 87.021615 -82.23084) (xy 87.085874 -82.199895) (xy 87.153194 -82.176338)
			(xy 87.222729 -82.160468) (xy 87.293603 -82.152482) (xy 87.329264 -82.151982) (xy 87.364925 -82.152482)
			(xy 87.435799 -82.160468) (xy 87.505334 -82.176338) (xy 87.572654 -82.199895) (xy 87.636913 -82.23084)
			(xy 87.697304 -82.268786) (xy 87.753066 -82.313255) (xy 87.803499 -82.363688) (xy 87.847968 -82.41945)
			(xy 87.885914 -82.479841) (xy 87.916859 -82.5441) (xy 87.940416 -82.61142) (xy 87.956286 -82.680955)
			(xy 87.964272 -82.751829) (xy 87.964272 -82.823151) (xy 87.956286 -82.894025) (xy 87.940416 -82.96356)
			(xy 87.916859 -83.03088) (xy 87.885914 -83.095139) (xy 87.847968 -83.15553) (xy 87.803499 -83.211292)
			(xy 87.753066 -83.261725) (xy 87.697304 -83.306194) (xy 87.636913 -83.34414) (xy 87.572654 -83.375085)
			(xy 87.505334 -83.398642) (xy 87.435799 -83.414512) (xy 87.364925 -83.422498) (xy 87.293603 -83.422498)
			(xy 87.222729 -83.414512) (xy 87.153194 -83.398642) (xy 87.085874 -83.375085) (xy 87.021615 -83.34414)
			(xy 86.961224 -83.306194) (xy 86.905462 -83.261725) (xy 86.855029 -83.211292) (xy 86.81056 -83.15553)
			(xy 86.772614 -83.095139) (xy 86.741669 -83.03088) (xy 86.718112 -82.96356) (xy 86.702242 -82.894025)
			(xy 86.694256 -82.823151) (xy 85.159858 -82.823151) (xy 85.151872 -82.894025) (xy 85.136002 -82.96356)
			(xy 85.112445 -83.03088) (xy 85.0815 -83.095139) (xy 85.043554 -83.15553) (xy 84.999085 -83.211292)
			(xy 84.948652 -83.261725) (xy 84.89289 -83.306194) (xy 84.832499 -83.34414) (xy 84.76824 -83.375085)
			(xy 84.70092 -83.398642) (xy 84.631385 -83.414512) (xy 84.560511 -83.422498) (xy 84.489189 -83.422498)
			(xy 84.418315 -83.414512) (xy 84.34878 -83.398642) (xy 84.28146 -83.375085) (xy 84.217201 -83.34414)
			(xy 84.15681 -83.306194) (xy 84.101048 -83.261725) (xy 84.050615 -83.211292) (xy 84.006146 -83.15553)
			(xy 83.9682 -83.095139) (xy 83.937255 -83.03088) (xy 83.913698 -82.96356) (xy 83.897828 -82.894025)
			(xy 83.889842 -82.823151) (xy 64.754913 -82.823151) (xy 62.383315 -85.194749) (xy 83.889842 -85.194749)
			(xy 83.889842 -85.123427) (xy 83.897828 -85.052553) (xy 83.913698 -84.983018) (xy 83.937255 -84.915698)
			(xy 83.9682 -84.851439) (xy 84.006146 -84.791048) (xy 84.050615 -84.735286) (xy 84.101048 -84.684853)
			(xy 84.15681 -84.640384) (xy 84.217201 -84.602438) (xy 84.28146 -84.571493) (xy 84.34878 -84.547936)
			(xy 84.418315 -84.532066) (xy 84.489189 -84.52408) (xy 84.52485 -84.52358) (xy 84.560511 -84.52408)
			(xy 84.631385 -84.532066) (xy 84.70092 -84.547936) (xy 84.76824 -84.571493) (xy 84.832499 -84.602438)
			(xy 84.89289 -84.640384) (xy 84.948652 -84.684853) (xy 84.999085 -84.735286) (xy 85.043554 -84.791048)
			(xy 85.0815 -84.851439) (xy 85.112445 -84.915698) (xy 85.136002 -84.983018) (xy 85.151872 -85.052553)
			(xy 85.159858 -85.123427) (xy 85.159858 -85.194749) (xy 86.694256 -85.194749) (xy 86.694256 -85.123427)
			(xy 86.702242 -85.052553) (xy 86.718112 -84.983018) (xy 86.741669 -84.915698) (xy 86.772614 -84.851439)
			(xy 86.81056 -84.791048) (xy 86.855029 -84.735286) (xy 86.905462 -84.684853) (xy 86.961224 -84.640384)
			(xy 87.021615 -84.602438) (xy 87.085874 -84.571493) (xy 87.153194 -84.547936) (xy 87.222729 -84.532066)
			(xy 87.293603 -84.52408) (xy 87.329264 -84.52358) (xy 87.364925 -84.52408) (xy 87.435799 -84.532066)
			(xy 87.505334 -84.547936) (xy 87.572654 -84.571493) (xy 87.636913 -84.602438) (xy 87.697304 -84.640384)
			(xy 87.753066 -84.684853) (xy 87.803499 -84.735286) (xy 87.847968 -84.791048) (xy 87.885914 -84.851439)
			(xy 87.916859 -84.915698) (xy 87.940416 -84.983018) (xy 87.956286 -85.052553) (xy 87.964272 -85.123427)
			(xy 87.964272 -85.194749) (xy 87.956286 -85.265623) (xy 87.940416 -85.335158) (xy 87.916859 -85.402478)
			(xy 87.885914 -85.466737) (xy 87.847968 -85.527128) (xy 87.803499 -85.58289) (xy 87.753066 -85.633323)
			(xy 87.697304 -85.677792) (xy 87.636913 -85.715738) (xy 87.572654 -85.746683) (xy 87.505334 -85.77024)
			(xy 87.435799 -85.78611) (xy 87.364925 -85.794096) (xy 87.293603 -85.794096) (xy 87.222729 -85.78611)
			(xy 87.153194 -85.77024) (xy 87.085874 -85.746683) (xy 87.021615 -85.715738) (xy 86.961224 -85.677792)
			(xy 86.905462 -85.633323) (xy 86.855029 -85.58289) (xy 86.81056 -85.527128) (xy 86.772614 -85.466737)
			(xy 86.741669 -85.402478) (xy 86.718112 -85.335158) (xy 86.702242 -85.265623) (xy 86.694256 -85.194749)
			(xy 85.159858 -85.194749) (xy 85.151872 -85.265623) (xy 85.136002 -85.335158) (xy 85.112445 -85.402478)
			(xy 85.0815 -85.466737) (xy 85.043554 -85.527128) (xy 84.999085 -85.58289) (xy 84.948652 -85.633323)
			(xy 84.89289 -85.677792) (xy 84.832499 -85.715738) (xy 84.76824 -85.746683) (xy 84.70092 -85.77024)
			(xy 84.631385 -85.78611) (xy 84.560511 -85.794096) (xy 84.489189 -85.794096) (xy 84.418315 -85.78611)
			(xy 84.34878 -85.77024) (xy 84.28146 -85.746683) (xy 84.217201 -85.715738) (xy 84.15681 -85.677792)
			(xy 84.101048 -85.633323) (xy 84.050615 -85.58289) (xy 84.006146 -85.527128) (xy 83.9682 -85.466737)
			(xy 83.937255 -85.402478) (xy 83.913698 -85.335158) (xy 83.897828 -85.265623) (xy 83.889842 -85.194749)
			(xy 62.383315 -85.194749) (xy 60.557309 -87.020755) (xy 83.889842 -87.020755) (xy 83.889842 -86.949433)
			(xy 83.897828 -86.878559) (xy 83.913698 -86.809024) (xy 83.937255 -86.741704) (xy 83.9682 -86.677445)
			(xy 84.006146 -86.617054) (xy 84.050615 -86.561292) (xy 84.101048 -86.510859) (xy 84.15681 -86.46639)
			(xy 84.217201 -86.428444) (xy 84.28146 -86.397499) (xy 84.34878 -86.373942) (xy 84.418315 -86.358072)
			(xy 84.489189 -86.350086) (xy 84.52485 -86.349586) (xy 84.560511 -86.350086) (xy 84.631385 -86.358072)
			(xy 84.70092 -86.373942) (xy 84.76824 -86.397499) (xy 84.832499 -86.428444) (xy 84.89289 -86.46639)
			(xy 84.948652 -86.510859) (xy 84.999085 -86.561292) (xy 85.043554 -86.617054) (xy 85.0815 -86.677445)
			(xy 85.112445 -86.741704) (xy 85.136002 -86.809024) (xy 85.151872 -86.878559) (xy 85.159858 -86.949433)
			(xy 85.159858 -87.020755) (xy 86.694256 -87.020755) (xy 86.694256 -86.949433) (xy 86.702242 -86.878559)
			(xy 86.718112 -86.809024) (xy 86.741669 -86.741704) (xy 86.772614 -86.677445) (xy 86.81056 -86.617054)
			(xy 86.855029 -86.561292) (xy 86.905462 -86.510859) (xy 86.961224 -86.46639) (xy 87.021615 -86.428444)
			(xy 87.085874 -86.397499) (xy 87.153194 -86.373942) (xy 87.222729 -86.358072) (xy 87.293603 -86.350086)
			(xy 87.329264 -86.349586) (xy 87.364925 -86.350086) (xy 87.435799 -86.358072) (xy 87.505334 -86.373942)
			(xy 87.572654 -86.397499) (xy 87.636913 -86.428444) (xy 87.697304 -86.46639) (xy 87.753066 -86.510859)
			(xy 87.803499 -86.561292) (xy 87.847968 -86.617054) (xy 87.885914 -86.677445) (xy 87.916859 -86.741704)
			(xy 87.940416 -86.809024) (xy 87.956286 -86.878559) (xy 87.964272 -86.949433) (xy 87.964272 -87.020755)
			(xy 87.956286 -87.091629) (xy 87.940416 -87.161164) (xy 87.916859 -87.228484) (xy 87.885914 -87.292743)
			(xy 87.847968 -87.353134) (xy 87.803499 -87.408896) (xy 87.753066 -87.459329) (xy 87.697304 -87.503798)
			(xy 87.636913 -87.541744) (xy 87.572654 -87.572689) (xy 87.505334 -87.596246) (xy 87.435799 -87.612116)
			(xy 87.364925 -87.620102) (xy 87.293603 -87.620102) (xy 87.222729 -87.612116) (xy 87.153194 -87.596246)
			(xy 87.085874 -87.572689) (xy 87.021615 -87.541744) (xy 86.961224 -87.503798) (xy 86.905462 -87.459329)
			(xy 86.855029 -87.408896) (xy 86.81056 -87.353134) (xy 86.772614 -87.292743) (xy 86.741669 -87.228484)
			(xy 86.718112 -87.161164) (xy 86.702242 -87.091629) (xy 86.694256 -87.020755) (xy 85.159858 -87.020755)
			(xy 85.151872 -87.091629) (xy 85.136002 -87.161164) (xy 85.112445 -87.228484) (xy 85.0815 -87.292743)
			(xy 85.043554 -87.353134) (xy 84.999085 -87.408896) (xy 84.948652 -87.459329) (xy 84.89289 -87.503798)
			(xy 84.832499 -87.541744) (xy 84.76824 -87.572689) (xy 84.70092 -87.596246) (xy 84.631385 -87.612116)
			(xy 84.560511 -87.620102) (xy 84.489189 -87.620102) (xy 84.418315 -87.612116) (xy 84.34878 -87.596246)
			(xy 84.28146 -87.572689) (xy 84.217201 -87.541744) (xy 84.15681 -87.503798) (xy 84.101048 -87.459329)
			(xy 84.050615 -87.408896) (xy 84.006146 -87.353134) (xy 83.9682 -87.292743) (xy 83.937255 -87.228484)
			(xy 83.913698 -87.161164) (xy 83.897828 -87.091629) (xy 83.889842 -87.020755) (xy 60.557309 -87.020755)
			(xy 58.984033 -88.594031) (xy 83.866982 -88.594031) (xy 83.866982 -88.522709) (xy 83.874968 -88.451835)
			(xy 83.890838 -88.3823) (xy 83.914395 -88.31498) (xy 83.94534 -88.250721) (xy 83.983286 -88.19033)
			(xy 84.027755 -88.134568) (xy 84.078188 -88.084135) (xy 84.13395 -88.039666) (xy 84.194341 -88.00172)
			(xy 84.2586 -87.970775) (xy 84.32592 -87.947218) (xy 84.395455 -87.931348) (xy 84.466329 -87.923362)
			(xy 84.50199 -87.922862) (xy 84.537651 -87.923362) (xy 84.608525 -87.931348) (xy 84.67806 -87.947218)
			(xy 84.74538 -87.970775) (xy 84.809639 -88.00172) (xy 84.87003 -88.039666) (xy 84.925792 -88.084135)
			(xy 84.976225 -88.134568) (xy 85.020694 -88.19033) (xy 85.05864 -88.250721) (xy 85.089585 -88.31498)
			(xy 85.113142 -88.3823) (xy 85.129012 -88.451835) (xy 85.136998 -88.522709) (xy 85.136998 -88.594031)
			(xy 86.671396 -88.594031) (xy 86.671396 -88.522709) (xy 86.679382 -88.451835) (xy 86.695252 -88.3823)
			(xy 86.718809 -88.31498) (xy 86.749754 -88.250721) (xy 86.7877 -88.19033) (xy 86.832169 -88.134568)
			(xy 86.882602 -88.084135) (xy 86.938364 -88.039666) (xy 86.998755 -88.00172) (xy 87.063014 -87.970775)
			(xy 87.130334 -87.947218) (xy 87.199869 -87.931348) (xy 87.270743 -87.923362) (xy 87.306404 -87.922862)
			(xy 87.342065 -87.923362) (xy 87.412939 -87.931348) (xy 87.482474 -87.947218) (xy 87.549794 -87.970775)
			(xy 87.614053 -88.00172) (xy 87.674444 -88.039666) (xy 87.730206 -88.084135) (xy 87.780639 -88.134568)
			(xy 87.825108 -88.19033) (xy 87.863054 -88.250721) (xy 87.893999 -88.31498) (xy 87.917556 -88.3823)
			(xy 87.933426 -88.451835) (xy 87.941412 -88.522709) (xy 87.941412 -88.594031) (xy 87.933426 -88.664905)
			(xy 87.917556 -88.73444) (xy 87.893999 -88.80176) (xy 87.863054 -88.866019) (xy 87.825108 -88.92641)
			(xy 87.780639 -88.982172) (xy 87.730206 -89.032605) (xy 87.674444 -89.077074) (xy 87.614053 -89.11502)
			(xy 87.549794 -89.145965) (xy 87.482474 -89.169522) (xy 87.412939 -89.185392) (xy 87.342065 -89.193378)
			(xy 87.270743 -89.193378) (xy 87.199869 -89.185392) (xy 87.130334 -89.169522) (xy 87.063014 -89.145965)
			(xy 86.998755 -89.11502) (xy 86.938364 -89.077074) (xy 86.882602 -89.032605) (xy 86.832169 -88.982172)
			(xy 86.7877 -88.92641) (xy 86.749754 -88.866019) (xy 86.718809 -88.80176) (xy 86.695252 -88.73444)
			(xy 86.679382 -88.664905) (xy 86.671396 -88.594031) (xy 85.136998 -88.594031) (xy 85.129012 -88.664905)
			(xy 85.113142 -88.73444) (xy 85.089585 -88.80176) (xy 85.05864 -88.866019) (xy 85.020694 -88.92641)
			(xy 84.976225 -88.982172) (xy 84.925792 -89.032605) (xy 84.87003 -89.077074) (xy 84.809639 -89.11502)
			(xy 84.74538 -89.145965) (xy 84.67806 -89.169522) (xy 84.608525 -89.185392) (xy 84.537651 -89.193378)
			(xy 84.466329 -89.193378) (xy 84.395455 -89.185392) (xy 84.32592 -89.169522) (xy 84.2586 -89.145965)
			(xy 84.194341 -89.11502) (xy 84.13395 -89.077074) (xy 84.078188 -89.032605) (xy 84.027755 -88.982172)
			(xy 83.983286 -88.92641) (xy 83.94534 -88.866019) (xy 83.914395 -88.80176) (xy 83.890838 -88.73444)
			(xy 83.874968 -88.664905) (xy 83.866982 -88.594031) (xy 58.984033 -88.594031) (xy 55.957216 -91.620848)
			(xy 26.928826 -91.620848) (xy 25.516316 -93.033358) (xy 29.519874 -93.033358) (xy 29.519874 -92.946458)
			(xy 29.527892 -92.859929) (xy 29.54386 -92.774509) (xy 29.567641 -92.690927) (xy 29.599033 -92.609895)
			(xy 29.637767 -92.532106) (xy 29.683514 -92.458222) (xy 29.735883 -92.388875) (xy 29.794427 -92.324655)
			(xy 29.858647 -92.266111) (xy 29.927994 -92.213742) (xy 30.001878 -92.167995) (xy 30.079667 -92.129261)
			(xy 30.160699 -92.097869) (xy 30.244281 -92.074088) (xy 30.329701 -92.05812) (xy 30.41623 -92.050102)
			(xy 30.45968 -92.0496) (xy 30.50313 -92.050102) (xy 30.589659 -92.05812) (xy 30.675079 -92.074088)
			(xy 30.758661 -92.097869) (xy 30.839693 -92.129261) (xy 30.917482 -92.167995) (xy 30.991366 -92.213742)
			(xy 31.060713 -92.266111) (xy 31.124933 -92.324655) (xy 31.183477 -92.388875) (xy 31.235846 -92.458222)
			(xy 31.281593 -92.532106) (xy 31.320327 -92.609895) (xy 31.351719 -92.690927) (xy 31.3755 -92.774509)
			(xy 31.391468 -92.859929) (xy 31.399486 -92.946458) (xy 31.399486 -93.033358) (xy 34.599874 -93.033358)
			(xy 34.599874 -92.946458) (xy 34.607892 -92.859929) (xy 34.62386 -92.774509) (xy 34.647641 -92.690927)
			(xy 34.679033 -92.609895) (xy 34.717767 -92.532106) (xy 34.763514 -92.458222) (xy 34.815883 -92.388875)
			(xy 34.874427 -92.324655) (xy 34.938647 -92.266111) (xy 35.007994 -92.213742) (xy 35.081878 -92.167995)
			(xy 35.159667 -92.129261) (xy 35.240699 -92.097869) (xy 35.324281 -92.074088) (xy 35.409701 -92.05812)
			(xy 35.49623 -92.050102) (xy 35.53968 -92.0496) (xy 35.58313 -92.050102) (xy 35.669659 -92.05812)
			(xy 35.755079 -92.074088) (xy 35.838661 -92.097869) (xy 35.919693 -92.129261) (xy 35.997482 -92.167995)
			(xy 36.071366 -92.213742) (xy 36.140713 -92.266111) (xy 36.204933 -92.324655) (xy 36.263477 -92.388875)
			(xy 36.315846 -92.458222) (xy 36.361593 -92.532106) (xy 36.400327 -92.609895) (xy 36.431719 -92.690927)
			(xy 36.4555 -92.774509) (xy 36.471468 -92.859929) (xy 36.479486 -92.946458) (xy 36.479486 -93.033358)
			(xy 36.471468 -93.119887) (xy 36.4555 -93.205307) (xy 36.431719 -93.288889) (xy 36.400327 -93.369921)
			(xy 36.361593 -93.44771) (xy 36.315846 -93.521594) (xy 36.263477 -93.590941) (xy 36.204933 -93.655161)
			(xy 36.140713 -93.713705) (xy 36.071366 -93.766074) (xy 35.997482 -93.811821) (xy 35.919693 -93.850555)
			(xy 35.838661 -93.881947) (xy 35.755079 -93.905728) (xy 35.669659 -93.921696) (xy 35.58313 -93.929714)
			(xy 35.49623 -93.929714) (xy 35.409701 -93.921696) (xy 35.324281 -93.905728) (xy 35.240699 -93.881947)
			(xy 35.159667 -93.850555) (xy 35.081878 -93.811821) (xy 35.007994 -93.766074) (xy 34.938647 -93.713705)
			(xy 34.874427 -93.655161) (xy 34.815883 -93.590941) (xy 34.763514 -93.521594) (xy 34.717767 -93.44771)
			(xy 34.679033 -93.369921) (xy 34.647641 -93.288889) (xy 34.62386 -93.205307) (xy 34.607892 -93.119887)
			(xy 34.599874 -93.033358) (xy 31.399486 -93.033358) (xy 31.391468 -93.119887) (xy 31.3755 -93.205307)
			(xy 31.351719 -93.288889) (xy 31.320327 -93.369921) (xy 31.281593 -93.44771) (xy 31.235846 -93.521594)
			(xy 31.183477 -93.590941) (xy 31.124933 -93.655161) (xy 31.060713 -93.713705) (xy 30.991366 -93.766074)
			(xy 30.917482 -93.811821) (xy 30.839693 -93.850555) (xy 30.758661 -93.881947) (xy 30.675079 -93.905728)
			(xy 30.589659 -93.921696) (xy 30.50313 -93.929714) (xy 30.41623 -93.929714) (xy 30.329701 -93.921696)
			(xy 30.244281 -93.905728) (xy 30.160699 -93.881947) (xy 30.079667 -93.850555) (xy 30.001878 -93.811821)
			(xy 29.927994 -93.766074) (xy 29.858647 -93.713705) (xy 29.794427 -93.655161) (xy 29.735883 -93.590941)
			(xy 29.683514 -93.521594) (xy 29.637767 -93.44771) (xy 29.599033 -93.369921) (xy 29.567641 -93.288889)
			(xy 29.54386 -93.205307) (xy 29.527892 -93.119887) (xy 29.519874 -93.033358) (xy 25.516316 -93.033358)
			(xy 23.551896 -94.997778) (xy 23.551896 -95.607142) (xy 26.754581 -95.607142) (xy 26.760681 -95.551705)
			(xy 26.774787 -95.497748) (xy 26.796599 -95.446419) (xy 26.825653 -95.398813) (xy 26.861328 -95.355945)
			(xy 26.902865 -95.318728) (xy 26.949378 -95.287955) (xy 26.999875 -95.264283) (xy 27.053282 -95.248215)
			(xy 27.108458 -95.240095) (xy 27.136344 -95.239586) (xy 27.16423 -95.240095) (xy 27.219406 -95.248215)
			(xy 27.272813 -95.264283) (xy 27.32331 -95.287955) (xy 27.369823 -95.318728) (xy 27.41136 -95.355945)
			(xy 27.447035 -95.398813) (xy 27.476089 -95.446419) (xy 27.497901 -95.497748) (xy 27.512007 -95.551705)
			(xy 27.51439 -95.573358) (xy 29.519874 -95.573358) (xy 29.519874 -95.486458) (xy 29.527892 -95.399929)
			(xy 29.54386 -95.314509) (xy 29.567641 -95.230927) (xy 29.599033 -95.149895) (xy 29.637767 -95.072106)
			(xy 29.683514 -94.998222) (xy 29.735883 -94.928875) (xy 29.794427 -94.864655) (xy 29.858647 -94.806111)
			(xy 29.927994 -94.753742) (xy 30.001878 -94.707995) (xy 30.079667 -94.669261) (xy 30.160699 -94.637869)
			(xy 30.244281 -94.614088) (xy 30.329701 -94.59812) (xy 30.41623 -94.590102) (xy 30.45968 -94.5896)
			(xy 30.50313 -94.590102) (xy 30.589659 -94.59812) (xy 30.675079 -94.614088) (xy 30.758661 -94.637869)
			(xy 30.839693 -94.669261) (xy 30.917482 -94.707995) (xy 30.991366 -94.753742) (xy 31.060713 -94.806111)
			(xy 31.124933 -94.864655) (xy 31.183477 -94.928875) (xy 31.235846 -94.998222) (xy 31.281593 -95.072106)
			(xy 31.320327 -95.149895) (xy 31.351719 -95.230927) (xy 31.3755 -95.314509) (xy 31.391468 -95.399929)
			(xy 31.399486 -95.486458) (xy 31.399486 -95.573358) (xy 34.599874 -95.573358) (xy 34.599874 -95.486458)
			(xy 34.607892 -95.399929) (xy 34.62386 -95.314509) (xy 34.647641 -95.230927) (xy 34.679033 -95.149895)
			(xy 34.717767 -95.072106) (xy 34.763514 -94.998222) (xy 34.815883 -94.928875) (xy 34.874427 -94.864655)
			(xy 34.938647 -94.806111) (xy 35.007994 -94.753742) (xy 35.081878 -94.707995) (xy 35.159667 -94.669261)
			(xy 35.240699 -94.637869) (xy 35.324281 -94.614088) (xy 35.409701 -94.59812) (xy 35.49623 -94.590102)
			(xy 35.53968 -94.5896) (xy 35.58313 -94.590102) (xy 35.669659 -94.59812) (xy 35.755079 -94.614088)
			(xy 35.838661 -94.637869) (xy 35.919693 -94.669261) (xy 35.997482 -94.707995) (xy 36.071366 -94.753742)
			(xy 36.140713 -94.806111) (xy 36.204933 -94.864655) (xy 36.263477 -94.928875) (xy 36.315846 -94.998222)
			(xy 36.361593 -95.072106) (xy 36.400327 -95.149895) (xy 36.431719 -95.230927) (xy 36.4555 -95.314509)
			(xy 36.471468 -95.399929) (xy 36.479486 -95.486458) (xy 36.479486 -95.573358) (xy 36.471468 -95.659887)
			(xy 36.4555 -95.745307) (xy 36.445333 -95.781042) (xy 39.818314 -95.781042) (xy 39.824323 -95.665104)
			(xy 39.838316 -95.549857) (xy 39.860227 -95.435851) (xy 39.889952 -95.323627) (xy 39.927348 -95.213721)
			(xy 39.972237 -95.106658) (xy 40.024406 -95.002946) (xy 40.083606 -94.903081) (xy 40.149555 -94.807538)
			(xy 40.221938 -94.716772) (xy 40.300411 -94.631217) (xy 40.384599 -94.551279) (xy 40.474101 -94.47734)
			(xy 40.568492 -94.409752) (xy 40.66732 -94.348838) (xy 40.770116 -94.294886) (xy 40.876389 -94.248156)
			(xy 40.985633 -94.208868) (xy 41.097326 -94.177211) (xy 41.210938 -94.153335) (xy 41.325926 -94.137354)
			(xy 41.441743 -94.129345) (xy 41.49979 -94.128844) (xy 41.557837 -94.129345) (xy 41.673654 -94.137354)
			(xy 41.788642 -94.153335) (xy 41.902254 -94.177211) (xy 42.013947 -94.208868) (xy 42.123191 -94.248156)
			(xy 42.229464 -94.294886) (xy 42.33226 -94.348838) (xy 42.431088 -94.409752) (xy 42.474869 -94.441101)
			(xy 63.647829 -94.441101) (xy 63.653878 -94.365531) (xy 63.667925 -94.291033) (xy 63.689811 -94.21845)
			(xy 63.719288 -94.148604) (xy 63.756023 -94.082287) (xy 63.799598 -94.020251) (xy 63.84952 -93.963198)
			(xy 63.905224 -93.911774) (xy 63.966079 -93.866563) (xy 64.031394 -93.828076) (xy 64.10043 -93.79675)
			(xy 64.172405 -93.77294) (xy 64.246503 -93.756915) (xy 64.321884 -93.748856) (xy 64.35979 -93.748352)
			(xy 64.397696 -93.748856) (xy 64.473077 -93.756915) (xy 64.547175 -93.77294) (xy 64.61915 -93.79675)
			(xy 64.688186 -93.828076) (xy 64.753501 -93.866563) (xy 64.814356 -93.911774) (xy 64.87006 -93.963198)
			(xy 64.919982 -94.020251) (xy 64.963557 -94.082287) (xy 65.000292 -94.148604) (xy 65.029769 -94.21845)
			(xy 65.051655 -94.291033) (xy 65.065702 -94.365531) (xy 65.071751 -94.441101) (xy 66.187829 -94.441101)
			(xy 66.193878 -94.365531) (xy 66.207925 -94.291033) (xy 66.229811 -94.21845) (xy 66.259288 -94.148604)
			(xy 66.296023 -94.082287) (xy 66.339598 -94.020251) (xy 66.38952 -93.963198) (xy 66.445224 -93.911774)
			(xy 66.506079 -93.866563) (xy 66.571394 -93.828076) (xy 66.64043 -93.79675) (xy 66.712405 -93.77294)
			(xy 66.786503 -93.756915) (xy 66.861884 -93.748856) (xy 66.89979 -93.748352) (xy 66.937696 -93.748856)
			(xy 67.013077 -93.756915) (xy 67.087175 -93.77294) (xy 67.15915 -93.79675) (xy 67.228186 -93.828076)
			(xy 67.293501 -93.866563) (xy 67.354356 -93.911774) (xy 67.41006 -93.963198) (xy 67.459982 -94.020251)
			(xy 67.503557 -94.082287) (xy 67.540292 -94.148604) (xy 67.569769 -94.21845) (xy 67.591655 -94.291033)
			(xy 67.605702 -94.365531) (xy 67.611751 -94.441101) (xy 68.727829 -94.441101) (xy 68.733878 -94.365531)
			(xy 68.747925 -94.291033) (xy 68.769811 -94.21845) (xy 68.799288 -94.148604) (xy 68.836023 -94.082287)
			(xy 68.879598 -94.020251) (xy 68.92952 -93.963198) (xy 68.985224 -93.911774) (xy 69.046079 -93.866563)
			(xy 69.111394 -93.828076) (xy 69.18043 -93.79675) (xy 69.252405 -93.77294) (xy 69.326503 -93.756915)
			(xy 69.401884 -93.748856) (xy 69.43979 -93.748352) (xy 69.477696 -93.748856) (xy 69.553077 -93.756915)
			(xy 69.627175 -93.77294) (xy 69.69915 -93.79675) (xy 69.768186 -93.828076) (xy 69.833501 -93.866563)
			(xy 69.894356 -93.911774) (xy 69.95006 -93.963198) (xy 69.999982 -94.020251) (xy 70.043557 -94.082287)
			(xy 70.080292 -94.148604) (xy 70.109769 -94.21845) (xy 70.131655 -94.291033) (xy 70.145702 -94.365531)
			(xy 70.151751 -94.441101) (xy 71.267829 -94.441101) (xy 71.273878 -94.365531) (xy 71.287925 -94.291033)
			(xy 71.309811 -94.21845) (xy 71.339288 -94.148604) (xy 71.376023 -94.082287) (xy 71.419598 -94.020251)
			(xy 71.46952 -93.963198) (xy 71.525224 -93.911774) (xy 71.586079 -93.866563) (xy 71.651394 -93.828076)
			(xy 71.72043 -93.79675) (xy 71.792405 -93.77294) (xy 71.866503 -93.756915) (xy 71.941884 -93.748856)
			(xy 71.97979 -93.748352) (xy 72.017696 -93.748856) (xy 72.093077 -93.756915) (xy 72.167175 -93.77294)
			(xy 72.23915 -93.79675) (xy 72.308186 -93.828076) (xy 72.373501 -93.866563) (xy 72.434356 -93.911774)
			(xy 72.49006 -93.963198) (xy 72.539982 -94.020251) (xy 72.583557 -94.082287) (xy 72.620292 -94.148604)
			(xy 72.649769 -94.21845) (xy 72.671655 -94.291033) (xy 72.685702 -94.365531) (xy 72.691751 -94.441101)
			(xy 73.807829 -94.441101) (xy 73.813878 -94.365531) (xy 73.827925 -94.291033) (xy 73.849811 -94.21845)
			(xy 73.879288 -94.148604) (xy 73.916023 -94.082287) (xy 73.959598 -94.020251) (xy 74.00952 -93.963198)
			(xy 74.065224 -93.911774) (xy 74.126079 -93.866563) (xy 74.191394 -93.828076) (xy 74.26043 -93.79675)
			(xy 74.332405 -93.77294) (xy 74.406503 -93.756915) (xy 74.481884 -93.748856) (xy 74.51979 -93.748352)
			(xy 74.557696 -93.748856) (xy 74.633077 -93.756915) (xy 74.707175 -93.77294) (xy 74.77915 -93.79675)
			(xy 74.848186 -93.828076) (xy 74.913501 -93.866563) (xy 74.974356 -93.911774) (xy 75.03006 -93.963198)
			(xy 75.079982 -94.020251) (xy 75.123557 -94.082287) (xy 75.160292 -94.148604) (xy 75.189769 -94.21845)
			(xy 75.211655 -94.291033) (xy 75.225702 -94.365531) (xy 75.231751 -94.441101) (xy 76.347829 -94.441101)
			(xy 76.353878 -94.365531) (xy 76.367925 -94.291033) (xy 76.389811 -94.21845) (xy 76.419288 -94.148604)
			(xy 76.456023 -94.082287) (xy 76.499598 -94.020251) (xy 76.54952 -93.963198) (xy 76.605224 -93.911774)
			(xy 76.666079 -93.866563) (xy 76.731394 -93.828076) (xy 76.80043 -93.79675) (xy 76.872405 -93.77294)
			(xy 76.946503 -93.756915) (xy 77.021884 -93.748856) (xy 77.05979 -93.748352) (xy 77.097696 -93.748856)
			(xy 77.173077 -93.756915) (xy 77.247175 -93.77294) (xy 77.31915 -93.79675) (xy 77.388186 -93.828076)
			(xy 77.453501 -93.866563) (xy 77.514356 -93.911774) (xy 77.57006 -93.963198) (xy 77.619982 -94.020251)
			(xy 77.663557 -94.082287) (xy 77.700292 -94.148604) (xy 77.729769 -94.21845) (xy 77.751655 -94.291033)
			(xy 77.765702 -94.365531) (xy 77.771751 -94.441101) (xy 78.887829 -94.441101) (xy 78.893878 -94.365531)
			(xy 78.907925 -94.291033) (xy 78.929811 -94.21845) (xy 78.959288 -94.148604) (xy 78.996023 -94.082287)
			(xy 79.039598 -94.020251) (xy 79.08952 -93.963198) (xy 79.145224 -93.911774) (xy 79.206079 -93.866563)
			(xy 79.271394 -93.828076) (xy 79.34043 -93.79675) (xy 79.412405 -93.77294) (xy 79.486503 -93.756915)
			(xy 79.561884 -93.748856) (xy 79.59979 -93.748352) (xy 79.637696 -93.748856) (xy 79.713077 -93.756915)
			(xy 79.787175 -93.77294) (xy 79.85915 -93.79675) (xy 79.928186 -93.828076) (xy 79.993501 -93.866563)
			(xy 80.054356 -93.911774) (xy 80.11006 -93.963198) (xy 80.159982 -94.020251) (xy 80.203557 -94.082287)
			(xy 80.240292 -94.148604) (xy 80.269769 -94.21845) (xy 80.291655 -94.291033) (xy 80.305702 -94.365531)
			(xy 80.311751 -94.441101) (xy 81.427829 -94.441101) (xy 81.433878 -94.365531) (xy 81.447925 -94.291033)
			(xy 81.469811 -94.21845) (xy 81.499288 -94.148604) (xy 81.536023 -94.082287) (xy 81.579598 -94.020251)
			(xy 81.62952 -93.963198) (xy 81.685224 -93.911774) (xy 81.746079 -93.866563) (xy 81.811394 -93.828076)
			(xy 81.88043 -93.79675) (xy 81.952405 -93.77294) (xy 82.026503 -93.756915) (xy 82.101884 -93.748856)
			(xy 82.13979 -93.748352) (xy 82.177696 -93.748856) (xy 82.253077 -93.756915) (xy 82.327175 -93.77294)
			(xy 82.39915 -93.79675) (xy 82.468186 -93.828076) (xy 82.533501 -93.866563) (xy 82.594356 -93.911774)
			(xy 82.65006 -93.963198) (xy 82.699982 -94.020251) (xy 82.743557 -94.082287) (xy 82.780292 -94.148604)
			(xy 82.809769 -94.21845) (xy 82.831655 -94.291033) (xy 82.845702 -94.365531) (xy 82.851751 -94.441101)
			(xy 82.849732 -94.516885) (xy 82.83967 -94.592025) (xy 82.821678 -94.66567) (xy 82.79596 -94.736986)
			(xy 82.762808 -94.805163) (xy 82.722596 -94.869431) (xy 82.675781 -94.92906) (xy 82.622893 -94.983376)
			(xy 82.564531 -95.031762) (xy 82.501356 -95.07367) (xy 82.434085 -95.108626) (xy 82.36348 -95.136233)
			(xy 82.290339 -95.156179) (xy 82.215494 -95.168238) (xy 82.13979 -95.172273) (xy 82.064086 -95.168238)
			(xy 81.989241 -95.156179) (xy 81.9161 -95.136233) (xy 81.845495 -95.108626) (xy 81.778224 -95.07367)
			(xy 81.715049 -95.031762) (xy 81.656687 -94.983376) (xy 81.603799 -94.92906) (xy 81.556984 -94.869431)
			(xy 81.516772 -94.805163) (xy 81.48362 -94.736986) (xy 81.457902 -94.66567) (xy 81.43991 -94.592025)
			(xy 81.429848 -94.516885) (xy 81.427829 -94.441101) (xy 80.311751 -94.441101) (xy 80.309732 -94.516885)
			(xy 80.29967 -94.592025) (xy 80.281678 -94.66567) (xy 80.25596 -94.736986) (xy 80.222808 -94.805163)
			(xy 80.182596 -94.869431) (xy 80.135781 -94.92906) (xy 80.082893 -94.983376) (xy 80.024531 -95.031762)
			(xy 79.961356 -95.07367) (xy 79.894085 -95.108626) (xy 79.82348 -95.136233) (xy 79.750339 -95.156179)
			(xy 79.675494 -95.168238) (xy 79.59979 -95.172273) (xy 79.524086 -95.168238) (xy 79.449241 -95.156179)
			(xy 79.3761 -95.136233) (xy 79.305495 -95.108626) (xy 79.238224 -95.07367) (xy 79.175049 -95.031762)
			(xy 79.116687 -94.983376) (xy 79.063799 -94.92906) (xy 79.016984 -94.869431) (xy 78.976772 -94.805163)
			(xy 78.94362 -94.736986) (xy 78.917902 -94.66567) (xy 78.89991 -94.592025) (xy 78.889848 -94.516885)
			(xy 78.887829 -94.441101) (xy 77.771751 -94.441101) (xy 77.769732 -94.516885) (xy 77.75967 -94.592025)
			(xy 77.741678 -94.66567) (xy 77.71596 -94.736986) (xy 77.682808 -94.805163) (xy 77.642596 -94.869431)
			(xy 77.595781 -94.92906) (xy 77.542893 -94.983376) (xy 77.484531 -95.031762) (xy 77.421356 -95.07367)
			(xy 77.354085 -95.108626) (xy 77.28348 -95.136233) (xy 77.210339 -95.156179) (xy 77.135494 -95.168238)
			(xy 77.05979 -95.172273) (xy 76.984086 -95.168238) (xy 76.909241 -95.156179) (xy 76.8361 -95.136233)
			(xy 76.765495 -95.108626) (xy 76.698224 -95.07367) (xy 76.635049 -95.031762) (xy 76.576687 -94.983376)
			(xy 76.523799 -94.92906) (xy 76.476984 -94.869431) (xy 76.436772 -94.805163) (xy 76.40362 -94.736986)
			(xy 76.377902 -94.66567) (xy 76.35991 -94.592025) (xy 76.349848 -94.516885) (xy 76.347829 -94.441101)
			(xy 75.231751 -94.441101) (xy 75.229732 -94.516885) (xy 75.21967 -94.592025) (xy 75.201678 -94.66567)
			(xy 75.17596 -94.736986) (xy 75.142808 -94.805163) (xy 75.102596 -94.869431) (xy 75.055781 -94.92906)
			(xy 75.002893 -94.983376) (xy 74.944531 -95.031762) (xy 74.881356 -95.07367) (xy 74.814085 -95.108626)
			(xy 74.74348 -95.136233) (xy 74.670339 -95.156179) (xy 74.595494 -95.168238) (xy 74.51979 -95.172273)
			(xy 74.444086 -95.168238) (xy 74.369241 -95.156179) (xy 74.2961 -95.136233) (xy 74.225495 -95.108626)
			(xy 74.158224 -95.07367) (xy 74.095049 -95.031762) (xy 74.036687 -94.983376) (xy 73.983799 -94.92906)
			(xy 73.936984 -94.869431) (xy 73.896772 -94.805163) (xy 73.86362 -94.736986) (xy 73.837902 -94.66567)
			(xy 73.81991 -94.592025) (xy 73.809848 -94.516885) (xy 73.807829 -94.441101) (xy 72.691751 -94.441101)
			(xy 72.689732 -94.516885) (xy 72.67967 -94.592025) (xy 72.661678 -94.66567) (xy 72.63596 -94.736986)
			(xy 72.602808 -94.805163) (xy 72.562596 -94.869431) (xy 72.515781 -94.92906) (xy 72.462893 -94.983376)
			(xy 72.404531 -95.031762) (xy 72.341356 -95.07367) (xy 72.274085 -95.108626) (xy 72.20348 -95.136233)
			(xy 72.130339 -95.156179) (xy 72.055494 -95.168238) (xy 71.97979 -95.172273) (xy 71.904086 -95.168238)
			(xy 71.829241 -95.156179) (xy 71.7561 -95.136233) (xy 71.685495 -95.108626) (xy 71.618224 -95.07367)
			(xy 71.555049 -95.031762) (xy 71.496687 -94.983376) (xy 71.443799 -94.92906) (xy 71.396984 -94.869431)
			(xy 71.356772 -94.805163) (xy 71.32362 -94.736986) (xy 71.297902 -94.66567) (xy 71.27991 -94.592025)
			(xy 71.269848 -94.516885) (xy 71.267829 -94.441101) (xy 70.151751 -94.441101) (xy 70.149732 -94.516885)
			(xy 70.13967 -94.592025) (xy 70.121678 -94.66567) (xy 70.09596 -94.736986) (xy 70.062808 -94.805163)
			(xy 70.022596 -94.869431) (xy 69.975781 -94.92906) (xy 69.922893 -94.983376) (xy 69.864531 -95.031762)
			(xy 69.801356 -95.07367) (xy 69.734085 -95.108626) (xy 69.66348 -95.136233) (xy 69.590339 -95.156179)
			(xy 69.515494 -95.168238) (xy 69.43979 -95.172273) (xy 69.364086 -95.168238) (xy 69.289241 -95.156179)
			(xy 69.2161 -95.136233) (xy 69.145495 -95.108626) (xy 69.078224 -95.07367) (xy 69.015049 -95.031762)
			(xy 68.956687 -94.983376) (xy 68.903799 -94.92906) (xy 68.856984 -94.869431) (xy 68.816772 -94.805163)
			(xy 68.78362 -94.736986) (xy 68.757902 -94.66567) (xy 68.73991 -94.592025) (xy 68.729848 -94.516885)
			(xy 68.727829 -94.441101) (xy 67.611751 -94.441101) (xy 67.609732 -94.516885) (xy 67.59967 -94.592025)
			(xy 67.581678 -94.66567) (xy 67.55596 -94.736986) (xy 67.522808 -94.805163) (xy 67.482596 -94.869431)
			(xy 67.435781 -94.92906) (xy 67.382893 -94.983376) (xy 67.324531 -95.031762) (xy 67.261356 -95.07367)
			(xy 67.194085 -95.108626) (xy 67.12348 -95.136233) (xy 67.050339 -95.156179) (xy 66.975494 -95.168238)
			(xy 66.89979 -95.172273) (xy 66.824086 -95.168238) (xy 66.749241 -95.156179) (xy 66.6761 -95.136233)
			(xy 66.605495 -95.108626) (xy 66.538224 -95.07367) (xy 66.475049 -95.031762) (xy 66.416687 -94.983376)
			(xy 66.363799 -94.92906) (xy 66.316984 -94.869431) (xy 66.276772 -94.805163) (xy 66.24362 -94.736986)
			(xy 66.217902 -94.66567) (xy 66.19991 -94.592025) (xy 66.189848 -94.516885) (xy 66.187829 -94.441101)
			(xy 65.071751 -94.441101) (xy 65.069732 -94.516885) (xy 65.05967 -94.592025) (xy 65.041678 -94.66567)
			(xy 65.01596 -94.736986) (xy 64.982808 -94.805163) (xy 64.942596 -94.869431) (xy 64.895781 -94.92906)
			(xy 64.842893 -94.983376) (xy 64.784531 -95.031762) (xy 64.721356 -95.07367) (xy 64.654085 -95.108626)
			(xy 64.58348 -95.136233) (xy 64.510339 -95.156179) (xy 64.435494 -95.168238) (xy 64.35979 -95.172273)
			(xy 64.284086 -95.168238) (xy 64.209241 -95.156179) (xy 64.1361 -95.136233) (xy 64.065495 -95.108626)
			(xy 63.998224 -95.07367) (xy 63.935049 -95.031762) (xy 63.876687 -94.983376) (xy 63.823799 -94.92906)
			(xy 63.776984 -94.869431) (xy 63.736772 -94.805163) (xy 63.70362 -94.736986) (xy 63.677902 -94.66567)
			(xy 63.65991 -94.592025) (xy 63.649848 -94.516885) (xy 63.647829 -94.441101) (xy 42.474869 -94.441101)
			(xy 42.525479 -94.47734) (xy 42.614981 -94.551279) (xy 42.699169 -94.631217) (xy 42.777642 -94.716772)
			(xy 42.850025 -94.807538) (xy 42.915974 -94.903081) (xy 42.975174 -95.002946) (xy 43.027343 -95.106658)
			(xy 43.072232 -95.213721) (xy 43.109628 -95.323627) (xy 43.139353 -95.435851) (xy 43.161264 -95.549857)
			(xy 43.175257 -95.665104) (xy 43.181266 -95.781042) (xy 43.179263 -95.897118) (xy 43.169255 -96.01278)
			(xy 43.151292 -96.127475) (xy 43.125459 -96.240658) (xy 43.091879 -96.351789) (xy 43.050711 -96.460338)
			(xy 43.002153 -96.565788) (xy 42.946436 -96.667637) (xy 42.883824 -96.7654) (xy 42.814617 -96.85861)
			(xy 42.739144 -96.946823) (xy 42.657765 -97.029619) (xy 42.570868 -97.106603) (xy 42.526017 -97.141121)
			(xy 63.647829 -97.141121) (xy 63.653878 -97.065551) (xy 63.667925 -96.991053) (xy 63.689811 -96.91847)
			(xy 63.719288 -96.848624) (xy 63.756023 -96.782307) (xy 63.799598 -96.720271) (xy 63.84952 -96.663218)
			(xy 63.905224 -96.611794) (xy 63.966079 -96.566583) (xy 64.031394 -96.528096) (xy 64.10043 -96.49677)
			(xy 64.172405 -96.47296) (xy 64.246503 -96.456935) (xy 64.321884 -96.448876) (xy 64.35979 -96.448372)
			(xy 64.397696 -96.448876) (xy 64.473077 -96.456935) (xy 64.547175 -96.47296) (xy 64.61915 -96.49677)
			(xy 64.688186 -96.528096) (xy 64.753501 -96.566583) (xy 64.814356 -96.611794) (xy 64.87006 -96.663218)
			(xy 64.919982 -96.720271) (xy 64.963557 -96.782307) (xy 65.000292 -96.848624) (xy 65.029769 -96.91847)
			(xy 65.051655 -96.991053) (xy 65.065702 -97.065551) (xy 65.071751 -97.141121) (xy 66.187829 -97.141121)
			(xy 66.193878 -97.065551) (xy 66.207925 -96.991053) (xy 66.229811 -96.91847) (xy 66.259288 -96.848624)
			(xy 66.296023 -96.782307) (xy 66.339598 -96.720271) (xy 66.38952 -96.663218) (xy 66.445224 -96.611794)
			(xy 66.506079 -96.566583) (xy 66.571394 -96.528096) (xy 66.64043 -96.49677) (xy 66.712405 -96.47296)
			(xy 66.786503 -96.456935) (xy 66.861884 -96.448876) (xy 66.89979 -96.448372) (xy 66.937696 -96.448876)
			(xy 67.013077 -96.456935) (xy 67.087175 -96.47296) (xy 67.15915 -96.49677) (xy 67.228186 -96.528096)
			(xy 67.293501 -96.566583) (xy 67.354356 -96.611794) (xy 67.41006 -96.663218) (xy 67.459982 -96.720271)
			(xy 67.503557 -96.782307) (xy 67.540292 -96.848624) (xy 67.569769 -96.91847) (xy 67.591655 -96.991053)
			(xy 67.605702 -97.065551) (xy 67.611751 -97.141121) (xy 68.727829 -97.141121) (xy 68.733878 -97.065551)
			(xy 68.747925 -96.991053) (xy 68.769811 -96.91847) (xy 68.799288 -96.848624) (xy 68.836023 -96.782307)
			(xy 68.879598 -96.720271) (xy 68.92952 -96.663218) (xy 68.985224 -96.611794) (xy 69.046079 -96.566583)
			(xy 69.111394 -96.528096) (xy 69.18043 -96.49677) (xy 69.252405 -96.47296) (xy 69.326503 -96.456935)
			(xy 69.401884 -96.448876) (xy 69.43979 -96.448372) (xy 69.477696 -96.448876) (xy 69.553077 -96.456935)
			(xy 69.627175 -96.47296) (xy 69.69915 -96.49677) (xy 69.768186 -96.528096) (xy 69.833501 -96.566583)
			(xy 69.894356 -96.611794) (xy 69.95006 -96.663218) (xy 69.999982 -96.720271) (xy 70.043557 -96.782307)
			(xy 70.080292 -96.848624) (xy 70.109769 -96.91847) (xy 70.131655 -96.991053) (xy 70.145702 -97.065551)
			(xy 70.151751 -97.141121) (xy 71.267829 -97.141121) (xy 71.273878 -97.065551) (xy 71.287925 -96.991053)
			(xy 71.309811 -96.91847) (xy 71.339288 -96.848624) (xy 71.376023 -96.782307) (xy 71.419598 -96.720271)
			(xy 71.46952 -96.663218) (xy 71.525224 -96.611794) (xy 71.586079 -96.566583) (xy 71.651394 -96.528096)
			(xy 71.72043 -96.49677) (xy 71.792405 -96.47296) (xy 71.866503 -96.456935) (xy 71.941884 -96.448876)
			(xy 71.97979 -96.448372) (xy 72.017696 -96.448876) (xy 72.093077 -96.456935) (xy 72.167175 -96.47296)
			(xy 72.23915 -96.49677) (xy 72.308186 -96.528096) (xy 72.373501 -96.566583) (xy 72.434356 -96.611794)
			(xy 72.49006 -96.663218) (xy 72.539982 -96.720271) (xy 72.583557 -96.782307) (xy 72.620292 -96.848624)
			(xy 72.649769 -96.91847) (xy 72.671655 -96.991053) (xy 72.685702 -97.065551) (xy 72.691751 -97.141121)
			(xy 73.807829 -97.141121) (xy 73.813878 -97.065551) (xy 73.827925 -96.991053) (xy 73.849811 -96.91847)
			(xy 73.879288 -96.848624) (xy 73.916023 -96.782307) (xy 73.959598 -96.720271) (xy 74.00952 -96.663218)
			(xy 74.065224 -96.611794) (xy 74.126079 -96.566583) (xy 74.191394 -96.528096) (xy 74.26043 -96.49677)
			(xy 74.332405 -96.47296) (xy 74.406503 -96.456935) (xy 74.481884 -96.448876) (xy 74.51979 -96.448372)
			(xy 74.557696 -96.448876) (xy 74.633077 -96.456935) (xy 74.707175 -96.47296) (xy 74.77915 -96.49677)
			(xy 74.848186 -96.528096) (xy 74.913501 -96.566583) (xy 74.974356 -96.611794) (xy 75.03006 -96.663218)
			(xy 75.079982 -96.720271) (xy 75.123557 -96.782307) (xy 75.160292 -96.848624) (xy 75.189769 -96.91847)
			(xy 75.211655 -96.991053) (xy 75.225702 -97.065551) (xy 75.231751 -97.141121) (xy 76.347829 -97.141121)
			(xy 76.353878 -97.065551) (xy 76.367925 -96.991053) (xy 76.389811 -96.91847) (xy 76.419288 -96.848624)
			(xy 76.456023 -96.782307) (xy 76.499598 -96.720271) (xy 76.54952 -96.663218) (xy 76.605224 -96.611794)
			(xy 76.666079 -96.566583) (xy 76.731394 -96.528096) (xy 76.80043 -96.49677) (xy 76.872405 -96.47296)
			(xy 76.946503 -96.456935) (xy 77.021884 -96.448876) (xy 77.05979 -96.448372) (xy 77.097696 -96.448876)
			(xy 77.173077 -96.456935) (xy 77.247175 -96.47296) (xy 77.31915 -96.49677) (xy 77.388186 -96.528096)
			(xy 77.453501 -96.566583) (xy 77.514356 -96.611794) (xy 77.57006 -96.663218) (xy 77.619982 -96.720271)
			(xy 77.663557 -96.782307) (xy 77.700292 -96.848624) (xy 77.729769 -96.91847) (xy 77.751655 -96.991053)
			(xy 77.765702 -97.065551) (xy 77.771751 -97.141121) (xy 78.887829 -97.141121) (xy 78.893878 -97.065551)
			(xy 78.907925 -96.991053) (xy 78.929811 -96.91847) (xy 78.959288 -96.848624) (xy 78.996023 -96.782307)
			(xy 79.039598 -96.720271) (xy 79.08952 -96.663218) (xy 79.145224 -96.611794) (xy 79.206079 -96.566583)
			(xy 79.271394 -96.528096) (xy 79.34043 -96.49677) (xy 79.412405 -96.47296) (xy 79.486503 -96.456935)
			(xy 79.561884 -96.448876) (xy 79.59979 -96.448372) (xy 79.637696 -96.448876) (xy 79.713077 -96.456935)
			(xy 79.787175 -96.47296) (xy 79.85915 -96.49677) (xy 79.928186 -96.528096) (xy 79.993501 -96.566583)
			(xy 80.054356 -96.611794) (xy 80.11006 -96.663218) (xy 80.159982 -96.720271) (xy 80.203557 -96.782307)
			(xy 80.240292 -96.848624) (xy 80.269769 -96.91847) (xy 80.291655 -96.991053) (xy 80.305702 -97.065551)
			(xy 80.311751 -97.141121) (xy 81.427829 -97.141121) (xy 81.433878 -97.065551) (xy 81.447925 -96.991053)
			(xy 81.469811 -96.91847) (xy 81.499288 -96.848624) (xy 81.536023 -96.782307) (xy 81.579598 -96.720271)
			(xy 81.62952 -96.663218) (xy 81.685224 -96.611794) (xy 81.746079 -96.566583) (xy 81.811394 -96.528096)
			(xy 81.88043 -96.49677) (xy 81.952405 -96.47296) (xy 82.026503 -96.456935) (xy 82.101884 -96.448876)
			(xy 82.13979 -96.448372) (xy 82.177696 -96.448876) (xy 82.253077 -96.456935) (xy 82.327175 -96.47296)
			(xy 82.39915 -96.49677) (xy 82.468186 -96.528096) (xy 82.533501 -96.566583) (xy 82.594356 -96.611794)
			(xy 82.65006 -96.663218) (xy 82.699982 -96.720271) (xy 82.743557 -96.782307) (xy 82.780292 -96.848624)
			(xy 82.809769 -96.91847) (xy 82.831655 -96.991053) (xy 82.845702 -97.065551) (xy 82.851751 -97.141121)
			(xy 82.849732 -97.216905) (xy 82.83967 -97.292045) (xy 82.821678 -97.36569) (xy 82.79596 -97.437006)
			(xy 82.762808 -97.505183) (xy 82.722596 -97.569451) (xy 82.675781 -97.62908) (xy 82.622893 -97.683396)
			(xy 82.564531 -97.731782) (xy 82.501356 -97.77369) (xy 82.434085 -97.808646) (xy 82.36348 -97.836253)
			(xy 82.290339 -97.856199) (xy 82.215494 -97.868258) (xy 82.13979 -97.872293) (xy 82.064086 -97.868258)
			(xy 81.989241 -97.856199) (xy 81.9161 -97.836253) (xy 81.845495 -97.808646) (xy 81.778224 -97.77369)
			(xy 81.715049 -97.731782) (xy 81.656687 -97.683396) (xy 81.603799 -97.62908) (xy 81.556984 -97.569451)
			(xy 81.516772 -97.505183) (xy 81.48362 -97.437006) (xy 81.457902 -97.36569) (xy 81.43991 -97.292045)
			(xy 81.429848 -97.216905) (xy 81.427829 -97.141121) (xy 80.311751 -97.141121) (xy 80.309732 -97.216905)
			(xy 80.29967 -97.292045) (xy 80.281678 -97.36569) (xy 80.25596 -97.437006) (xy 80.222808 -97.505183)
			(xy 80.182596 -97.569451) (xy 80.135781 -97.62908) (xy 80.082893 -97.683396) (xy 80.024531 -97.731782)
			(xy 79.961356 -97.77369) (xy 79.894085 -97.808646) (xy 79.82348 -97.836253) (xy 79.750339 -97.856199)
			(xy 79.675494 -97.868258) (xy 79.59979 -97.872293) (xy 79.524086 -97.868258) (xy 79.449241 -97.856199)
			(xy 79.3761 -97.836253) (xy 79.305495 -97.808646) (xy 79.238224 -97.77369) (xy 79.175049 -97.731782)
			(xy 79.116687 -97.683396) (xy 79.063799 -97.62908) (xy 79.016984 -97.569451) (xy 78.976772 -97.505183)
			(xy 78.94362 -97.437006) (xy 78.917902 -97.36569) (xy 78.89991 -97.292045) (xy 78.889848 -97.216905)
			(xy 78.887829 -97.141121) (xy 77.771751 -97.141121) (xy 77.769732 -97.216905) (xy 77.75967 -97.292045)
			(xy 77.741678 -97.36569) (xy 77.71596 -97.437006) (xy 77.682808 -97.505183) (xy 77.642596 -97.569451)
			(xy 77.595781 -97.62908) (xy 77.542893 -97.683396) (xy 77.484531 -97.731782) (xy 77.421356 -97.77369)
			(xy 77.354085 -97.808646) (xy 77.28348 -97.836253) (xy 77.210339 -97.856199) (xy 77.135494 -97.868258)
			(xy 77.05979 -97.872293) (xy 76.984086 -97.868258) (xy 76.909241 -97.856199) (xy 76.8361 -97.836253)
			(xy 76.765495 -97.808646) (xy 76.698224 -97.77369) (xy 76.635049 -97.731782) (xy 76.576687 -97.683396)
			(xy 76.523799 -97.62908) (xy 76.476984 -97.569451) (xy 76.436772 -97.505183) (xy 76.40362 -97.437006)
			(xy 76.377902 -97.36569) (xy 76.35991 -97.292045) (xy 76.349848 -97.216905) (xy 76.347829 -97.141121)
			(xy 75.231751 -97.141121) (xy 75.229732 -97.216905) (xy 75.21967 -97.292045) (xy 75.201678 -97.36569)
			(xy 75.17596 -97.437006) (xy 75.142808 -97.505183) (xy 75.102596 -97.569451) (xy 75.055781 -97.62908)
			(xy 75.002893 -97.683396) (xy 74.944531 -97.731782) (xy 74.881356 -97.77369) (xy 74.814085 -97.808646)
			(xy 74.74348 -97.836253) (xy 74.670339 -97.856199) (xy 74.595494 -97.868258) (xy 74.51979 -97.872293)
			(xy 74.444086 -97.868258) (xy 74.369241 -97.856199) (xy 74.2961 -97.836253) (xy 74.225495 -97.808646)
			(xy 74.158224 -97.77369) (xy 74.095049 -97.731782) (xy 74.036687 -97.683396) (xy 73.983799 -97.62908)
			(xy 73.936984 -97.569451) (xy 73.896772 -97.505183) (xy 73.86362 -97.437006) (xy 73.837902 -97.36569)
			(xy 73.81991 -97.292045) (xy 73.809848 -97.216905) (xy 73.807829 -97.141121) (xy 72.691751 -97.141121)
			(xy 72.689732 -97.216905) (xy 72.67967 -97.292045) (xy 72.661678 -97.36569) (xy 72.63596 -97.437006)
			(xy 72.602808 -97.505183) (xy 72.562596 -97.569451) (xy 72.515781 -97.62908) (xy 72.462893 -97.683396)
			(xy 72.404531 -97.731782) (xy 72.341356 -97.77369) (xy 72.274085 -97.808646) (xy 72.20348 -97.836253)
			(xy 72.130339 -97.856199) (xy 72.055494 -97.868258) (xy 71.97979 -97.872293) (xy 71.904086 -97.868258)
			(xy 71.829241 -97.856199) (xy 71.7561 -97.836253) (xy 71.685495 -97.808646) (xy 71.618224 -97.77369)
			(xy 71.555049 -97.731782) (xy 71.496687 -97.683396) (xy 71.443799 -97.62908) (xy 71.396984 -97.569451)
			(xy 71.356772 -97.505183) (xy 71.32362 -97.437006) (xy 71.297902 -97.36569) (xy 71.27991 -97.292045)
			(xy 71.269848 -97.216905) (xy 71.267829 -97.141121) (xy 70.151751 -97.141121) (xy 70.149732 -97.216905)
			(xy 70.13967 -97.292045) (xy 70.121678 -97.36569) (xy 70.09596 -97.437006) (xy 70.062808 -97.505183)
			(xy 70.022596 -97.569451) (xy 69.975781 -97.62908) (xy 69.922893 -97.683396) (xy 69.864531 -97.731782)
			(xy 69.801356 -97.77369) (xy 69.734085 -97.808646) (xy 69.66348 -97.836253) (xy 69.590339 -97.856199)
			(xy 69.515494 -97.868258) (xy 69.43979 -97.872293) (xy 69.364086 -97.868258) (xy 69.289241 -97.856199)
			(xy 69.2161 -97.836253) (xy 69.145495 -97.808646) (xy 69.078224 -97.77369) (xy 69.015049 -97.731782)
			(xy 68.956687 -97.683396) (xy 68.903799 -97.62908) (xy 68.856984 -97.569451) (xy 68.816772 -97.505183)
			(xy 68.78362 -97.437006) (xy 68.757902 -97.36569) (xy 68.73991 -97.292045) (xy 68.729848 -97.216905)
			(xy 68.727829 -97.141121) (xy 67.611751 -97.141121) (xy 67.609732 -97.216905) (xy 67.59967 -97.292045)
			(xy 67.581678 -97.36569) (xy 67.55596 -97.437006) (xy 67.522808 -97.505183) (xy 67.482596 -97.569451)
			(xy 67.435781 -97.62908) (xy 67.382893 -97.683396) (xy 67.324531 -97.731782) (xy 67.261356 -97.77369)
			(xy 67.194085 -97.808646) (xy 67.12348 -97.836253) (xy 67.050339 -97.856199) (xy 66.975494 -97.868258)
			(xy 66.89979 -97.872293) (xy 66.824086 -97.868258) (xy 66.749241 -97.856199) (xy 66.6761 -97.836253)
			(xy 66.605495 -97.808646) (xy 66.538224 -97.77369) (xy 66.475049 -97.731782) (xy 66.416687 -97.683396)
			(xy 66.363799 -97.62908) (xy 66.316984 -97.569451) (xy 66.276772 -97.505183) (xy 66.24362 -97.437006)
			(xy 66.217902 -97.36569) (xy 66.19991 -97.292045) (xy 66.189848 -97.216905) (xy 66.187829 -97.141121)
			(xy 65.071751 -97.141121) (xy 65.069732 -97.216905) (xy 65.05967 -97.292045) (xy 65.041678 -97.36569)
			(xy 65.01596 -97.437006) (xy 64.982808 -97.505183) (xy 64.942596 -97.569451) (xy 64.895781 -97.62908)
			(xy 64.842893 -97.683396) (xy 64.784531 -97.731782) (xy 64.721356 -97.77369) (xy 64.654085 -97.808646)
			(xy 64.58348 -97.836253) (xy 64.510339 -97.856199) (xy 64.435494 -97.868258) (xy 64.35979 -97.872293)
			(xy 64.284086 -97.868258) (xy 64.209241 -97.856199) (xy 64.1361 -97.836253) (xy 64.065495 -97.808646)
			(xy 63.998224 -97.77369) (xy 63.935049 -97.731782) (xy 63.876687 -97.683396) (xy 63.823799 -97.62908)
			(xy 63.776984 -97.569451) (xy 63.736772 -97.505183) (xy 63.70362 -97.437006) (xy 63.677902 -97.36569)
			(xy 63.65991 -97.292045) (xy 63.649848 -97.216905) (xy 63.647829 -97.141121) (xy 42.526017 -97.141121)
			(xy 42.478867 -97.177408) (xy 42.3822 -97.241698) (xy 42.281328 -97.299165) (xy 42.176731 -97.349536)
			(xy 42.068908 -97.392571) (xy 41.958374 -97.428065) (xy 41.845654 -97.455848) (xy 41.731286 -97.475788)
			(xy 41.615814 -97.48779) (xy 41.49979 -97.491797) (xy 41.383766 -97.48779) (xy 41.268294 -97.475788)
			(xy 41.153926 -97.455848) (xy 41.041206 -97.428065) (xy 40.930672 -97.392571) (xy 40.822849 -97.349536)
			(xy 40.718252 -97.299165) (xy 40.61738 -97.241698) (xy 40.520713 -97.177408) (xy 40.428712 -97.106603)
			(xy 40.341815 -97.029619) (xy 40.260436 -96.946823) (xy 40.184963 -96.85861) (xy 40.115756 -96.7654)
			(xy 40.053144 -96.667637) (xy 39.997427 -96.565788) (xy 39.948869 -96.460338) (xy 39.907701 -96.351789)
			(xy 39.874121 -96.240658) (xy 39.848288 -96.127475) (xy 39.830325 -96.01278) (xy 39.820317 -95.897118)
			(xy 39.818314 -95.781042) (xy 36.445333 -95.781042) (xy 36.431719 -95.828889) (xy 36.400327 -95.909921)
			(xy 36.361593 -95.98771) (xy 36.315846 -96.061594) (xy 36.263477 -96.130941) (xy 36.204933 -96.195161)
			(xy 36.140713 -96.253705) (xy 36.071366 -96.306074) (xy 35.997482 -96.351821) (xy 35.919693 -96.390555)
			(xy 35.838661 -96.421947) (xy 35.755079 -96.445728) (xy 35.669659 -96.461696) (xy 35.58313 -96.469714)
			(xy 35.49623 -96.469714) (xy 35.409701 -96.461696) (xy 35.324281 -96.445728) (xy 35.240699 -96.421947)
			(xy 35.159667 -96.390555) (xy 35.081878 -96.351821) (xy 35.007994 -96.306074) (xy 34.938647 -96.253705)
			(xy 34.874427 -96.195161) (xy 34.815883 -96.130941) (xy 34.763514 -96.061594) (xy 34.717767 -95.98771)
			(xy 34.679033 -95.909921) (xy 34.647641 -95.828889) (xy 34.62386 -95.745307) (xy 34.607892 -95.659887)
			(xy 34.599874 -95.573358) (xy 31.399486 -95.573358) (xy 31.391468 -95.659887) (xy 31.3755 -95.745307)
			(xy 31.351719 -95.828889) (xy 31.320327 -95.909921) (xy 31.281593 -95.98771) (xy 31.235846 -96.061594)
			(xy 31.183477 -96.130941) (xy 31.124933 -96.195161) (xy 31.060713 -96.253705) (xy 30.991366 -96.306074)
			(xy 30.917482 -96.351821) (xy 30.839693 -96.390555) (xy 30.758661 -96.421947) (xy 30.675079 -96.445728)
			(xy 30.589659 -96.461696) (xy 30.50313 -96.469714) (xy 30.41623 -96.469714) (xy 30.329701 -96.461696)
			(xy 30.244281 -96.445728) (xy 30.160699 -96.421947) (xy 30.079667 -96.390555) (xy 30.001878 -96.351821)
			(xy 29.927994 -96.306074) (xy 29.858647 -96.253705) (xy 29.794427 -96.195161) (xy 29.735883 -96.130941)
			(xy 29.683514 -96.061594) (xy 29.637767 -95.98771) (xy 29.599033 -95.909921) (xy 29.567641 -95.828889)
			(xy 29.54386 -95.745307) (xy 29.527892 -95.659887) (xy 29.519874 -95.573358) (xy 27.51439 -95.573358)
			(xy 27.518107 -95.607142) (xy 27.51607 -95.662876) (xy 27.50594 -95.717719) (xy 27.487933 -95.770503)
			(xy 27.462432 -95.820103) (xy 27.429981 -95.865461) (xy 27.391272 -95.90561) (xy 27.347129 -95.939696)
			(xy 27.298494 -95.966992) (xy 27.246403 -95.986915) (xy 27.191966 -95.999041) (xy 27.136344 -96.003112)
			(xy 27.080722 -95.999041) (xy 27.026285 -95.986915) (xy 26.974194 -95.966992) (xy 26.925559 -95.939696)
			(xy 26.881416 -95.90561) (xy 26.842707 -95.865461) (xy 26.810256 -95.820103) (xy 26.784755 -95.770503)
			(xy 26.766748 -95.717719) (xy 26.756618 -95.662876) (xy 26.754581 -95.607142) (xy 23.551896 -95.607142)
			(xy 23.551896 -98.113358) (xy 29.519874 -98.113358) (xy 29.519874 -98.026458) (xy 29.527892 -97.939929)
			(xy 29.54386 -97.854509) (xy 29.567641 -97.770927) (xy 29.599033 -97.689895) (xy 29.637767 -97.612106)
			(xy 29.683514 -97.538222) (xy 29.735883 -97.468875) (xy 29.794427 -97.404655) (xy 29.858647 -97.346111)
			(xy 29.927994 -97.293742) (xy 30.001878 -97.247995) (xy 30.079667 -97.209261) (xy 30.160699 -97.177869)
			(xy 30.244281 -97.154088) (xy 30.329701 -97.13812) (xy 30.41623 -97.130102) (xy 30.45968 -97.1296)
			(xy 30.50313 -97.130102) (xy 30.589659 -97.13812) (xy 30.675079 -97.154088) (xy 30.758661 -97.177869)
			(xy 30.839693 -97.209261) (xy 30.917482 -97.247995) (xy 30.991366 -97.293742) (xy 31.060713 -97.346111)
			(xy 31.124933 -97.404655) (xy 31.183477 -97.468875) (xy 31.235846 -97.538222) (xy 31.281593 -97.612106)
			(xy 31.320327 -97.689895) (xy 31.351719 -97.770927) (xy 31.3755 -97.854509) (xy 31.391468 -97.939929)
			(xy 31.399486 -98.026458) (xy 31.399486 -98.113358) (xy 34.599874 -98.113358) (xy 34.599874 -98.026458)
			(xy 34.607892 -97.939929) (xy 34.62386 -97.854509) (xy 34.647641 -97.770927) (xy 34.679033 -97.689895)
			(xy 34.717767 -97.612106) (xy 34.763514 -97.538222) (xy 34.815883 -97.468875) (xy 34.874427 -97.404655)
			(xy 34.938647 -97.346111) (xy 35.007994 -97.293742) (xy 35.081878 -97.247995) (xy 35.159667 -97.209261)
			(xy 35.240699 -97.177869) (xy 35.324281 -97.154088) (xy 35.409701 -97.13812) (xy 35.49623 -97.130102)
			(xy 35.53968 -97.1296) (xy 35.58313 -97.130102) (xy 35.669659 -97.13812) (xy 35.755079 -97.154088)
			(xy 35.838661 -97.177869) (xy 35.919693 -97.209261) (xy 35.997482 -97.247995) (xy 36.071366 -97.293742)
			(xy 36.140713 -97.346111) (xy 36.204933 -97.404655) (xy 36.263477 -97.468875) (xy 36.315846 -97.538222)
			(xy 36.361593 -97.612106) (xy 36.400327 -97.689895) (xy 36.431719 -97.770927) (xy 36.4555 -97.854509)
			(xy 36.471468 -97.939929) (xy 36.479486 -98.026458) (xy 36.479486 -98.113358) (xy 36.471468 -98.199887)
			(xy 36.4555 -98.285307) (xy 36.431719 -98.368889) (xy 36.400327 -98.449921) (xy 36.361593 -98.52771)
			(xy 36.315846 -98.601594) (xy 36.263477 -98.670941) (xy 36.204933 -98.735161) (xy 36.140713 -98.793705)
			(xy 36.071366 -98.846074) (xy 35.997482 -98.891821) (xy 35.919693 -98.930555) (xy 35.838661 -98.961947)
			(xy 35.755079 -98.985728) (xy 35.669659 -99.001696) (xy 35.58313 -99.009714) (xy 35.49623 -99.009714)
			(xy 35.409701 -99.001696) (xy 35.324281 -98.985728) (xy 35.240699 -98.961947) (xy 35.159667 -98.930555)
			(xy 35.081878 -98.891821) (xy 35.007994 -98.846074) (xy 34.938647 -98.793705) (xy 34.874427 -98.735161)
			(xy 34.815883 -98.670941) (xy 34.763514 -98.601594) (xy 34.717767 -98.52771) (xy 34.679033 -98.449921)
			(xy 34.647641 -98.368889) (xy 34.62386 -98.285307) (xy 34.607892 -98.199887) (xy 34.599874 -98.113358)
			(xy 31.399486 -98.113358) (xy 31.391468 -98.199887) (xy 31.3755 -98.285307) (xy 31.351719 -98.368889)
			(xy 31.320327 -98.449921) (xy 31.281593 -98.52771) (xy 31.235846 -98.601594) (xy 31.183477 -98.670941)
			(xy 31.124933 -98.735161) (xy 31.060713 -98.793705) (xy 30.991366 -98.846074) (xy 30.917482 -98.891821)
			(xy 30.839693 -98.930555) (xy 30.758661 -98.961947) (xy 30.675079 -98.985728) (xy 30.589659 -99.001696)
			(xy 30.50313 -99.009714) (xy 30.41623 -99.009714) (xy 30.329701 -99.001696) (xy 30.244281 -98.985728)
			(xy 30.160699 -98.961947) (xy 30.079667 -98.930555) (xy 30.001878 -98.891821) (xy 29.927994 -98.846074)
			(xy 29.858647 -98.793705) (xy 29.794427 -98.735161) (xy 29.735883 -98.670941) (xy 29.683514 -98.601594)
			(xy 29.637767 -98.52771) (xy 29.599033 -98.449921) (xy 29.567641 -98.368889) (xy 29.54386 -98.285307)
			(xy 29.527892 -98.199887) (xy 29.519874 -98.113358) (xy 23.551896 -98.113358) (xy 23.551896 -99.355674)
			(xy 26.722323 -99.355674) (xy 26.728423 -99.300237) (xy 26.742529 -99.24628) (xy 26.764341 -99.194951)
			(xy 26.793395 -99.147345) (xy 26.82907 -99.104477) (xy 26.870607 -99.06726) (xy 26.91712 -99.036487)
			(xy 26.967617 -99.012815) (xy 27.021024 -98.996747) (xy 27.0762 -98.988627) (xy 27.104086 -98.988118)
			(xy 27.131972 -98.988627) (xy 27.187148 -98.996747) (xy 27.240555 -99.012815) (xy 27.291052 -99.036487)
			(xy 27.337565 -99.06726) (xy 27.379102 -99.104477) (xy 27.414777 -99.147345) (xy 27.443831 -99.194951)
			(xy 27.465643 -99.24628) (xy 27.479749 -99.300237) (xy 27.485849 -99.355674) (xy 27.483812 -99.411408)
			(xy 27.473682 -99.466251) (xy 27.455675 -99.519035) (xy 27.430174 -99.568635) (xy 27.397723 -99.613993)
			(xy 27.359014 -99.654142) (xy 27.314871 -99.688228) (xy 27.266236 -99.715524) (xy 27.214145 -99.735447)
			(xy 27.159708 -99.747573) (xy 27.104086 -99.751644) (xy 27.048464 -99.747573) (xy 26.994027 -99.735447)
			(xy 26.941936 -99.715524) (xy 26.893301 -99.688228) (xy 26.849158 -99.654142) (xy 26.810449 -99.613993)
			(xy 26.777998 -99.568635) (xy 26.752497 -99.519035) (xy 26.73449 -99.466251) (xy 26.72436 -99.411408)
			(xy 26.722323 -99.355674) (xy 23.551896 -99.355674) (xy 23.551896 -100.644071) (xy 28.700637 -100.644071)
			(xy 28.703538 -100.589034) (xy 28.714329 -100.534987) (xy 28.732787 -100.483056) (xy 28.758526 -100.434323)
			(xy 28.791012 -100.389801) (xy 28.829567 -100.350418) (xy 28.873389 -100.316995) (xy 28.921565 -100.290226)
			(xy 28.973093 -100.27067) (xy 29.026898 -100.258733) (xy 29.081861 -100.254665) (xy 29.136838 -100.258549)
			(xy 29.190683 -100.270306) (xy 29.242275 -100.289689) (xy 29.266642 -100.302568) (xy 29.286857 -100.313124)
			(xy 29.330086 -100.327636) (xy 29.37521 -100.334207) (xy 29.420783 -100.332626) (xy 29.465343 -100.322943)
			(xy 29.507462 -100.30547) (xy 29.545791 -100.280766) (xy 29.5791 -100.249623) (xy 29.606321 -100.213039)
			(xy 29.616908 -100.19284) (xy 29.636481 -100.154349) (xy 29.681725 -100.080791) (xy 29.733522 -100.011691)
			(xy 29.791437 -99.947632) (xy 29.854981 -99.889152) (xy 29.923619 -99.836744) (xy 29.996773 -99.79085)
			(xy 30.073827 -99.751857) (xy 30.154131 -99.720093) (xy 30.23701 -99.695825) (xy 30.321764 -99.679258)
			(xy 30.40768 -99.670532) (xy 30.494035 -99.669719) (xy 30.5801 -99.676828) (xy 30.665151 -99.691797)
			(xy 30.748471 -99.714501) (xy 30.829359 -99.744749) (xy 30.907133 -99.782286) (xy 30.981137 -99.826795)
			(xy 31.050749 -99.877902) (xy 31.115383 -99.935176) (xy 31.174492 -99.998135) (xy 31.227581 -100.066248)
			(xy 31.2742 -100.138941) (xy 31.313959 -100.215603) (xy 31.346521 -100.295587) (xy 31.371613 -100.37822)
			(xy 31.389023 -100.462805) (xy 31.398604 -100.54863) (xy 31.400276 -100.634972) (xy 31.398942 -100.653358)
			(xy 34.599874 -100.653358) (xy 34.599874 -100.566458) (xy 34.607892 -100.479929) (xy 34.62386 -100.394509)
			(xy 34.647641 -100.310927) (xy 34.679033 -100.229895) (xy 34.717767 -100.152106) (xy 34.763514 -100.078222)
			(xy 34.815883 -100.008875) (xy 34.874427 -99.944655) (xy 34.938647 -99.886111) (xy 35.007994 -99.833742)
			(xy 35.081878 -99.787995) (xy 35.159667 -99.749261) (xy 35.240699 -99.717869) (xy 35.324281 -99.694088)
			(xy 35.409701 -99.67812) (xy 35.49623 -99.670102) (xy 35.53968 -99.6696) (xy 35.58313 -99.670102)
			(xy 35.669659 -99.67812) (xy 35.755079 -99.694088) (xy 35.838661 -99.717869) (xy 35.919693 -99.749261)
			(xy 35.997482 -99.787995) (xy 36.071366 -99.833742) (xy 36.140713 -99.886111) (xy 36.204933 -99.944655)
			(xy 36.263477 -100.008875) (xy 36.315846 -100.078222) (xy 36.361593 -100.152106) (xy 36.400327 -100.229895)
			(xy 36.431719 -100.310927) (xy 36.4555 -100.394509) (xy 36.471468 -100.479929) (xy 36.479486 -100.566458)
			(xy 36.479486 -100.653358) (xy 36.471468 -100.739887) (xy 36.4555 -100.825307) (xy 36.450559 -100.842673)
			(xy 60.260476 -100.842673) (xy 60.260476 -100.771351) (xy 60.268462 -100.700477) (xy 60.284332 -100.630942)
			(xy 60.307889 -100.563622) (xy 60.338834 -100.499363) (xy 60.37678 -100.438972) (xy 60.421249 -100.38321)
			(xy 60.471682 -100.332777) (xy 60.527444 -100.288308) (xy 60.587835 -100.250362) (xy 60.652094 -100.219417)
			(xy 60.719414 -100.19586) (xy 60.788949 -100.17999) (xy 60.859823 -100.172004) (xy 60.895484 -100.171504)
			(xy 60.931145 -100.172004) (xy 61.002019 -100.17999) (xy 61.071554 -100.19586) (xy 61.138874 -100.219417)
			(xy 61.203133 -100.250362) (xy 61.263524 -100.288308) (xy 61.319286 -100.332777) (xy 61.369719 -100.38321)
			(xy 61.414188 -100.438972) (xy 61.452134 -100.499363) (xy 61.483079 -100.563622) (xy 61.506636 -100.630942)
			(xy 61.522506 -100.700477) (xy 61.530492 -100.771351) (xy 61.530492 -100.842673) (xy 61.526399 -100.878995)
			(xy 62.538348 -100.878995) (xy 62.538348 -100.807673) (xy 62.546334 -100.736799) (xy 62.562204 -100.667264)
			(xy 62.585761 -100.599944) (xy 62.616706 -100.535685) (xy 62.654652 -100.475294) (xy 62.699121 -100.419532)
			(xy 62.749554 -100.369099) (xy 62.805316 -100.32463) (xy 62.865707 -100.286684) (xy 62.929966 -100.255739)
			(xy 62.997286 -100.232182) (xy 63.066821 -100.216312) (xy 63.137695 -100.208326) (xy 63.173356 -100.207826)
			(xy 63.209017 -100.208326) (xy 63.279891 -100.216312) (xy 63.349426 -100.232182) (xy 63.416746 -100.255739)
			(xy 63.481005 -100.286684) (xy 63.541396 -100.32463) (xy 63.597158 -100.369099) (xy 63.647591 -100.419532)
			(xy 63.69206 -100.475294) (xy 63.730006 -100.535685) (xy 63.760951 -100.599944) (xy 63.784508 -100.667264)
			(xy 63.800378 -100.736799) (xy 63.80521 -100.779681) (xy 64.78828 -100.779681) (xy 64.78828 -100.708359)
			(xy 64.796266 -100.637485) (xy 64.812136 -100.56795) (xy 64.835693 -100.50063) (xy 64.866638 -100.436371)
			(xy 64.904584 -100.37598) (xy 64.949053 -100.320218) (xy 64.999486 -100.269785) (xy 65.055248 -100.225316)
			(xy 65.115639 -100.18737) (xy 65.179898 -100.156425) (xy 65.247218 -100.132868) (xy 65.316753 -100.116998)
			(xy 65.387627 -100.109012) (xy 65.423288 -100.108512) (xy 65.458949 -100.109012) (xy 65.529823 -100.116998)
			(xy 65.599358 -100.132868) (xy 65.666678 -100.156425) (xy 65.730937 -100.18737) (xy 65.791328 -100.225316)
			(xy 65.84709 -100.269785) (xy 65.897523 -100.320218) (xy 65.941992 -100.37598) (xy 65.979938 -100.436371)
			(xy 66.010883 -100.50063) (xy 66.03444 -100.56795) (xy 66.05031 -100.637485) (xy 66.058296 -100.708359)
			(xy 66.058296 -100.779681) (xy 66.058267 -100.779935) (xy 66.939152 -100.779935) (xy 66.939152 -100.708613)
			(xy 66.947138 -100.637739) (xy 66.963008 -100.568204) (xy 66.986565 -100.500884) (xy 67.01751 -100.436625)
			(xy 67.055456 -100.376234) (xy 67.099925 -100.320472) (xy 67.150358 -100.270039) (xy 67.20612 -100.22557)
			(xy 67.266511 -100.187624) (xy 67.33077 -100.156679) (xy 67.39809 -100.133122) (xy 67.467625 -100.117252)
			(xy 67.538499 -100.109266) (xy 67.57416 -100.108766) (xy 67.609821 -100.109266) (xy 67.680695 -100.117252)
			(xy 67.75023 -100.133122) (xy 67.81755 -100.156679) (xy 67.881809 -100.187624) (xy 67.9422 -100.22557)
			(xy 67.997962 -100.270039) (xy 68.048395 -100.320472) (xy 68.092864 -100.376234) (xy 68.13081 -100.436625)
			(xy 68.161755 -100.500884) (xy 68.185312 -100.568204) (xy 68.201182 -100.637739) (xy 68.209168 -100.708613)
			(xy 68.209168 -100.779935) (xy 68.205075 -100.816257) (xy 69.095866 -100.816257) (xy 69.095866 -100.744935)
			(xy 69.103852 -100.674061) (xy 69.119722 -100.604526) (xy 69.143279 -100.537206) (xy 69.174224 -100.472947)
			(xy 69.21217 -100.412556) (xy 69.256639 -100.356794) (xy 69.307072 -100.306361) (xy 69.362834 -100.261892)
			(xy 69.423225 -100.223946) (xy 69.487484 -100.193001) (xy 69.554804 -100.169444) (xy 69.624339 -100.153574)
			(xy 69.695213 -100.145588) (xy 69.730874 -100.145088) (xy 69.766535 -100.145588) (xy 69.837409 -100.153574)
			(xy 69.906944 -100.169444) (xy 69.974264 -100.193001) (xy 70.038523 -100.223946) (xy 70.098914 -100.261892)
			(xy 70.154676 -100.306361) (xy 70.205109 -100.356794) (xy 70.249578 -100.412556) (xy 70.287524 -100.472947)
			(xy 70.318469 -100.537206) (xy 70.342026 -100.604526) (xy 70.357896 -100.674061) (xy 70.365882 -100.744935)
			(xy 70.365882 -100.816257) (xy 70.357896 -100.887131) (xy 70.342026 -100.956666) (xy 70.318469 -101.023986)
			(xy 70.287524 -101.088245) (xy 70.249578 -101.148636) (xy 70.205109 -101.204398) (xy 70.154676 -101.254831)
			(xy 70.098914 -101.2993) (xy 70.038523 -101.337246) (xy 69.974264 -101.368191) (xy 69.906944 -101.391748)
			(xy 69.837409 -101.407618) (xy 69.766535 -101.415604) (xy 69.695213 -101.415604) (xy 69.624339 -101.407618)
			(xy 69.554804 -101.391748) (xy 69.487484 -101.368191) (xy 69.423225 -101.337246) (xy 69.362834 -101.2993)
			(xy 69.307072 -101.254831) (xy 69.256639 -101.204398) (xy 69.21217 -101.148636) (xy 69.174224 -101.088245)
			(xy 69.143279 -101.023986) (xy 69.119722 -100.956666) (xy 69.103852 -100.887131) (xy 69.095866 -100.816257)
			(xy 68.205075 -100.816257) (xy 68.201182 -100.850809) (xy 68.185312 -100.920344) (xy 68.161755 -100.987664)
			(xy 68.13081 -101.051923) (xy 68.092864 -101.112314) (xy 68.048395 -101.168076) (xy 67.997962 -101.218509)
			(xy 67.9422 -101.262978) (xy 67.881809 -101.300924) (xy 67.81755 -101.331869) (xy 67.75023 -101.355426)
			(xy 67.680695 -101.371296) (xy 67.609821 -101.379282) (xy 67.538499 -101.379282) (xy 67.467625 -101.371296)
			(xy 67.39809 -101.355426) (xy 67.33077 -101.331869) (xy 67.266511 -101.300924) (xy 67.20612 -101.262978)
			(xy 67.150358 -101.218509) (xy 67.099925 -101.168076) (xy 67.055456 -101.112314) (xy 67.01751 -101.051923)
			(xy 66.986565 -100.987664) (xy 66.963008 -100.920344) (xy 66.947138 -100.850809) (xy 66.939152 -100.779935)
			(xy 66.058267 -100.779935) (xy 66.05031 -100.850555) (xy 66.03444 -100.92009) (xy 66.010883 -100.98741)
			(xy 65.979938 -101.051669) (xy 65.941992 -101.11206) (xy 65.897523 -101.167822) (xy 65.84709 -101.218255)
			(xy 65.791328 -101.262724) (xy 65.730937 -101.30067) (xy 65.666678 -101.331615) (xy 65.599358 -101.355172)
			(xy 65.529823 -101.371042) (xy 65.458949 -101.379028) (xy 65.387627 -101.379028) (xy 65.316753 -101.371042)
			(xy 65.247218 -101.355172) (xy 65.179898 -101.331615) (xy 65.115639 -101.30067) (xy 65.055248 -101.262724)
			(xy 64.999486 -101.218255) (xy 64.949053 -101.167822) (xy 64.904584 -101.11206) (xy 64.866638 -101.051669)
			(xy 64.835693 -100.98741) (xy 64.812136 -100.92009) (xy 64.796266 -100.850555) (xy 64.78828 -100.779681)
			(xy 63.80521 -100.779681) (xy 63.808364 -100.807673) (xy 63.808364 -100.878995) (xy 63.800378 -100.949869)
			(xy 63.784508 -101.019404) (xy 63.760951 -101.086724) (xy 63.730006 -101.150983) (xy 63.69206 -101.211374)
			(xy 63.647591 -101.267136) (xy 63.597158 -101.317569) (xy 63.541396 -101.362038) (xy 63.481005 -101.399984)
			(xy 63.416746 -101.430929) (xy 63.349426 -101.454486) (xy 63.279891 -101.470356) (xy 63.209017 -101.478342)
			(xy 63.137695 -101.478342) (xy 63.066821 -101.470356) (xy 62.997286 -101.454486) (xy 62.929966 -101.430929)
			(xy 62.865707 -101.399984) (xy 62.805316 -101.362038) (xy 62.749554 -101.317569) (xy 62.699121 -101.267136)
			(xy 62.654652 -101.211374) (xy 62.616706 -101.150983) (xy 62.585761 -101.086724) (xy 62.562204 -101.019404)
			(xy 62.546334 -100.949869) (xy 62.538348 -100.878995) (xy 61.526399 -100.878995) (xy 61.522506 -100.913547)
			(xy 61.506636 -100.983082) (xy 61.483079 -101.050402) (xy 61.452134 -101.114661) (xy 61.414188 -101.175052)
			(xy 61.369719 -101.230814) (xy 61.319286 -101.281247) (xy 61.263524 -101.325716) (xy 61.203133 -101.363662)
			(xy 61.138874 -101.394607) (xy 61.071554 -101.418164) (xy 61.002019 -101.434034) (xy 60.931145 -101.44202)
			(xy 60.859823 -101.44202) (xy 60.788949 -101.434034) (xy 60.719414 -101.418164) (xy 60.652094 -101.394607)
			(xy 60.587835 -101.363662) (xy 60.527444 -101.325716) (xy 60.471682 -101.281247) (xy 60.421249 -101.230814)
			(xy 60.37678 -101.175052) (xy 60.338834 -101.114661) (xy 60.307889 -101.050402) (xy 60.284332 -100.983082)
			(xy 60.268462 -100.913547) (xy 60.260476 -100.842673) (xy 36.450559 -100.842673) (xy 36.431719 -100.908889)
			(xy 36.400327 -100.989921) (xy 36.361593 -101.06771) (xy 36.315846 -101.141594) (xy 36.263477 -101.210941)
			(xy 36.204933 -101.275161) (xy 36.140713 -101.333705) (xy 36.071366 -101.386074) (xy 35.997482 -101.431821)
			(xy 35.919693 -101.470555) (xy 35.838661 -101.501947) (xy 35.755079 -101.525728) (xy 35.669659 -101.541696)
			(xy 35.58313 -101.549714) (xy 35.49623 -101.549714) (xy 35.409701 -101.541696) (xy 35.324281 -101.525728)
			(xy 35.240699 -101.501947) (xy 35.159667 -101.470555) (xy 35.081878 -101.431821) (xy 35.007994 -101.386074)
			(xy 34.938647 -101.333705) (xy 34.874427 -101.275161) (xy 34.815883 -101.210941) (xy 34.763514 -101.141594)
			(xy 34.717767 -101.06771) (xy 34.679033 -100.989921) (xy 34.647641 -100.908889) (xy 34.62386 -100.825307)
			(xy 34.607892 -100.739887) (xy 34.599874 -100.653358) (xy 31.398942 -100.653358) (xy 31.394025 -100.721104)
			(xy 31.379903 -100.8063) (xy 31.358029 -100.889842) (xy 31.328588 -100.971027) (xy 31.291828 -101.04917)
			(xy 31.248057 -101.123614) (xy 31.197646 -101.193732) (xy 31.141018 -101.258932) (xy 31.078651 -101.318665)
			(xy 31.01107 -101.372429) (xy 30.938844 -101.41977) (xy 30.862582 -101.46029) (xy 30.782926 -101.493647)
			(xy 30.700547 -101.51956) (xy 30.616139 -101.537811) (xy 30.530414 -101.548247) (xy 30.444093 -101.550778)
			(xy 30.357903 -101.545385) (xy 30.272571 -101.532112) (xy 30.188815 -101.511071) (xy 30.107341 -101.482439)
			(xy 30.028835 -101.446459) (xy 29.953959 -101.403431) (xy 29.883344 -101.353721) (xy 29.817583 -101.297745)
			(xy 29.757232 -101.235975) (xy 29.702798 -101.168933) (xy 29.65474 -101.097182) (xy 29.633672 -101.059488)
			(xy 29.622346 -101.039693) (xy 29.593782 -101.004146) (xy 29.559329 -100.974272) (xy 29.520095 -100.95103)
			(xy 29.477342 -100.935168) (xy 29.432443 -100.927195) (xy 29.386842 -100.927367) (xy 29.342005 -100.935679)
			(xy 29.299372 -100.951865) (xy 29.279596 -100.963222) (xy 29.255722 -100.976995) (xy 29.204927 -100.998382)
			(xy 29.151583 -101.012236) (xy 29.096801 -101.018268) (xy 29.041721 -101.016353) (xy 28.98749 -101.00653)
			(xy 28.935237 -100.989004) (xy 28.886051 -100.96414) (xy 28.840955 -100.932456) (xy 28.800889 -100.894612)
			(xy 28.766686 -100.851395) (xy 28.73906 -100.803705) (xy 28.718585 -100.752536) (xy 28.705688 -100.698953)
			(xy 28.700637 -100.644071) (xy 23.551896 -100.644071) (xy 23.551896 -101.892626) (xy 39.461947 -101.892626)
			(xy 39.468047 -101.837189) (xy 39.482153 -101.783232) (xy 39.503965 -101.731903) (xy 39.533019 -101.684297)
			(xy 39.568694 -101.641429) (xy 39.610231 -101.604212) (xy 39.656744 -101.573439) (xy 39.707241 -101.549767)
			(xy 39.760648 -101.533699) (xy 39.815824 -101.525579) (xy 39.84371 -101.52507) (xy 39.871596 -101.525579)
			(xy 39.926772 -101.533699) (xy 39.980179 -101.549767) (xy 40.030676 -101.573439) (xy 40.077189 -101.604212)
			(xy 40.118726 -101.641429) (xy 40.154401 -101.684297) (xy 40.183455 -101.731903) (xy 40.205267 -101.783232)
			(xy 40.219373 -101.837189) (xy 40.225473 -101.892626) (xy 40.223436 -101.94836) (xy 40.213306 -102.003203)
			(xy 40.209696 -102.013784) (xy 86.510875 -102.013784) (xy 86.516975 -101.958347) (xy 86.531081 -101.90439)
			(xy 86.552893 -101.853061) (xy 86.581947 -101.805455) (xy 86.617622 -101.762587) (xy 86.659159 -101.72537)
			(xy 86.705672 -101.694597) (xy 86.756169 -101.670925) (xy 86.809576 -101.654857) (xy 86.864752 -101.646737)
			(xy 86.892638 -101.646228) (xy 86.920524 -101.646737) (xy 86.9757 -101.654857) (xy 87.029107 -101.670925)
			(xy 87.079604 -101.694597) (xy 87.126117 -101.72537) (xy 87.167654 -101.762587) (xy 87.203329 -101.805455)
			(xy 87.232383 -101.853061) (xy 87.254195 -101.90439) (xy 87.268301 -101.958347) (xy 87.274401 -102.013784)
			(xy 87.272364 -102.069518) (xy 87.262234 -102.124361) (xy 87.244227 -102.177145) (xy 87.218726 -102.226745)
			(xy 87.186275 -102.272103) (xy 87.147566 -102.312252) (xy 87.103423 -102.346338) (xy 87.054788 -102.373634)
			(xy 87.002697 -102.393557) (xy 86.94826 -102.405683) (xy 86.892638 -102.409754) (xy 86.837016 -102.405683)
			(xy 86.782579 -102.393557) (xy 86.730488 -102.373634) (xy 86.681853 -102.346338) (xy 86.63771 -102.312252)
			(xy 86.599001 -102.272103) (xy 86.56655 -102.226745) (xy 86.541049 -102.177145) (xy 86.523042 -102.124361)
			(xy 86.512912 -102.069518) (xy 86.510875 -102.013784) (xy 40.209696 -102.013784) (xy 40.195299 -102.055987)
			(xy 40.169798 -102.105587) (xy 40.137347 -102.150945) (xy 40.098638 -102.191094) (xy 40.054495 -102.22518)
			(xy 40.00586 -102.252476) (xy 39.953769 -102.272399) (xy 39.899332 -102.284525) (xy 39.84371 -102.288596)
			(xy 39.788088 -102.284525) (xy 39.733651 -102.272399) (xy 39.68156 -102.252476) (xy 39.632925 -102.22518)
			(xy 39.588782 -102.191094) (xy 39.550073 -102.150945) (xy 39.517622 -102.105587) (xy 39.492121 -102.055987)
			(xy 39.474114 -102.003203) (xy 39.463984 -101.94836) (xy 39.461947 -101.892626) (xy 23.551896 -101.892626)
			(xy 23.551896 -105.596436) (xy 23.552412 -105.613086) (xy 23.561038 -105.645248) (xy 23.577693 -105.674084)
			(xy 23.601242 -105.697627) (xy 23.630081 -105.714275) (xy 23.662246 -105.722892) (xy 23.678896 -105.723436)
			(xy 23.706611 -105.723969) (xy 23.761448 -105.732059) (xy 23.814539 -105.747996) (xy 23.864765 -105.771446)
			(xy 23.911071 -105.801915) (xy 23.952482 -105.838762) (xy 23.988128 -105.881212) (xy 24.017257 -105.928372)
			(xy 24.039258 -105.97925) (xy 24.046942 -106.005884) (xy 24.053237 -106.027142) (xy 24.072031 -106.067289)
			(xy 24.097505 -106.103566) (xy 24.128886 -106.134874) (xy 24.165223 -106.160264) (xy 24.205413 -106.178965)
			(xy 24.248238 -106.19041) (xy 24.292399 -106.194253) (xy 24.336557 -106.190376) (xy 24.379373 -106.178897)
			(xy 24.419548 -106.160165) (xy 24.455865 -106.134748) (xy 24.471884 -106.119422) (xy 26.64841 -103.942896)
			(xy 26.648918 -103.942896) (xy 26.665567 -103.942372) (xy 26.697731 -103.93375) (xy 26.726567 -103.917097)
			(xy 26.750111 -103.893549) (xy 26.766758 -103.86471) (xy 26.775375 -103.832546) (xy 26.775918 -103.815896)
			(xy 26.775918 -103.773224) (xy 26.724102 -103.705152) (xy 26.6827 -103.693722) (xy 26.656289 -103.685906)
			(xy 26.605871 -103.663731) (xy 26.559166 -103.634537) (xy 26.517145 -103.598931) (xy 26.480679 -103.557653)
			(xy 26.450527 -103.511561) (xy 26.427317 -103.461612) (xy 26.411529 -103.408845) (xy 26.403493 -103.354356)
			(xy 26.403375 -103.299277) (xy 26.411178 -103.244754) (xy 26.426739 -103.19192) (xy 26.449735 -103.141872)
			(xy 26.479689 -103.095651) (xy 26.515978 -103.054217) (xy 26.557847 -103.018431) (xy 26.604426 -102.989037)
			(xy 26.654748 -102.966647) (xy 26.707766 -102.951724) (xy 26.762379 -102.94458) (xy 26.817452 -102.945363)
			(xy 26.87184 -102.954056) (xy 26.924413 -102.97048) (xy 26.974078 -102.994291) (xy 27.019803 -103.024997)
			(xy 27.060638 -103.061958) (xy 27.095735 -103.104407) (xy 27.124363 -103.151461) (xy 27.145927 -103.202142)
			(xy 27.159981 -103.255397) (xy 27.166231 -103.31012) (xy 27.164547 -103.365173) (xy 27.154966 -103.419411)
			(xy 27.137685 -103.471709) (xy 27.113064 -103.520978) (xy 27.097736 -103.543862) (xy 27.085017 -103.563105)
			(xy 27.065949 -103.605101) (xy 27.054773 -103.649847) (xy 27.051855 -103.695876) (xy 27.057291 -103.741676)
			(xy 27.070902 -103.785743) (xy 27.092242 -103.826631) (xy 27.120609 -103.862997) (xy 27.155073 -103.893646)
			(xy 27.194502 -103.917574) (xy 27.237601 -103.933994) (xy 27.282956 -103.942367) (xy 27.306016 -103.942896)
			(xy 29.393896 -103.942896) (xy 29.41746 -103.942411) (xy 29.463782 -103.933744) (xy 29.507714 -103.916688)
			(xy 29.54775 -103.891827) (xy 29.582518 -103.860012) (xy 29.610826 -103.822335) (xy 29.631705 -103.780086)
			(xy 29.644439 -103.734712) (xy 29.648592 -103.687769) (xy 29.644022 -103.640864) (xy 29.630885 -103.595605)
			(xy 29.620718 -103.574342) (xy 29.601702 -103.535682) (xy 29.569999 -103.455565) (xy 29.545758 -103.372884)
			(xy 29.529182 -103.288332) (xy 29.520411 -103.202618) (xy 29.519518 -103.116461) (xy 29.526511 -103.030584)
			(xy 29.541331 -102.945706) (xy 29.563853 -102.86254) (xy 29.593889 -102.781784) (xy 29.631188 -102.704114)
			(xy 29.675435 -102.630181) (xy 29.72626 -102.560607) (xy 29.783237 -102.495974) (xy 29.845888 -102.436824)
			(xy 29.913688 -102.383654) (xy 29.986067 -102.33691) (xy 30.062419 -102.296983) (xy 30.142104 -102.264208)
			(xy 30.224452 -102.23886) (xy 30.308775 -102.221153) (xy 30.394363 -102.211233) (xy 30.480501 -102.209186)
			(xy 30.566464 -102.215026) (xy 30.651533 -102.228707) (xy 30.734993 -102.250112) (xy 30.816145 -102.279063)
			(xy 30.894308 -102.315317) (xy 30.968827 -102.358569) (xy 31.039077 -102.408457) (xy 31.104468 -102.464563)
			(xy 31.164452 -102.526415) (xy 31.218526 -102.593496) (xy 31.266237 -102.665242) (xy 31.307184 -102.741052)
			(xy 31.341024 -102.82029) (xy 31.367473 -102.902291) (xy 31.386309 -102.986369) (xy 31.397375 -103.071817)
			(xy 31.400578 -103.157919) (xy 31.398718 -103.200962) (xy 31.397915 -103.222837) (xy 31.403022 -103.266309)
			(xy 31.415506 -103.308263) (xy 31.434996 -103.347456) (xy 31.460916 -103.382728) (xy 31.492498 -103.413034)
			(xy 31.528808 -103.437479) (xy 31.568771 -103.455337) (xy 31.611203 -103.466081) (xy 31.654849 -103.469392)
			(xy 31.698417 -103.465172) (xy 31.740617 -103.453547) (xy 31.780199 -103.43486) (xy 31.815992 -103.409665)
			(xy 31.831788 -103.39451) (xy 32.394398 -102.8319) (xy 34.569654 -102.8319) (xy 34.584138 -102.83152)
			(xy 34.612353 -102.824949) (xy 34.638357 -102.812182) (xy 34.66081 -102.793877) (xy 34.678554 -102.770978)
			(xy 34.68497 -102.757986) (xy 34.703427 -102.718897) (xy 34.74652 -102.643954) (xy 34.79631 -102.573283)
			(xy 34.852377 -102.50748) (xy 34.914247 -102.447102) (xy 34.981398 -102.392657) (xy 35.053264 -102.344607)
			(xy 35.129237 -102.303356) (xy 35.208675 -102.269253) (xy 35.290908 -102.242586) (xy 35.375242 -102.223579)
			(xy 35.460965 -102.212394) (xy 35.547352 -102.209125) (xy 35.633675 -102.213799) (xy 35.719205 -102.226377)
			(xy 35.803218 -102.246753) (xy 35.885007 -102.274754) (xy 35.96388 -102.310145) (xy 36.039172 -102.352627)
			(xy 36.110246 -102.40184) (xy 36.176503 -102.457369) (xy 36.237383 -102.518746) (xy 36.292372 -102.585452)
			(xy 36.309369 -102.61043) (xy 84.840825 -102.61043) (xy 84.846925 -102.554993) (xy 84.861031 -102.501036)
			(xy 84.882843 -102.449707) (xy 84.911897 -102.402101) (xy 84.947572 -102.359233) (xy 84.989109 -102.322016)
			(xy 85.035622 -102.291243) (xy 85.086119 -102.267571) (xy 85.139526 -102.251503) (xy 85.194702 -102.243383)
			(xy 85.222588 -102.242874) (xy 85.250474 -102.243383) (xy 85.30565 -102.251503) (xy 85.359057 -102.267571)
			(xy 85.409554 -102.291243) (xy 85.456067 -102.322016) (xy 85.497604 -102.359233) (xy 85.533279 -102.402101)
			(xy 85.562333 -102.449707) (xy 85.584145 -102.501036) (xy 85.598251 -102.554993) (xy 85.604351 -102.61043)
			(xy 85.602314 -102.666164) (xy 85.592184 -102.721007) (xy 85.574177 -102.773791) (xy 85.548676 -102.823391)
			(xy 85.516225 -102.868749) (xy 85.477516 -102.908898) (xy 85.433373 -102.942984) (xy 85.384738 -102.97028)
			(xy 85.332647 -102.990203) (xy 85.27821 -103.002329) (xy 85.222588 -103.0064) (xy 85.166966 -103.002329)
			(xy 85.112529 -102.990203) (xy 85.060438 -102.97028) (xy 85.011803 -102.942984) (xy 84.96766 -102.908898)
			(xy 84.928951 -102.868749) (xy 84.8965 -102.823391) (xy 84.870999 -102.773791) (xy 84.852992 -102.721007)
			(xy 84.842862 -102.666164) (xy 84.840825 -102.61043) (xy 36.309369 -102.61043) (xy 36.341006 -102.656924)
			(xy 36.382874 -102.732558) (xy 36.417623 -102.811716) (xy 36.444959 -102.893729) (xy 36.464651 -102.977906)
			(xy 36.476534 -103.063535) (xy 36.480506 -103.149893) (xy 36.476535 -103.236251) (xy 36.464654 -103.32188)
			(xy 36.444963 -103.406057) (xy 36.417628 -103.48807) (xy 36.406473 -103.513483) (xy 60.260476 -103.513483)
			(xy 60.260476 -103.442161) (xy 60.268462 -103.371287) (xy 60.284332 -103.301752) (xy 60.307889 -103.234432)
			(xy 60.338834 -103.170173) (xy 60.37678 -103.109782) (xy 60.421249 -103.05402) (xy 60.471682 -103.003587)
			(xy 60.527444 -102.959118) (xy 60.587835 -102.921172) (xy 60.652094 -102.890227) (xy 60.719414 -102.86667)
			(xy 60.788949 -102.8508) (xy 60.859823 -102.842814) (xy 60.895484 -102.842314) (xy 60.931145 -102.842814)
			(xy 61.002019 -102.8508) (xy 61.071554 -102.86667) (xy 61.138874 -102.890227) (xy 61.203133 -102.921172)
			(xy 61.263524 -102.959118) (xy 61.319286 -103.003587) (xy 61.369719 -103.05402) (xy 61.414188 -103.109782)
			(xy 61.452134 -103.170173) (xy 61.483079 -103.234432) (xy 61.506636 -103.301752) (xy 61.522506 -103.371287)
			(xy 61.530492 -103.442161) (xy 61.530492 -103.513483) (xy 61.526399 -103.549805) (xy 62.538348 -103.549805)
			(xy 62.538348 -103.478483) (xy 62.546334 -103.407609) (xy 62.562204 -103.338074) (xy 62.585761 -103.270754)
			(xy 62.616706 -103.206495) (xy 62.654652 -103.146104) (xy 62.699121 -103.090342) (xy 62.749554 -103.039909)
			(xy 62.805316 -102.99544) (xy 62.865707 -102.957494) (xy 62.929966 -102.926549) (xy 62.997286 -102.902992)
			(xy 63.066821 -102.887122) (xy 63.137695 -102.879136) (xy 63.173356 -102.878636) (xy 63.209017 -102.879136)
			(xy 63.279891 -102.887122) (xy 63.349426 -102.902992) (xy 63.416746 -102.926549) (xy 63.481005 -102.957494)
			(xy 63.541396 -102.99544) (xy 63.597158 -103.039909) (xy 63.647591 -103.090342) (xy 63.69206 -103.146104)
			(xy 63.730006 -103.206495) (xy 63.760951 -103.270754) (xy 63.784508 -103.338074) (xy 63.800378 -103.407609)
			(xy 63.80521 -103.450491) (xy 64.78828 -103.450491) (xy 64.78828 -103.379169) (xy 64.796266 -103.308295)
			(xy 64.812136 -103.23876) (xy 64.835693 -103.17144) (xy 64.866638 -103.107181) (xy 64.904584 -103.04679)
			(xy 64.949053 -102.991028) (xy 64.999486 -102.940595) (xy 65.055248 -102.896126) (xy 65.115639 -102.85818)
			(xy 65.179898 -102.827235) (xy 65.247218 -102.803678) (xy 65.316753 -102.787808) (xy 65.387627 -102.779822)
			(xy 65.423288 -102.779322) (xy 65.458949 -102.779822) (xy 65.529823 -102.787808) (xy 65.599358 -102.803678)
			(xy 65.666678 -102.827235) (xy 65.730937 -102.85818) (xy 65.791328 -102.896126) (xy 65.84709 -102.940595)
			(xy 65.897523 -102.991028) (xy 65.941992 -103.04679) (xy 65.979938 -103.107181) (xy 66.010883 -103.17144)
			(xy 66.03444 -103.23876) (xy 66.05031 -103.308295) (xy 66.058296 -103.379169) (xy 66.058296 -103.450491)
			(xy 66.058267 -103.450745) (xy 66.939152 -103.450745) (xy 66.939152 -103.379423) (xy 66.947138 -103.308549)
			(xy 66.963008 -103.239014) (xy 66.986565 -103.171694) (xy 67.01751 -103.107435) (xy 67.055456 -103.047044)
			(xy 67.099925 -102.991282) (xy 67.150358 -102.940849) (xy 67.20612 -102.89638) (xy 67.266511 -102.858434)
			(xy 67.33077 -102.827489) (xy 67.39809 -102.803932) (xy 67.467625 -102.788062) (xy 67.538499 -102.780076)
			(xy 67.57416 -102.779576) (xy 67.609821 -102.780076) (xy 67.680695 -102.788062) (xy 67.75023 -102.803932)
			(xy 67.81755 -102.827489) (xy 67.881809 -102.858434) (xy 67.9422 -102.89638) (xy 67.997962 -102.940849)
			(xy 68.048395 -102.991282) (xy 68.092864 -103.047044) (xy 68.13081 -103.107435) (xy 68.161755 -103.171694)
			(xy 68.185312 -103.239014) (xy 68.201182 -103.308549) (xy 68.209168 -103.379423) (xy 68.209168 -103.450745)
			(xy 68.205075 -103.487067) (xy 69.095866 -103.487067) (xy 69.095866 -103.415745) (xy 69.103852 -103.344871)
			(xy 69.119722 -103.275336) (xy 69.143279 -103.208016) (xy 69.174224 -103.143757) (xy 69.21217 -103.083366)
			(xy 69.256639 -103.027604) (xy 69.307072 -102.977171) (xy 69.362834 -102.932702) (xy 69.423225 -102.894756)
			(xy 69.487484 -102.863811) (xy 69.554804 -102.840254) (xy 69.624339 -102.824384) (xy 69.695213 -102.816398)
			(xy 69.730874 -102.815898) (xy 69.766535 -102.816398) (xy 69.837409 -102.824384) (xy 69.906944 -102.840254)
			(xy 69.974264 -102.863811) (xy 70.038523 -102.894756) (xy 70.098914 -102.932702) (xy 70.154676 -102.977171)
			(xy 70.205109 -103.027604) (xy 70.249578 -103.083366) (xy 70.287524 -103.143757) (xy 70.318469 -103.208016)
			(xy 70.342026 -103.275336) (xy 70.357896 -103.344871) (xy 70.365882 -103.415745) (xy 70.365882 -103.487067)
			(xy 70.357896 -103.557941) (xy 70.342026 -103.627476) (xy 70.318469 -103.694796) (xy 70.287524 -103.759055)
			(xy 70.249578 -103.819446) (xy 70.205109 -103.875208) (xy 70.154676 -103.925641) (xy 70.153082 -103.926912)
			(xy 83.171537 -103.926912) (xy 83.177637 -103.871475) (xy 83.191743 -103.817518) (xy 83.213555 -103.766189)
			(xy 83.242609 -103.718583) (xy 83.278284 -103.675715) (xy 83.319821 -103.638498) (xy 83.366334 -103.607725)
			(xy 83.416831 -103.584053) (xy 83.470238 -103.567985) (xy 83.525414 -103.559865) (xy 83.5533 -103.559356)
			(xy 83.581186 -103.559865) (xy 83.636362 -103.567985) (xy 83.689769 -103.584053) (xy 83.740266 -103.607725)
			(xy 83.786779 -103.638498) (xy 83.828316 -103.675715) (xy 83.863991 -103.718583) (xy 83.893045 -103.766189)
			(xy 83.914857 -103.817518) (xy 83.928963 -103.871475) (xy 83.935063 -103.926912) (xy 83.933026 -103.982646)
			(xy 83.922896 -104.037489) (xy 83.904889 -104.090273) (xy 83.879388 -104.139873) (xy 83.846937 -104.185231)
			(xy 83.808228 -104.22538) (xy 83.764085 -104.259466) (xy 83.71545 -104.286762) (xy 83.663359 -104.306685)
			(xy 83.608922 -104.318811) (xy 83.5533 -104.322882) (xy 83.497678 -104.318811) (xy 83.443241 -104.306685)
			(xy 83.39115 -104.286762) (xy 83.342515 -104.259466) (xy 83.298372 -104.22538) (xy 83.259663 -104.185231)
			(xy 83.227212 -104.139873) (xy 83.201711 -104.090273) (xy 83.183704 -104.037489) (xy 83.173574 -103.982646)
			(xy 83.171537 -103.926912) (xy 70.153082 -103.926912) (xy 70.098914 -103.97011) (xy 70.038523 -104.008056)
			(xy 69.974264 -104.039001) (xy 69.906944 -104.062558) (xy 69.837409 -104.078428) (xy 69.766535 -104.086414)
			(xy 69.695213 -104.086414) (xy 69.624339 -104.078428) (xy 69.554804 -104.062558) (xy 69.487484 -104.039001)
			(xy 69.423225 -104.008056) (xy 69.362834 -103.97011) (xy 69.307072 -103.925641) (xy 69.256639 -103.875208)
			(xy 69.21217 -103.819446) (xy 69.174224 -103.759055) (xy 69.143279 -103.694796) (xy 69.119722 -103.627476)
			(xy 69.103852 -103.557941) (xy 69.095866 -103.487067) (xy 68.205075 -103.487067) (xy 68.201182 -103.521619)
			(xy 68.185312 -103.591154) (xy 68.161755 -103.658474) (xy 68.13081 -103.722733) (xy 68.092864 -103.783124)
			(xy 68.048395 -103.838886) (xy 67.997962 -103.889319) (xy 67.9422 -103.933788) (xy 67.881809 -103.971734)
			(xy 67.81755 -104.002679) (xy 67.75023 -104.026236) (xy 67.680695 -104.042106) (xy 67.609821 -104.050092)
			(xy 67.538499 -104.050092) (xy 67.467625 -104.042106) (xy 67.39809 -104.026236) (xy 67.33077 -104.002679)
			(xy 67.266511 -103.971734) (xy 67.20612 -103.933788) (xy 67.150358 -103.889319) (xy 67.099925 -103.838886)
			(xy 67.055456 -103.783124) (xy 67.01751 -103.722733) (xy 66.986565 -103.658474) (xy 66.963008 -103.591154)
			(xy 66.947138 -103.521619) (xy 66.939152 -103.450745) (xy 66.058267 -103.450745) (xy 66.05031 -103.521365)
			(xy 66.03444 -103.5909) (xy 66.010883 -103.65822) (xy 65.979938 -103.722479) (xy 65.941992 -103.78287)
			(xy 65.897523 -103.838632) (xy 65.84709 -103.889065) (xy 65.791328 -103.933534) (xy 65.730937 -103.97148)
			(xy 65.666678 -104.002425) (xy 65.599358 -104.025982) (xy 65.529823 -104.041852) (xy 65.458949 -104.049838)
			(xy 65.387627 -104.049838) (xy 65.316753 -104.041852) (xy 65.247218 -104.025982) (xy 65.179898 -104.002425)
			(xy 65.115639 -103.97148) (xy 65.055248 -103.933534) (xy 64.999486 -103.889065) (xy 64.949053 -103.838632)
			(xy 64.904584 -103.78287) (xy 64.866638 -103.722479) (xy 64.835693 -103.65822) (xy 64.812136 -103.5909)
			(xy 64.796266 -103.521365) (xy 64.78828 -103.450491) (xy 63.80521 -103.450491) (xy 63.808364 -103.478483)
			(xy 63.808364 -103.549805) (xy 63.800378 -103.620679) (xy 63.784508 -103.690214) (xy 63.760951 -103.757534)
			(xy 63.730006 -103.821793) (xy 63.69206 -103.882184) (xy 63.647591 -103.937946) (xy 63.597158 -103.988379)
			(xy 63.541396 -104.032848) (xy 63.481005 -104.070794) (xy 63.416746 -104.101739) (xy 63.349426 -104.125296)
			(xy 63.279891 -104.141166) (xy 63.209017 -104.149152) (xy 63.137695 -104.149152) (xy 63.066821 -104.141166)
			(xy 62.997286 -104.125296) (xy 62.929966 -104.101739) (xy 62.865707 -104.070794) (xy 62.805316 -104.032848)
			(xy 62.749554 -103.988379) (xy 62.699121 -103.937946) (xy 62.654652 -103.882184) (xy 62.616706 -103.821793)
			(xy 62.585761 -103.757534) (xy 62.562204 -103.690214) (xy 62.546334 -103.620679) (xy 62.538348 -103.549805)
			(xy 61.526399 -103.549805) (xy 61.522506 -103.584357) (xy 61.506636 -103.653892) (xy 61.483079 -103.721212)
			(xy 61.452134 -103.785471) (xy 61.414188 -103.845862) (xy 61.369719 -103.901624) (xy 61.319286 -103.952057)
			(xy 61.263524 -103.996526) (xy 61.203133 -104.034472) (xy 61.138874 -104.065417) (xy 61.071554 -104.088974)
			(xy 61.002019 -104.104844) (xy 60.931145 -104.11283) (xy 60.859823 -104.11283) (xy 60.788949 -104.104844)
			(xy 60.719414 -104.088974) (xy 60.652094 -104.065417) (xy 60.587835 -104.034472) (xy 60.527444 -103.996526)
			(xy 60.471682 -103.952057) (xy 60.421249 -103.901624) (xy 60.37678 -103.845862) (xy 60.338834 -103.785471)
			(xy 60.307889 -103.721212) (xy 60.284332 -103.653892) (xy 60.268462 -103.584357) (xy 60.260476 -103.513483)
			(xy 36.406473 -103.513483) (xy 36.38288 -103.567229) (xy 36.341013 -103.642864) (xy 36.292381 -103.714337)
			(xy 36.237393 -103.781043) (xy 36.176514 -103.842421) (xy 36.110258 -103.897951) (xy 36.039184 -103.947166)
			(xy 35.963893 -103.989648) (xy 35.885021 -104.02504) (xy 35.803232 -104.053043) (xy 35.719219 -104.07342)
			(xy 35.63369 -104.086) (xy 35.547367 -104.090675) (xy 35.460979 -104.087407) (xy 35.375257 -104.076223)
			(xy 35.290922 -104.057218) (xy 35.208689 -104.030552) (xy 35.12925 -103.99645) (xy 35.053276 -103.9552)
			(xy 34.98141 -103.907151) (xy 34.914258 -103.852708) (xy 34.852387 -103.792331) (xy 34.796319 -103.726529)
			(xy 34.746527 -103.655859) (xy 34.703433 -103.580916) (xy 34.68497 -103.54183) (xy 34.678585 -103.52882)
			(xy 34.660847 -103.505909) (xy 34.638387 -103.487602) (xy 34.612369 -103.474847) (xy 34.584142 -103.468306)
			(xy 34.569654 -103.467916) (xy 32.657542 -103.467916) (xy 31.546546 -104.578912) (xy 31.291276 -104.578912)
			(xy 31.268112 -104.579458) (xy 31.222559 -104.587896) (xy 31.17929 -104.604452) (xy 31.139739 -104.628576)
			(xy 31.105216 -104.65947) (xy 31.076864 -104.696111) (xy 31.055625 -104.737283) (xy 31.0422 -104.781624)
			(xy 31.037035 -104.827663) (xy 31.040301 -104.873876) (xy 31.05189 -104.918731) (xy 31.071418 -104.960743)
			(xy 31.098238 -104.998518) (xy 31.114492 -105.01503) (xy 31.145529 -105.04584) (xy 31.202373 -105.112309)
			(xy 31.252798 -105.183769) (xy 31.29637 -105.259603) (xy 31.332712 -105.339155) (xy 31.36151 -105.421738)
			(xy 31.382515 -105.506639) (xy 31.395546 -105.593123) (xy 31.40049 -105.680443) (xy 31.398561 -105.733358)
			(xy 34.599874 -105.733358) (xy 34.599874 -105.646458) (xy 34.607892 -105.559929) (xy 34.62386 -105.474509)
			(xy 34.647641 -105.390927) (xy 34.679033 -105.309895) (xy 34.717767 -105.232106) (xy 34.763514 -105.158222)
			(xy 34.815883 -105.088875) (xy 34.874427 -105.024655) (xy 34.938647 -104.966111) (xy 35.007994 -104.913742)
			(xy 35.081878 -104.867995) (xy 35.159667 -104.829261) (xy 35.240699 -104.797869) (xy 35.324281 -104.774088)
			(xy 35.409701 -104.75812) (xy 35.49623 -104.750102) (xy 35.53968 -104.7496) (xy 35.58313 -104.750102)
			(xy 35.669659 -104.75812) (xy 35.755079 -104.774088) (xy 35.838661 -104.797869) (xy 35.919693 -104.829261)
			(xy 35.997482 -104.867995) (xy 36.071366 -104.913742) (xy 36.140713 -104.966111) (xy 36.204933 -105.024655)
			(xy 36.263477 -105.088875) (xy 36.300179 -105.137476) (xy 82.472021 -105.137476) (xy 82.478121 -105.082039)
			(xy 82.492227 -105.028082) (xy 82.514039 -104.976753) (xy 82.543093 -104.929147) (xy 82.578768 -104.886279)
			(xy 82.620305 -104.849062) (xy 82.666818 -104.818289) (xy 82.717315 -104.794617) (xy 82.770722 -104.778549)
			(xy 82.825898 -104.770429) (xy 82.853784 -104.76992) (xy 82.88167 -104.770429) (xy 82.936846 -104.778549)
			(xy 82.990253 -104.794617) (xy 83.04075 -104.818289) (xy 83.087263 -104.849062) (xy 83.1288 -104.886279)
			(xy 83.164475 -104.929147) (xy 83.193529 -104.976753) (xy 83.215341 -105.028082) (xy 83.229447 -105.082039)
			(xy 83.235547 -105.137476) (xy 83.23351 -105.19321) (xy 83.22338 -105.248053) (xy 83.205373 -105.300837)
			(xy 83.179872 -105.350437) (xy 83.147421 -105.395795) (xy 83.108712 -105.435944) (xy 83.064569 -105.47003)
			(xy 83.015934 -105.497326) (xy 82.963843 -105.517249) (xy 82.909406 -105.529375) (xy 82.853784 -105.533446)
			(xy 82.798162 -105.529375) (xy 82.743725 -105.517249) (xy 82.691634 -105.497326) (xy 82.642999 -105.47003)
			(xy 82.598856 -105.435944) (xy 82.560147 -105.395795) (xy 82.527696 -105.350437) (xy 82.502195 -105.300837)
			(xy 82.484188 -105.248053) (xy 82.474058 -105.19321) (xy 82.472021 -105.137476) (xy 36.300179 -105.137476)
			(xy 36.315846 -105.158222) (xy 36.361593 -105.232106) (xy 36.400327 -105.309895) (xy 36.431719 -105.390927)
			(xy 36.4555 -105.474509) (xy 36.471468 -105.559929) (xy 36.479486 -105.646458) (xy 36.479486 -105.733358)
			(xy 36.471468 -105.819887) (xy 36.4555 -105.905307) (xy 36.431719 -105.988889) (xy 36.400327 -106.069921)
			(xy 36.361593 -106.14771) (xy 36.340514 -106.181753) (xy 60.260476 -106.181753) (xy 60.260476 -106.110431)
			(xy 60.268462 -106.039557) (xy 60.284332 -105.970022) (xy 60.307889 -105.902702) (xy 60.338834 -105.838443)
			(xy 60.37678 -105.778052) (xy 60.421249 -105.72229) (xy 60.471682 -105.671857) (xy 60.527444 -105.627388)
			(xy 60.587835 -105.589442) (xy 60.652094 -105.558497) (xy 60.719414 -105.53494) (xy 60.788949 -105.51907)
			(xy 60.859823 -105.511084) (xy 60.895484 -105.510584) (xy 60.931145 -105.511084) (xy 61.002019 -105.51907)
			(xy 61.071554 -105.53494) (xy 61.138874 -105.558497) (xy 61.203133 -105.589442) (xy 61.263524 -105.627388)
			(xy 61.319286 -105.671857) (xy 61.369719 -105.72229) (xy 61.414188 -105.778052) (xy 61.452134 -105.838443)
			(xy 61.483079 -105.902702) (xy 61.506636 -105.970022) (xy 61.522506 -106.039557) (xy 61.530492 -106.110431)
			(xy 61.530492 -106.181753) (xy 61.526399 -106.218075) (xy 62.538348 -106.218075) (xy 62.538348 -106.146753)
			(xy 62.546334 -106.075879) (xy 62.562204 -106.006344) (xy 62.585761 -105.939024) (xy 62.616706 -105.874765)
			(xy 62.654652 -105.814374) (xy 62.699121 -105.758612) (xy 62.749554 -105.708179) (xy 62.805316 -105.66371)
			(xy 62.865707 -105.625764) (xy 62.929966 -105.594819) (xy 62.997286 -105.571262) (xy 63.066821 -105.555392)
			(xy 63.137695 -105.547406) (xy 63.173356 -105.546906) (xy 63.209017 -105.547406) (xy 63.279891 -105.555392)
			(xy 63.349426 -105.571262) (xy 63.416746 -105.594819) (xy 63.481005 -105.625764) (xy 63.541396 -105.66371)
			(xy 63.597158 -105.708179) (xy 63.647591 -105.758612) (xy 63.69206 -105.814374) (xy 63.730006 -105.874765)
			(xy 63.760951 -105.939024) (xy 63.784508 -106.006344) (xy 63.800378 -106.075879) (xy 63.80521 -106.118761)
			(xy 64.78828 -106.118761) (xy 64.78828 -106.047439) (xy 64.796266 -105.976565) (xy 64.812136 -105.90703)
			(xy 64.835693 -105.83971) (xy 64.866638 -105.775451) (xy 64.904584 -105.71506) (xy 64.949053 -105.659298)
			(xy 64.999486 -105.608865) (xy 65.055248 -105.564396) (xy 65.115639 -105.52645) (xy 65.179898 -105.495505)
			(xy 65.247218 -105.471948) (xy 65.316753 -105.456078) (xy 65.387627 -105.448092) (xy 65.423288 -105.447592)
			(xy 65.458949 -105.448092) (xy 65.529823 -105.456078) (xy 65.599358 -105.471948) (xy 65.666678 -105.495505)
			(xy 65.730937 -105.52645) (xy 65.791328 -105.564396) (xy 65.84709 -105.608865) (xy 65.897523 -105.659298)
			(xy 65.941992 -105.71506) (xy 65.979938 -105.775451) (xy 66.010883 -105.83971) (xy 66.03444 -105.90703)
			(xy 66.05031 -105.976565) (xy 66.058296 -106.047439) (xy 66.058296 -106.118761) (xy 66.058267 -106.119015)
			(xy 66.939152 -106.119015) (xy 66.939152 -106.047693) (xy 66.947138 -105.976819) (xy 66.963008 -105.907284)
			(xy 66.986565 -105.839964) (xy 67.01751 -105.775705) (xy 67.055456 -105.715314) (xy 67.099925 -105.659552)
			(xy 67.150358 -105.609119) (xy 67.20612 -105.56465) (xy 67.266511 -105.526704) (xy 67.33077 -105.495759)
			(xy 67.39809 -105.472202) (xy 67.467625 -105.456332) (xy 67.538499 -105.448346) (xy 67.57416 -105.447846)
			(xy 67.609821 -105.448346) (xy 67.680695 -105.456332) (xy 67.75023 -105.472202) (xy 67.81755 -105.495759)
			(xy 67.881809 -105.526704) (xy 67.9422 -105.56465) (xy 67.997962 -105.609119) (xy 68.048395 -105.659552)
			(xy 68.092864 -105.715314) (xy 68.13081 -105.775705) (xy 68.161755 -105.839964) (xy 68.185312 -105.907284)
			(xy 68.201182 -105.976819) (xy 68.209168 -106.047693) (xy 68.209168 -106.119015) (xy 68.205075 -106.155337)
			(xy 69.095866 -106.155337) (xy 69.095866 -106.084015) (xy 69.103852 -106.013141) (xy 69.119722 -105.943606)
			(xy 69.143279 -105.876286) (xy 69.174224 -105.812027) (xy 69.21217 -105.751636) (xy 69.256639 -105.695874)
			(xy 69.307072 -105.645441) (xy 69.362834 -105.600972) (xy 69.423225 -105.563026) (xy 69.487484 -105.532081)
			(xy 69.554804 -105.508524) (xy 69.624339 -105.492654) (xy 69.695213 -105.484668) (xy 69.730874 -105.484168)
			(xy 69.766535 -105.484668) (xy 69.837409 -105.492654) (xy 69.906944 -105.508524) (xy 69.974264 -105.532081)
			(xy 70.038523 -105.563026) (xy 70.098914 -105.600972) (xy 70.154676 -105.645441) (xy 70.205109 -105.695874)
			(xy 70.249578 -105.751636) (xy 70.287524 -105.812027) (xy 70.318469 -105.876286) (xy 70.342026 -105.943606)
			(xy 70.357896 -106.013141) (xy 70.365882 -106.084015) (xy 70.365882 -106.155337) (xy 70.357896 -106.226211)
			(xy 70.355308 -106.23755) (xy 81.739739 -106.23755) (xy 81.745839 -106.182113) (xy 81.759945 -106.128156)
			(xy 81.781757 -106.076827) (xy 81.810811 -106.029221) (xy 81.846486 -105.986353) (xy 81.888023 -105.949136)
			(xy 81.934536 -105.918363) (xy 81.985033 -105.894691) (xy 82.03844 -105.878623) (xy 82.093616 -105.870503)
			(xy 82.121502 -105.869994) (xy 82.149388 -105.870503) (xy 82.204564 -105.878623) (xy 82.257971 -105.894691)
			(xy 82.308468 -105.918363) (xy 82.354981 -105.949136) (xy 82.396518 -105.986353) (xy 82.432193 -106.029221)
			(xy 82.461247 -106.076827) (xy 82.483059 -106.128156) (xy 82.497165 -106.182113) (xy 82.503265 -106.23755)
			(xy 82.501228 -106.293284) (xy 82.491098 -106.348127) (xy 82.473091 -106.400911) (xy 82.44759 -106.450511)
			(xy 82.415139 -106.495869) (xy 82.37643 -106.536018) (xy 82.332287 -106.570104) (xy 82.283652 -106.5974)
			(xy 82.231561 -106.617323) (xy 82.177124 -106.629449) (xy 82.121502 -106.63352) (xy 82.06588 -106.629449)
			(xy 82.011443 -106.617323) (xy 81.959352 -106.5974) (xy 81.910717 -106.570104) (xy 81.866574 -106.536018)
			(xy 81.827865 -106.495869) (xy 81.795414 -106.450511) (xy 81.769913 -106.400911) (xy 81.751906 -106.348127)
			(xy 81.741776 -106.293284) (xy 81.739739 -106.23755) (xy 70.355308 -106.23755) (xy 70.342026 -106.295746)
			(xy 70.318469 -106.363066) (xy 70.287524 -106.427325) (xy 70.249578 -106.487716) (xy 70.205109 -106.543478)
			(xy 70.154676 -106.593911) (xy 70.098914 -106.63838) (xy 70.038523 -106.676326) (xy 69.974264 -106.707271)
			(xy 69.906944 -106.730828) (xy 69.837409 -106.746698) (xy 69.766535 -106.754684) (xy 69.695213 -106.754684)
			(xy 69.624339 -106.746698) (xy 69.554804 -106.730828) (xy 69.487484 -106.707271) (xy 69.423225 -106.676326)
			(xy 69.362834 -106.63838) (xy 69.307072 -106.593911) (xy 69.256639 -106.543478) (xy 69.21217 -106.487716)
			(xy 69.174224 -106.427325) (xy 69.143279 -106.363066) (xy 69.119722 -106.295746) (xy 69.103852 -106.226211)
			(xy 69.095866 -106.155337) (xy 68.205075 -106.155337) (xy 68.201182 -106.189889) (xy 68.185312 -106.259424)
			(xy 68.161755 -106.326744) (xy 68.13081 -106.391003) (xy 68.092864 -106.451394) (xy 68.048395 -106.507156)
			(xy 67.997962 -106.557589) (xy 67.9422 -106.602058) (xy 67.881809 -106.640004) (xy 67.81755 -106.670949)
			(xy 67.75023 -106.694506) (xy 67.680695 -106.710376) (xy 67.609821 -106.718362) (xy 67.538499 -106.718362)
			(xy 67.467625 -106.710376) (xy 67.39809 -106.694506) (xy 67.33077 -106.670949) (xy 67.266511 -106.640004)
			(xy 67.20612 -106.602058) (xy 67.150358 -106.557589) (xy 67.099925 -106.507156) (xy 67.055456 -106.451394)
			(xy 67.01751 -106.391003) (xy 66.986565 -106.326744) (xy 66.963008 -106.259424) (xy 66.947138 -106.189889)
			(xy 66.939152 -106.119015) (xy 66.058267 -106.119015) (xy 66.05031 -106.189635) (xy 66.03444 -106.25917)
			(xy 66.010883 -106.32649) (xy 65.979938 -106.390749) (xy 65.941992 -106.45114) (xy 65.897523 -106.506902)
			(xy 65.84709 -106.557335) (xy 65.791328 -106.601804) (xy 65.730937 -106.63975) (xy 65.666678 -106.670695)
			(xy 65.599358 -106.694252) (xy 65.529823 -106.710122) (xy 65.458949 -106.718108) (xy 65.387627 -106.718108)
			(xy 65.316753 -106.710122) (xy 65.247218 -106.694252) (xy 65.179898 -106.670695) (xy 65.115639 -106.63975)
			(xy 65.055248 -106.601804) (xy 64.999486 -106.557335) (xy 64.949053 -106.506902) (xy 64.904584 -106.45114)
			(xy 64.866638 -106.390749) (xy 64.835693 -106.32649) (xy 64.812136 -106.25917) (xy 64.796266 -106.189635)
			(xy 64.78828 -106.118761) (xy 63.80521 -106.118761) (xy 63.808364 -106.146753) (xy 63.808364 -106.218075)
			(xy 63.800378 -106.288949) (xy 63.784508 -106.358484) (xy 63.760951 -106.425804) (xy 63.730006 -106.490063)
			(xy 63.69206 -106.550454) (xy 63.647591 -106.606216) (xy 63.597158 -106.656649) (xy 63.541396 -106.701118)
			(xy 63.481005 -106.739064) (xy 63.416746 -106.770009) (xy 63.349426 -106.793566) (xy 63.279891 -106.809436)
			(xy 63.209017 -106.817422) (xy 63.137695 -106.817422) (xy 63.066821 -106.809436) (xy 62.997286 -106.793566)
			(xy 62.929966 -106.770009) (xy 62.865707 -106.739064) (xy 62.805316 -106.701118) (xy 62.749554 -106.656649)
			(xy 62.699121 -106.606216) (xy 62.654652 -106.550454) (xy 62.616706 -106.490063) (xy 62.585761 -106.425804)
			(xy 62.562204 -106.358484) (xy 62.546334 -106.288949) (xy 62.538348 -106.218075) (xy 61.526399 -106.218075)
			(xy 61.522506 -106.252627) (xy 61.506636 -106.322162) (xy 61.483079 -106.389482) (xy 61.452134 -106.453741)
			(xy 61.414188 -106.514132) (xy 61.369719 -106.569894) (xy 61.319286 -106.620327) (xy 61.263524 -106.664796)
			(xy 61.203133 -106.702742) (xy 61.138874 -106.733687) (xy 61.071554 -106.757244) (xy 61.002019 -106.773114)
			(xy 60.931145 -106.7811) (xy 60.859823 -106.7811) (xy 60.788949 -106.773114) (xy 60.719414 -106.757244)
			(xy 60.652094 -106.733687) (xy 60.587835 -106.702742) (xy 60.527444 -106.664796) (xy 60.471682 -106.620327)
			(xy 60.421249 -106.569894) (xy 60.37678 -106.514132) (xy 60.338834 -106.453741) (xy 60.307889 -106.389482)
			(xy 60.284332 -106.322162) (xy 60.268462 -106.252627) (xy 60.260476 -106.181753) (xy 36.340514 -106.181753)
			(xy 36.315846 -106.221594) (xy 36.263477 -106.290941) (xy 36.204933 -106.355161) (xy 36.140713 -106.413705)
			(xy 36.071366 -106.466074) (xy 35.997482 -106.511821) (xy 35.919693 -106.550555) (xy 35.838661 -106.581947)
			(xy 35.755079 -106.605728) (xy 35.669659 -106.621696) (xy 35.58313 -106.629714) (xy 35.49623 -106.629714)
			(xy 35.409701 -106.621696) (xy 35.324281 -106.605728) (xy 35.240699 -106.581947) (xy 35.159667 -106.550555)
			(xy 35.081878 -106.511821) (xy 35.007994 -106.466074) (xy 34.938647 -106.413705) (xy 34.874427 -106.355161)
			(xy 34.815883 -106.290941) (xy 34.763514 -106.221594) (xy 34.717767 -106.14771) (xy 34.679033 -106.069921)
			(xy 34.647641 -105.988889) (xy 34.62386 -105.905307) (xy 34.607892 -105.819887) (xy 34.599874 -105.733358)
			(xy 31.398561 -105.733358) (xy 31.397304 -105.767846) (xy 31.386016 -105.854574) (xy 31.366723 -105.93988)
			(xy 31.339592 -106.023026) (xy 31.304858 -106.103293) (xy 31.26282 -106.179988) (xy 31.213842 -106.252448)
			(xy 31.158348 -106.320048) (xy 31.096816 -106.382202) (xy 31.029778 -106.438373) (xy 30.957815 -106.488077)
			(xy 30.881546 -106.530884) (xy 30.801633 -106.566424) (xy 30.718764 -106.59439) (xy 30.633657 -106.61454)
			(xy 30.547046 -106.6267) (xy 30.45968 -106.630765) (xy 30.372314 -106.6267) (xy 30.285703 -106.61454)
			(xy 30.200596 -106.59439) (xy 30.117727 -106.566424) (xy 30.037814 -106.530884) (xy 29.961545 -106.488077)
			(xy 29.889582 -106.438373) (xy 29.822544 -106.382202) (xy 29.761012 -106.320048) (xy 29.705518 -106.252448)
			(xy 29.65654 -106.179988) (xy 29.614502 -106.103293) (xy 29.579768 -106.023026) (xy 29.552637 -105.93988)
			(xy 29.533344 -105.854574) (xy 29.522056 -105.767846) (xy 29.51887 -105.680443) (xy 29.523814 -105.593123)
			(xy 29.536845 -105.506639) (xy 29.55785 -105.421738) (xy 29.586648 -105.339155) (xy 29.62299 -105.259603)
			(xy 29.666562 -105.183769) (xy 29.716987 -105.112309) (xy 29.773831 -105.04584) (xy 29.804868 -105.01503)
			(xy 29.821098 -104.998497) (xy 29.847909 -104.960722) (xy 29.86743 -104.918714) (xy 29.879014 -104.873863)
			(xy 29.882278 -104.827655) (xy 29.877113 -104.781621) (xy 29.863691 -104.737286) (xy 29.842456 -104.696117)
			(xy 29.814111 -104.659479) (xy 29.779595 -104.628585) (xy 29.740052 -104.604457) (xy 29.696791 -104.587896)
			(xy 29.651245 -104.57945) (xy 29.628084 -104.578912) (xy 26.911554 -104.578912) (xy 24.339804 -107.150662)
			(xy 24.330914 -107.182158) (xy 24.323035 -107.207743) (xy 24.301199 -107.256619) (xy 24.272747 -107.301964)
			(xy 24.238237 -107.342887) (xy 24.198347 -107.378586) (xy 24.153859 -107.40836) (xy 24.105647 -107.431624)
			(xy 24.054656 -107.447923) (xy 24.001889 -107.456935) (xy 23.948379 -107.458485) (xy 23.895178 -107.452541)
			(xy 23.869142 -107.446318) (xy 23.846605 -107.440992) (xy 23.800407 -107.437815) (xy 23.754397 -107.443053)
			(xy 23.710096 -107.456534) (xy 23.668967 -107.477811) (xy 23.632368 -107.506182) (xy 23.601511 -107.54071)
			(xy 23.577413 -107.580253) (xy 23.560872 -107.623505) (xy 23.552434 -107.669037) (xy 23.551896 -107.69219)
			(xy 23.551896 -108.081826) (xy 27.690064 -108.081826) (xy 27.690064 -106.569764) (xy 27.690565 -106.537819)
			(xy 27.698573 -106.474433) (xy 27.714462 -106.41255) (xy 27.737981 -106.353146) (xy 27.768761 -106.297159)
			(xy 27.806314 -106.24547) (xy 27.85005 -106.198896) (xy 27.899278 -106.158171) (xy 27.953223 -106.123937)
			(xy 28.011032 -106.096734) (xy 28.071795 -106.076991) (xy 28.134554 -106.065019) (xy 28.198318 -106.061008)
			(xy 28.262082 -106.065019) (xy 28.324841 -106.076991) (xy 28.385604 -106.096734) (xy 28.443413 -106.123937)
			(xy 28.497358 -106.158171) (xy 28.546586 -106.198896) (xy 28.590322 -106.24547) (xy 28.627875 -106.297159)
			(xy 28.658655 -106.353146) (xy 28.682174 -106.41255) (xy 28.698063 -106.474433) (xy 28.706071 -106.537819)
			(xy 28.706572 -106.569764) (xy 28.706572 -107.160483) (xy 50.873904 -107.160483) (xy 50.873904 -107.079373)
			(xy 50.881854 -106.998654) (xy 50.897677 -106.919103) (xy 50.921222 -106.841487) (xy 50.952261 -106.766551)
			(xy 50.990496 -106.695019) (xy 51.035558 -106.627579) (xy 51.087013 -106.56488) (xy 51.144366 -106.507527)
			(xy 51.207065 -106.456072) (xy 51.274505 -106.41101) (xy 51.346037 -106.372775) (xy 51.420973 -106.341736)
			(xy 51.498589 -106.318191) (xy 51.57814 -106.302368) (xy 51.658859 -106.294418) (xy 51.699414 -106.29392)
			(xy 51.739969 -106.294418) (xy 51.820688 -106.302368) (xy 51.900239 -106.318191) (xy 51.977855 -106.341736)
			(xy 52.052791 -106.372775) (xy 52.124323 -106.41101) (xy 52.191763 -106.456072) (xy 52.254462 -106.507527)
			(xy 52.311815 -106.56488) (xy 52.36327 -106.627579) (xy 52.408332 -106.695019) (xy 52.446567 -106.766551)
			(xy 52.477606 -106.841487) (xy 52.501151 -106.919103) (xy 52.516974 -106.998654) (xy 52.524924 -107.079373)
			(xy 52.524924 -107.160483) (xy 52.516974 -107.241202) (xy 52.501151 -107.320753) (xy 52.477606 -107.398369)
			(xy 52.446567 -107.473305) (xy 52.44021 -107.485198) (xy 81.147157 -107.485198) (xy 81.153257 -107.429761)
			(xy 81.167363 -107.375804) (xy 81.189175 -107.324475) (xy 81.218229 -107.276869) (xy 81.253904 -107.234001)
			(xy 81.295441 -107.196784) (xy 81.341954 -107.166011) (xy 81.392451 -107.142339) (xy 81.445858 -107.126271)
			(xy 81.501034 -107.118151) (xy 81.52892 -107.117642) (xy 81.556806 -107.118151) (xy 81.611982 -107.126271)
			(xy 81.665389 -107.142339) (xy 81.715886 -107.166011) (xy 81.762399 -107.196784) (xy 81.803936 -107.234001)
			(xy 81.839611 -107.276869) (xy 81.868665 -107.324475) (xy 81.890477 -107.375804) (xy 81.904583 -107.429761)
			(xy 81.910683 -107.485198) (xy 81.908646 -107.540932) (xy 81.898516 -107.595775) (xy 81.880509 -107.648559)
			(xy 81.855008 -107.698159) (xy 81.822557 -107.743517) (xy 81.783848 -107.783666) (xy 81.739705 -107.817752)
			(xy 81.69107 -107.845048) (xy 81.638979 -107.864971) (xy 81.584542 -107.877097) (xy 81.52892 -107.881168)
			(xy 81.473298 -107.877097) (xy 81.418861 -107.864971) (xy 81.36677 -107.845048) (xy 81.318135 -107.817752)
			(xy 81.273992 -107.783666) (xy 81.235283 -107.743517) (xy 81.202832 -107.698159) (xy 81.177331 -107.648559)
			(xy 81.159324 -107.595775) (xy 81.149194 -107.540932) (xy 81.147157 -107.485198) (xy 52.44021 -107.485198)
			(xy 52.408332 -107.544837) (xy 52.36327 -107.612277) (xy 52.311815 -107.674976) (xy 52.254462 -107.732329)
			(xy 52.191763 -107.783784) (xy 52.124323 -107.828846) (xy 52.052791 -107.867081) (xy 51.977855 -107.89812)
			(xy 51.900239 -107.921665) (xy 51.820688 -107.937488) (xy 51.739969 -107.945438) (xy 51.658859 -107.945438)
			(xy 51.57814 -107.937488) (xy 51.498589 -107.921665) (xy 51.420973 -107.89812) (xy 51.346037 -107.867081)
			(xy 51.274505 -107.828846) (xy 51.207065 -107.783784) (xy 51.144366 -107.732329) (xy 51.087013 -107.674976)
			(xy 51.035558 -107.612277) (xy 50.990496 -107.544837) (xy 50.952261 -107.473305) (xy 50.921222 -107.398369)
			(xy 50.897677 -107.320753) (xy 50.881854 -107.241202) (xy 50.873904 -107.160483) (xy 28.706572 -107.160483)
			(xy 28.706572 -107.660694) (xy 29.130752 -108.084874) (xy 29.14672 -108.10005) (xy 29.182804 -108.125308)
			(xy 29.222702 -108.143968) (xy 29.265219 -108.155471) (xy 29.309082 -108.159474) (xy 29.352979 -108.155857)
			(xy 29.395595 -108.144727) (xy 29.435655 -108.126418) (xy 29.47196 -108.101478) (xy 29.503422 -108.070654)
			(xy 29.529101 -108.034868) (xy 29.548227 -107.995192) (xy 29.554678 -107.97413) (xy 29.566981 -107.932502)
			(xy 29.598211 -107.851504) (xy 29.636773 -107.773729) (xy 29.68234 -107.699839) (xy 29.734523 -107.630463)
			(xy 29.792878 -107.566193) (xy 29.856908 -107.507574) (xy 29.926068 -107.455107) (xy 29.99977 -107.409237)
			(xy 30.077386 -107.370355) (xy 30.158255 -107.338792) (xy 30.241689 -107.314817) (xy 30.326978 -107.298635)
			(xy 30.413395 -107.290382) (xy 30.500204 -107.290128) (xy 30.586668 -107.297877) (xy 30.672049 -107.313563)
			(xy 30.755622 -107.33705) (xy 30.836674 -107.368141) (xy 30.914515 -107.406569) (xy 30.988483 -107.452009)
			(xy 31.057948 -107.504072) (xy 31.122319 -107.562316) (xy 31.181048 -107.626246) (xy 31.233634 -107.695316)
			(xy 31.279631 -107.768938) (xy 31.318646 -107.846487) (xy 31.350348 -107.927302) (xy 31.374466 -108.010695)
			(xy 31.390796 -108.095955) (xy 31.399198 -108.182358) (xy 31.3996 -108.269167) (xy 31.392 -108.355644)
			(xy 31.376462 -108.441052) (xy 31.353118 -108.524665) (xy 31.322167 -108.60577) (xy 31.303468 -108.644944)
			(xy 31.293567 -108.666196) (xy 31.28091 -108.711334) (xy 31.276745 -108.758027) (xy 31.281214 -108.804692)
			(xy 31.294163 -108.849747) (xy 31.315155 -108.891663) (xy 31.343478 -108.929019) (xy 31.37817 -108.960547)
			(xy 31.418056 -108.985179) (xy 31.461783 -109.00208) (xy 31.507867 -109.010675) (xy 31.531306 -109.011212)
			(xy 34.468054 -109.011212) (xy 34.491492 -109.010698) (xy 34.537571 -109.002093) (xy 34.581292 -108.985186)
			(xy 34.621172 -108.96055) (xy 34.655859 -108.929019) (xy 34.684177 -108.891663) (xy 34.705166 -108.849749)
			(xy 34.718114 -108.804696) (xy 34.722582 -108.758034) (xy 34.71842 -108.711343) (xy 34.705767 -108.666207)
			(xy 34.695892 -108.644944) (xy 34.677206 -108.605828) (xy 34.646265 -108.524843) (xy 34.62291 -108.441355)
			(xy 34.607339 -108.35607) (xy 34.599684 -108.269715) (xy 34.60001 -108.183021) (xy 34.608315 -108.096726)
			(xy 34.624529 -108.011561) (xy 34.648512 -107.928251) (xy 34.680062 -107.847501) (xy 34.718911 -107.769999)
			(xy 34.76473 -107.696401) (xy 34.817128 -107.627334) (xy 34.875661 -107.563383) (xy 34.939832 -107.505091)
			(xy 35.009096 -107.452954) (xy 35.082866 -107.407413) (xy 35.160514 -107.368856) (xy 35.241381 -107.33761)
			(xy 35.324782 -107.313941) (xy 35.410007 -107.298048) (xy 35.496333 -107.290068) (xy 35.583027 -107.290068)
			(xy 35.669353 -107.298048) (xy 35.754578 -107.313941) (xy 35.837979 -107.33761) (xy 35.918846 -107.368856)
			(xy 35.996494 -107.407413) (xy 36.070264 -107.452954) (xy 36.139528 -107.505091) (xy 36.203699 -107.563383)
			(xy 36.262232 -107.627334) (xy 36.31463 -107.696401) (xy 36.360449 -107.769999) (xy 36.399298 -107.847501)
			(xy 36.430848 -107.928251) (xy 36.454831 -108.011561) (xy 36.471045 -108.096726) (xy 36.47935 -108.183021)
			(xy 36.479676 -108.269715) (xy 36.472021 -108.35607) (xy 36.45645 -108.441355) (xy 36.433095 -108.524843)
			(xy 36.402154 -108.605828) (xy 36.383468 -108.644944) (xy 36.373567 -108.666196) (xy 36.36091 -108.711334)
			(xy 36.356745 -108.758027) (xy 36.361214 -108.804692) (xy 36.374163 -108.849747) (xy 36.395155 -108.891663)
			(xy 36.423478 -108.929019) (xy 36.45817 -108.960547) (xy 36.498056 -108.985179) (xy 36.541783 -109.00208)
			(xy 36.587867 -109.010675) (xy 36.611306 -109.011212) (xy 37.41674 -109.011212) (xy 38.018212 -108.40974)
			(xy 56.473598 -108.40974) (xy 57.0214 -108.957542) (xy 86.877655 -108.957542) (xy 86.879665 -108.766859)
			(xy 86.889712 -108.57643) (xy 86.907778 -108.386594) (xy 86.933831 -108.197688) (xy 86.967824 -108.010049)
			(xy 87.009697 -107.824009) (xy 87.059376 -107.6399) (xy 87.116772 -107.458049) (xy 87.181783 -107.278779)
			(xy 87.254294 -107.102409) (xy 87.334175 -106.929253) (xy 87.421285 -106.759618) (xy 87.515469 -106.593806)
			(xy 87.61656 -106.432112) (xy 87.724376 -106.274824) (xy 87.838728 -106.122221) (xy 87.959411 -105.974573)
			(xy 88.086212 -105.832145) (xy 88.218903 -105.695189) (xy 88.357251 -105.563948) (xy 88.501008 -105.438656)
			(xy 88.649919 -105.319536) (xy 88.80372 -105.2068) (xy 88.962136 -105.100647) (xy 89.124887 -105.001267)
			(xy 89.291682 -104.908837) (xy 89.462226 -104.82352) (xy 89.636214 -104.745468) (xy 89.813339 -104.674821)
			(xy 89.993284 -104.611703) (xy 90.17573 -104.556227) (xy 90.360353 -104.508492) (xy 90.546823 -104.468582)
			(xy 90.734811 -104.436569) (xy 90.923981 -104.412509) (xy 91.113997 -104.396446) (xy 91.304521 -104.388407)
			(xy 91.399868 -104.387904) (xy 91.495215 -104.388407) (xy 91.685739 -104.396446) (xy 91.875755 -104.412509)
			(xy 92.064925 -104.436569) (xy 92.252913 -104.468582) (xy 92.439383 -104.508492) (xy 92.624006 -104.556227)
			(xy 92.806452 -104.611703) (xy 92.986397 -104.674821) (xy 93.163522 -104.745468) (xy 93.33751 -104.82352)
			(xy 93.508054 -104.908837) (xy 93.674849 -105.001267) (xy 93.8376 -105.100647) (xy 93.996016 -105.2068)
			(xy 94.149817 -105.319536) (xy 94.298728 -105.438656) (xy 94.442485 -105.563948) (xy 94.580833 -105.695189)
			(xy 94.713524 -105.832145) (xy 94.840325 -105.974573) (xy 94.961008 -106.122221) (xy 95.07536 -106.274824)
			(xy 95.183176 -106.432112) (xy 95.284267 -106.593806) (xy 95.378451 -106.759618) (xy 95.465561 -106.929253)
			(xy 95.545442 -107.102409) (xy 95.617953 -107.278779) (xy 95.682964 -107.458049) (xy 95.74036 -107.6399)
			(xy 95.790039 -107.824009) (xy 95.831912 -108.010049) (xy 95.865905 -108.197688) (xy 95.891958 -108.386594)
			(xy 95.910024 -108.57643) (xy 95.920071 -108.766859) (xy 95.922081 -108.957542) (xy 95.916051 -109.148141)
			(xy 95.901992 -109.338315) (xy 95.879927 -109.527728) (xy 95.849898 -109.716043) (xy 95.811956 -109.902924)
			(xy 95.76617 -110.08804) (xy 95.712621 -110.27106) (xy 95.651403 -110.451661) (xy 95.582627 -110.62952)
			(xy 95.506414 -110.804322) (xy 95.4229 -110.975756) (xy 95.332233 -111.143516) (xy 95.234574 -111.307305)
			(xy 95.130097 -111.466832) (xy 95.018988 -111.621813) (xy 94.901445 -111.771971) (xy 94.777675 -111.917041)
			(xy 94.6479 -112.056765) (xy 94.512351 -112.190893) (xy 94.371267 -112.319187) (xy 94.2249 -112.441421)
			(xy 94.073511 -112.557375) (xy 93.917368 -112.666844) (xy 93.756749 -112.769633) (xy 93.591939 -112.865559)
			(xy 93.423232 -112.954453) (xy 93.250927 -113.036155) (xy 93.075332 -113.110521) (xy 92.896757 -113.177419)
			(xy 92.715521 -113.236729) (xy 92.531946 -113.288346) (xy 92.346358 -113.332178) (xy 92.159088 -113.368147)
			(xy 91.970467 -113.39619) (xy 91.780832 -113.416256) (xy 91.590519 -113.42831) (xy 91.399868 -113.432331)
			(xy 91.209217 -113.42831) (xy 91.018904 -113.416256) (xy 90.829269 -113.39619) (xy 90.640648 -113.368147)
			(xy 90.453378 -113.332178) (xy 90.26779 -113.288346) (xy 90.084215 -113.236729) (xy 89.902979 -113.177419)
			(xy 89.724404 -113.110521) (xy 89.548809 -113.036155) (xy 89.376504 -112.954453) (xy 89.207797 -112.865559)
			(xy 89.042987 -112.769633) (xy 88.882368 -112.666844) (xy 88.726225 -112.557375) (xy 88.574836 -112.441421)
			(xy 88.428469 -112.319187) (xy 88.287385 -112.190893) (xy 88.151836 -112.056765) (xy 88.022061 -111.917041)
			(xy 87.898291 -111.771971) (xy 87.780748 -111.621813) (xy 87.669639 -111.466832) (xy 87.565162 -111.307305)
			(xy 87.467503 -111.143516) (xy 87.376836 -110.975756) (xy 87.293322 -110.804322) (xy 87.217109 -110.62952)
			(xy 87.148333 -110.451661) (xy 87.087115 -110.27106) (xy 87.033566 -110.08804) (xy 86.98778 -109.902924)
			(xy 86.949838 -109.716043) (xy 86.919809 -109.527728) (xy 86.897744 -109.338315) (xy 86.883685 -109.148141)
			(xy 86.877655 -108.957542) (xy 57.0214 -108.957542) (xy 65.98285 -117.918992) (xy 66.483484 -117.918992)
			(xy 67.133978 -117.268498) (xy 67.156922 -117.246263) (xy 67.207408 -117.207102) (xy 67.262404 -117.174577)
			(xy 67.321043 -117.149202) (xy 67.3824 -117.131376) (xy 67.445507 -117.121381) (xy 67.509369 -117.119374)
			(xy 67.57298 -117.125387) (xy 67.635334 -117.139325) (xy 67.695451 -117.160968) (xy 67.752381 -117.189975)
			(xy 67.805226 -117.225889) (xy 67.853153 -117.268143) (xy 67.895407 -117.31607) (xy 67.931321 -117.368915)
			(xy 67.960328 -117.425845) (xy 67.981971 -117.485962) (xy 67.995909 -117.548316) (xy 68.001922 -117.611927)
			(xy 67.999915 -117.675789) (xy 67.98992 -117.738896) (xy 67.972094 -117.800253) (xy 67.946719 -117.858892)
			(xy 67.914194 -117.913888) (xy 67.875033 -117.964374) (xy 67.852798 -117.987318) (xy 66.960496 -118.87962)
			(xy 66.949114 -118.891806) (xy 66.932508 -118.920707) (xy 66.923937 -118.952919) (xy 66.923986 -118.986251)
			(xy 66.93265 -119.018438) (xy 66.949342 -119.04729) (xy 66.96075 -119.059452) (xy 67.856608 -119.95531)
			(xy 67.878843 -119.978254) (xy 67.918004 -120.02874) (xy 67.950529 -120.083736) (xy 67.975904 -120.142375)
			(xy 67.99373 -120.203732) (xy 68.003725 -120.266839) (xy 68.005732 -120.330701) (xy 67.999719 -120.394312)
			(xy 67.985781 -120.456666) (xy 67.964138 -120.516783) (xy 67.935131 -120.573713) (xy 67.899217 -120.626558)
			(xy 67.856963 -120.674485) (xy 67.809036 -120.716739) (xy 67.756191 -120.752653) (xy 67.699261 -120.78166)
			(xy 67.639144 -120.803303) (xy 67.57679 -120.817241) (xy 67.513179 -120.823254) (xy 67.449317 -120.821247)
			(xy 67.38621 -120.811252) (xy 67.324853 -120.793426) (xy 67.266214 -120.768051) (xy 67.211218 -120.735526)
			(xy 67.160732 -120.696365) (xy 67.137788 -120.67413) (xy 66.431922 -119.968264) (xy 65.100708 -119.968264)
			(xy 55.614824 -110.48238) (xy 41.65981 -110.48238) (xy 41.636766 -110.482875) (xy 41.591425 -110.491133)
			(xy 41.548318 -110.507434) (xy 41.508858 -110.531244) (xy 41.47434 -110.561781) (xy 41.445897 -110.598044)
			(xy 41.424461 -110.638843) (xy 41.410737 -110.682838) (xy 41.405174 -110.728588) (xy 41.406064 -110.75162)
			(xy 41.407196 -110.778645) (xy 41.402742 -110.83255) (xy 41.390717 -110.885285) (xy 41.371362 -110.935792)
			(xy 41.345067 -110.983059) (xy 41.312357 -111.026136) (xy 41.27389 -111.064161) (xy 41.230437 -111.09637)
			(xy 41.182869 -111.122117) (xy 41.132142 -111.140885) (xy 41.079271 -111.152299) (xy 41.025318 -111.15613)
			(xy 40.971365 -111.152299) (xy 40.918494 -111.140885) (xy 40.867767 -111.122117) (xy 40.820199 -111.09637)
			(xy 40.776746 -111.064161) (xy 40.738279 -111.026136) (xy 40.705569 -110.983059) (xy 40.679274 -110.935792)
			(xy 40.659919 -110.885285) (xy 40.647894 -110.83255) (xy 40.64344 -110.778645) (xy 40.644572 -110.75162)
			(xy 40.645436 -110.728597) (xy 40.639816 -110.682874) (xy 40.626057 -110.638909) (xy 40.604609 -110.598139)
			(xy 40.576171 -110.561896) (xy 40.541674 -110.531364) (xy 40.502245 -110.507541) (xy 40.459171 -110.491205)
			(xy 40.41386 -110.482889) (xy 40.390826 -110.48238) (xy 40.336978 -110.48238) (xy 40.305735 -110.481831)
			(xy 40.243717 -110.474191) (xy 40.183104 -110.459005) (xy 40.124811 -110.436502) (xy 40.069716 -110.407022)
			(xy 40.018651 -110.371009) (xy 39.972387 -110.329007) (xy 39.931622 -110.281649) (xy 39.896971 -110.22965)
			(xy 39.868957 -110.173796) (xy 39.848003 -110.114928) (xy 39.834424 -110.053935) (xy 39.828426 -109.991737)
			(xy 39.830099 -109.929273) (xy 39.839418 -109.867486) (xy 39.856243 -109.807307) (xy 39.86784 -109.778292)
			(xy 39.876132 -109.757128) (xy 39.885904 -109.71274) (xy 39.887629 -109.667322) (xy 39.881254 -109.62232)
			(xy 39.866981 -109.579169) (xy 39.845265 -109.539242) (xy 39.816797 -109.503811) (xy 39.782484 -109.474005)
			(xy 39.743419 -109.450774) (xy 39.700847 -109.434856) (xy 39.656123 -109.426759) (xy 39.633398 -109.426248)
			(xy 38.439344 -109.426248) (xy 37.837872 -110.02772) (xy 36.629594 -110.02772) (xy 36.606581 -110.028227)
			(xy 36.561311 -110.036535) (xy 36.518278 -110.052859) (xy 36.478888 -110.076667) (xy 36.444429 -110.107179)
			(xy 36.416029 -110.143398) (xy 36.394615 -110.184139) (xy 36.380889 -110.228071) (xy 36.375299 -110.273756)
			(xy 36.378028 -110.319701) (xy 36.388986 -110.364403) (xy 36.397946 -110.385606) (xy 36.415302 -110.42557)
			(xy 36.443401 -110.50805) (xy 36.46375 -110.592775) (xy 36.476174 -110.679019) (xy 36.480566 -110.766043)
			(xy 36.476889 -110.8531) (xy 36.465174 -110.939443) (xy 36.445522 -111.024333) (xy 36.418101 -111.107041)
			(xy 36.383147 -111.186857) (xy 36.340958 -111.263097) (xy 36.291898 -111.335108) (xy 36.236386 -111.402271)
			(xy 36.174899 -111.464011) (xy 36.107965 -111.519798) (xy 36.0493 -111.56012) (xy 40.009063 -111.56012)
			(xy 40.015163 -111.504683) (xy 40.029269 -111.450726) (xy 40.051081 -111.399397) (xy 40.080135 -111.351791)
			(xy 40.11581 -111.308923) (xy 40.157347 -111.271706) (xy 40.20386 -111.240933) (xy 40.254357 -111.217261)
			(xy 40.307764 -111.201193) (xy 40.36294 -111.193073) (xy 40.390826 -111.192564) (xy 40.418712 -111.193073)
			(xy 40.473888 -111.201193) (xy 40.527295 -111.217261) (xy 40.577792 -111.240933) (xy 40.624305 -111.271706)
			(xy 40.665842 -111.308923) (xy 40.701517 -111.351791) (xy 40.730571 -111.399397) (xy 40.752383 -111.450726)
			(xy 40.766489 -111.504683) (xy 40.772589 -111.56012) (xy 40.770552 -111.615854) (xy 40.760422 -111.670697)
			(xy 40.742415 -111.723481) (xy 40.716914 -111.773081) (xy 40.684463 -111.818439) (xy 40.645754 -111.858588)
			(xy 40.601611 -111.892674) (xy 40.552976 -111.91997) (xy 40.500885 -111.939893) (xy 40.446448 -111.952019)
			(xy 40.390826 -111.95609) (xy 40.335204 -111.952019) (xy 40.280767 -111.939893) (xy 40.228676 -111.91997)
			(xy 40.180041 -111.892674) (xy 40.135898 -111.858588) (xy 40.097189 -111.818439) (xy 40.064738 -111.773081)
			(xy 40.039237 -111.723481) (xy 40.02123 -111.670697) (xy 40.0111 -111.615854) (xy 40.009063 -111.56012)
			(xy 36.0493 -111.56012) (xy 36.036156 -111.569154) (xy 35.96009 -111.611655) (xy 35.880418 -111.646937)
			(xy 35.797824 -111.674697) (xy 35.713016 -111.694698) (xy 35.626721 -111.706768) (xy 35.53968 -111.710802)
			(xy 35.452639 -111.706768) (xy 35.366344 -111.694698) (xy 35.281536 -111.674697) (xy 35.198942 -111.646937)
			(xy 35.11927 -111.611655) (xy 35.043204 -111.569154) (xy 34.971395 -111.519798) (xy 34.904461 -111.464011)
			(xy 34.842974 -111.402271) (xy 34.787462 -111.335108) (xy 34.738402 -111.263097) (xy 34.696213 -111.186857)
			(xy 34.661259 -111.107041) (xy 34.633838 -111.024333) (xy 34.614186 -110.939443) (xy 34.602471 -110.8531)
			(xy 34.598794 -110.766043) (xy 34.603186 -110.679019) (xy 34.61561 -110.592775) (xy 34.635959 -110.50805)
			(xy 34.664058 -110.42557) (xy 34.681414 -110.385606) (xy 34.690266 -110.364368) (xy 34.701191 -110.319682)
			(xy 34.703898 -110.273759) (xy 34.698297 -110.228099) (xy 34.684573 -110.184191) (xy 34.663172 -110.14347)
			(xy 34.634794 -110.107264) (xy 34.600364 -110.076754) (xy 34.561006 -110.052938) (xy 34.518006 -110.036592)
			(xy 34.472766 -110.02825) (xy 34.449766 -110.02772) (xy 31.549594 -110.02772) (xy 31.526581 -110.028227)
			(xy 31.481311 -110.036535) (xy 31.438278 -110.052859) (xy 31.398888 -110.076667) (xy 31.364429 -110.107179)
			(xy 31.336029 -110.143398) (xy 31.314615 -110.184139) (xy 31.300889 -110.228071) (xy 31.295299 -110.273756)
			(xy 31.298028 -110.319701) (xy 31.308986 -110.364403) (xy 31.317946 -110.385606) (xy 31.33532 -110.425622)
			(xy 31.363446 -110.508209) (xy 31.383802 -110.593045) (xy 31.396212 -110.679403) (xy 31.400571 -110.766538)
			(xy 31.396841 -110.853703) (xy 31.385053 -110.940148) (xy 31.365309 -111.025129) (xy 31.337779 -111.107916)
			(xy 31.3027 -111.187797) (xy 31.260373 -111.264086) (xy 31.211161 -111.336127) (xy 31.155489 -111.4033)
			(xy 31.093834 -111.465028) (xy 31.026727 -111.520779) (xy 30.954745 -111.570076) (xy 30.878506 -111.612494)
			(xy 30.798667 -111.647668) (xy 30.715912 -111.675296) (xy 30.630954 -111.69514) (xy 30.544524 -111.707031)
			(xy 30.457364 -111.710865) (xy 30.370223 -111.706609) (xy 30.283851 -111.694301) (xy 30.19899 -111.674045)
			(xy 30.116371 -111.646017) (xy 30.036702 -111.610457) (xy 29.960669 -111.567671) (xy 29.888926 -111.518027)
			(xy 29.82209 -111.461951) (xy 29.760735 -111.399926) (xy 29.705388 -111.332484) (xy 29.656526 -111.260206)
			(xy 29.614568 -111.183713) (xy 29.579876 -111.103663) (xy 29.552747 -111.020744) (xy 29.533414 -110.935668)
			(xy 29.522045 -110.849168) (xy 29.518736 -110.761986) (xy 29.523517 -110.674872) (xy 29.536345 -110.588576)
			(xy 29.557111 -110.503839) (xy 29.585636 -110.421389) (xy 29.621676 -110.341936) (xy 29.664919 -110.266163)
			(xy 29.689552 -110.230158) (xy 29.697756 -110.21781) (xy 29.708737 -110.190279) (xy 29.713054 -110.160954)
			(xy 29.710474 -110.131427) (xy 29.701135 -110.103296) (xy 29.685545 -110.078087) (xy 29.675328 -110.067344)
			(xy 27.690064 -108.081826) (xy 23.551896 -108.081826) (xy 23.551896 -108.23448) (xy 25.728186 -110.41077)
			(xy 27.424887 -110.41077) (xy 27.430987 -110.355333) (xy 27.445093 -110.301376) (xy 27.466905 -110.250047)
			(xy 27.495959 -110.202441) (xy 27.531634 -110.159573) (xy 27.573171 -110.122356) (xy 27.619684 -110.091583)
			(xy 27.670181 -110.067911) (xy 27.723588 -110.051843) (xy 27.778764 -110.043723) (xy 27.80665 -110.043214)
			(xy 27.834536 -110.043723) (xy 27.889712 -110.051843) (xy 27.943119 -110.067911) (xy 27.993616 -110.091583)
			(xy 28.040129 -110.122356) (xy 28.081666 -110.159573) (xy 28.117341 -110.202441) (xy 28.146395 -110.250047)
			(xy 28.168207 -110.301376) (xy 28.182313 -110.355333) (xy 28.188413 -110.41077) (xy 28.186376 -110.466504)
			(xy 28.176246 -110.521347) (xy 28.158239 -110.574131) (xy 28.132738 -110.623731) (xy 28.100287 -110.669089)
			(xy 28.061578 -110.709238) (xy 28.017435 -110.743324) (xy 27.9688 -110.77062) (xy 27.916709 -110.790543)
			(xy 27.862272 -110.802669) (xy 27.80665 -110.80674) (xy 27.751028 -110.802669) (xy 27.696591 -110.790543)
			(xy 27.6445 -110.77062) (xy 27.595865 -110.743324) (xy 27.551722 -110.709238) (xy 27.513013 -110.669089)
			(xy 27.480562 -110.623731) (xy 27.455061 -110.574131) (xy 27.437054 -110.521347) (xy 27.426924 -110.466504)
			(xy 27.424887 -110.41077) (xy 25.728186 -110.41077) (xy 28.884372 -113.566956) (xy 28.884372 -121.148956)
			(xy 72.868285 -121.148956) (xy 72.874295 -120.946255) (xy 72.888307 -120.74395) (xy 72.910302 -120.542356)
			(xy 72.940243 -120.341789) (xy 72.978084 -120.142561) (xy 73.023767 -119.944983) (xy 73.07722 -119.749365)
			(xy 73.138359 -119.556011) (xy 73.20709 -119.365223) (xy 73.283304 -119.1773) (xy 73.366883 -118.992534)
			(xy 73.457696 -118.811215) (xy 73.555601 -118.633625) (xy 73.660446 -118.460041) (xy 73.772067 -118.290735)
			(xy 73.890289 -118.12597) (xy 74.014929 -117.966005) (xy 74.14579 -117.811089) (xy 74.28267 -117.661464)
			(xy 74.425354 -117.517364) (xy 74.57362 -117.379012) (xy 74.727236 -117.246627) (xy 74.885961 -117.120413)
			(xy 75.04955 -117.000569) (xy 75.217745 -116.887281) (xy 75.390284 -116.780726) (xy 75.566899 -116.681071)
			(xy 75.747312 -116.588471) (xy 75.931243 -116.503071) (xy 76.118404 -116.425004) (xy 76.308504 -116.354392)
			(xy 76.501244 -116.291346) (xy 76.696325 -116.235963) (xy 76.893442 -116.188331) (xy 77.092286 -116.148523)
			(xy 77.292548 -116.116601) (xy 77.493914 -116.092617) (xy 77.696071 -116.076606) (xy 77.898703 -116.068595)
			(xy 78.000098 -116.068094) (xy 78.101493 -116.068595) (xy 78.304125 -116.076606) (xy 78.506282 -116.092617)
			(xy 78.707648 -116.116601) (xy 78.90791 -116.148523) (xy 79.106754 -116.188331) (xy 79.303871 -116.235963)
			(xy 79.498952 -116.291346) (xy 79.691692 -116.354392) (xy 79.881792 -116.425004) (xy 80.068953 -116.503071)
			(xy 80.252884 -116.588471) (xy 80.433297 -116.681071) (xy 80.609912 -116.780726) (xy 80.782451 -116.887281)
			(xy 80.950646 -117.000569) (xy 81.114235 -117.120413) (xy 81.27296 -117.246627) (xy 81.426576 -117.379012)
			(xy 81.574842 -117.517364) (xy 81.717526 -117.661464) (xy 81.854406 -117.811089) (xy 81.985267 -117.966005)
			(xy 82.109907 -118.12597) (xy 82.228129 -118.290735) (xy 82.33975 -118.460041) (xy 82.444595 -118.633625)
			(xy 82.5425 -118.811215) (xy 82.633313 -118.992534) (xy 82.716892 -119.1773) (xy 82.793106 -119.365223)
			(xy 82.861837 -119.556011) (xy 82.922976 -119.749365) (xy 82.976429 -119.944983) (xy 83.022112 -120.142561)
			(xy 83.059953 -120.341789) (xy 83.089894 -120.542356) (xy 83.111889 -120.74395) (xy 83.125901 -120.946255)
			(xy 83.131911 -121.148956) (xy 83.129907 -121.351736) (xy 83.119894 -121.554279) (xy 83.101887 -121.756268)
			(xy 83.075915 -121.957387) (xy 83.042017 -122.157324) (xy 83.000246 -122.355766) (xy 82.950669 -122.552402)
			(xy 82.893361 -122.746926) (xy 82.828414 -122.939034) (xy 82.755927 -123.128427) (xy 82.676015 -123.314808)
			(xy 82.588803 -123.497886) (xy 82.494425 -123.677376) (xy 82.39303 -123.852997) (xy 82.284776 -124.024476)
			(xy 82.169832 -124.191543) (xy 82.048377 -124.35394) (xy 81.920602 -124.511411) (xy 81.786705 -124.663711)
			(xy 81.646896 -124.810603) (xy 81.501392 -124.951856) (xy 81.350422 -125.087251) (xy 81.194221 -125.216576)
			(xy 81.033032 -125.339629) (xy 80.867108 -125.456218) (xy 80.696708 -125.566161) (xy 80.522097 -125.669286)
			(xy 80.343548 -125.765432) (xy 80.16134 -125.85445) (xy 79.975758 -125.936199) (xy 79.787091 -126.010553)
			(xy 79.595633 -126.077395) (xy 79.401685 -126.136621) (xy 79.205548 -126.188139) (xy 79.007529 -126.231868)
			(xy 78.807937 -126.267739) (xy 78.607083 -126.295698) (xy 78.405282 -126.315699) (xy 78.202848 -126.327712)
			(xy 78.000098 -126.331719) (xy 77.797348 -126.327712) (xy 77.594914 -126.315699) (xy 77.393113 -126.295698)
			(xy 77.192259 -126.267739) (xy 76.992667 -126.231868) (xy 76.794648 -126.188139) (xy 76.598511 -126.136621)
			(xy 76.404563 -126.077395) (xy 76.213105 -126.010553) (xy 76.024438 -125.936199) (xy 75.838856 -125.85445)
			(xy 75.656648 -125.765432) (xy 75.478099 -125.669286) (xy 75.303488 -125.566161) (xy 75.133088 -125.456218)
			(xy 74.967164 -125.339629) (xy 74.805975 -125.216576) (xy 74.649774 -125.087251) (xy 74.498804 -124.951856)
			(xy 74.3533 -124.810603) (xy 74.213491 -124.663711) (xy 74.079594 -124.511411) (xy 73.951819 -124.35394)
			(xy 73.830364 -124.191543) (xy 73.71542 -124.024476) (xy 73.607166 -123.852997) (xy 73.505771 -123.677376)
			(xy 73.411393 -123.497886) (xy 73.324181 -123.314808) (xy 73.244269 -123.128427) (xy 73.171782 -122.939034)
			(xy 73.106835 -122.746926) (xy 73.049527 -122.552402) (xy 72.99995 -122.355766) (xy 72.958179 -122.157324)
			(xy 72.924281 -121.957387) (xy 72.898309 -121.756268) (xy 72.880302 -121.554279) (xy 72.870289 -121.351736)
			(xy 72.868285 -121.148956) (xy 28.884372 -121.148956) (xy 28.884372 -128.695873) (xy 51.075072 -128.695873)
			(xy 51.075072 -128.614763) (xy 51.083022 -128.534044) (xy 51.098845 -128.454493) (xy 51.12239 -128.376877)
			(xy 51.153429 -128.301941) (xy 51.191664 -128.230409) (xy 51.236726 -128.162969) (xy 51.288181 -128.10027)
			(xy 51.345534 -128.042917) (xy 51.408233 -127.991462) (xy 51.475673 -127.9464) (xy 51.547205 -127.908165)
			(xy 51.622141 -127.877126) (xy 51.699757 -127.853581) (xy 51.779308 -127.837758) (xy 51.860027 -127.829808)
			(xy 51.900582 -127.82931) (xy 51.941137 -127.829808) (xy 52.021856 -127.837758) (xy 52.101407 -127.853581)
			(xy 52.179023 -127.877126) (xy 52.253959 -127.908165) (xy 52.325491 -127.9464) (xy 52.392931 -127.991462)
			(xy 52.45563 -128.042917) (xy 52.512983 -128.10027) (xy 52.564438 -128.162969) (xy 52.6095 -128.230409)
			(xy 52.647735 -128.301941) (xy 52.678774 -128.376877) (xy 52.702319 -128.454493) (xy 52.718142 -128.534044)
			(xy 52.726092 -128.614763) (xy 52.726092 -128.695873) (xy 52.718142 -128.776592) (xy 52.702319 -128.856143)
			(xy 52.678774 -128.933759) (xy 52.647735 -129.008695) (xy 52.6095 -129.080227) (xy 52.564438 -129.147667)
			(xy 52.512983 -129.210366) (xy 52.45563 -129.267719) (xy 52.392931 -129.319174) (xy 52.325491 -129.364236)
			(xy 52.253959 -129.402471) (xy 52.179023 -129.43351) (xy 52.101407 -129.457055) (xy 52.021856 -129.472878)
			(xy 51.941137 -129.480828) (xy 51.860027 -129.480828) (xy 51.779308 -129.472878) (xy 51.699757 -129.457055)
			(xy 51.622141 -129.43351) (xy 51.547205 -129.402471) (xy 51.475673 -129.364236) (xy 51.408233 -129.319174)
			(xy 51.345534 -129.267719) (xy 51.288181 -129.210366) (xy 51.236726 -129.147667) (xy 51.191664 -129.080227)
			(xy 51.153429 -129.008695) (xy 51.12239 -128.933759) (xy 51.098845 -128.856143) (xy 51.083022 -128.776592)
			(xy 51.075072 -128.695873) (xy 28.884372 -128.695873) (xy 28.884372 -131.250791) (xy 73.677518 -131.250791)
			(xy 73.677518 -131.179469) (xy 73.685504 -131.108595) (xy 73.701374 -131.03906) (xy 73.724931 -130.97174)
			(xy 73.755876 -130.907481) (xy 73.793822 -130.84709) (xy 73.838291 -130.791328) (xy 73.888724 -130.740895)
			(xy 73.944486 -130.696426) (xy 74.004877 -130.65848) (xy 74.069136 -130.627535) (xy 74.136456 -130.603978)
			(xy 74.205991 -130.588108) (xy 74.276865 -130.580122) (xy 74.312526 -130.579622) (xy 74.348187 -130.580122)
			(xy 74.419061 -130.588108) (xy 74.488596 -130.603978) (xy 74.555916 -130.627535) (xy 74.620175 -130.65848)
			(xy 74.680566 -130.696426) (xy 74.736328 -130.740895) (xy 74.786761 -130.791328) (xy 74.83123 -130.84709)
			(xy 74.869176 -130.907481) (xy 74.900121 -130.97174) (xy 74.923678 -131.03906) (xy 74.939548 -131.108595)
			(xy 74.947385 -131.178147) (xy 75.70139 -131.178147) (xy 75.70139 -131.106825) (xy 75.709376 -131.035951)
			(xy 75.725246 -130.966416) (xy 75.748803 -130.899096) (xy 75.779748 -130.834837) (xy 75.817694 -130.774446)
			(xy 75.862163 -130.718684) (xy 75.912596 -130.668251) (xy 75.968358 -130.623782) (xy 76.028749 -130.585836)
			(xy 76.093008 -130.554891) (xy 76.160328 -130.531334) (xy 76.229863 -130.515464) (xy 76.300737 -130.507478)
			(xy 76.336398 -130.506978) (xy 76.372059 -130.507478) (xy 76.442933 -130.515464) (xy 76.512468 -130.531334)
			(xy 76.579788 -130.554891) (xy 76.644047 -130.585836) (xy 76.704438 -130.623782) (xy 76.7602 -130.668251)
			(xy 76.810633 -130.718684) (xy 76.855102 -130.774446) (xy 76.893048 -130.834837) (xy 76.923993 -130.899096)
			(xy 76.94755 -130.966416) (xy 76.96342 -131.035951) (xy 76.971406 -131.106825) (xy 76.971406 -131.178147)
			(xy 76.968258 -131.206087) (xy 77.588356 -131.206087) (xy 77.588356 -131.134765) (xy 77.596342 -131.063891)
			(xy 77.612212 -130.994356) (xy 77.635769 -130.927036) (xy 77.666714 -130.862777) (xy 77.70466 -130.802386)
			(xy 77.749129 -130.746624) (xy 77.799562 -130.696191) (xy 77.855324 -130.651722) (xy 77.915715 -130.613776)
			(xy 77.979974 -130.582831) (xy 78.047294 -130.559274) (xy 78.116829 -130.543404) (xy 78.187703 -130.535418)
			(xy 78.223364 -130.534918) (xy 78.259025 -130.535418) (xy 78.329899 -130.543404) (xy 78.399434 -130.559274)
			(xy 78.466754 -130.582831) (xy 78.531013 -130.613776) (xy 78.591404 -130.651722) (xy 78.647166 -130.696191)
			(xy 78.697599 -130.746624) (xy 78.742068 -130.802386) (xy 78.780014 -130.862777) (xy 78.810959 -130.927036)
			(xy 78.834516 -130.994356) (xy 78.850386 -131.063891) (xy 78.858372 -131.134765) (xy 78.858372 -131.206087)
			(xy 78.850386 -131.276961) (xy 78.85004 -131.278477) (xy 79.829906 -131.278477) (xy 79.829906 -131.207155)
			(xy 79.837892 -131.136281) (xy 79.853762 -131.066746) (xy 79.877319 -130.999426) (xy 79.908264 -130.935167)
			(xy 79.94621 -130.874776) (xy 79.990679 -130.819014) (xy 80.041112 -130.768581) (xy 80.096874 -130.724112)
			(xy 80.157265 -130.686166) (xy 80.221524 -130.655221) (xy 80.288844 -130.631664) (xy 80.358379 -130.615794)
			(xy 80.429253 -130.607808) (xy 80.464914 -130.607308) (xy 80.500575 -130.607808) (xy 80.571449 -130.615794)
			(xy 80.640984 -130.631664) (xy 80.708304 -130.655221) (xy 80.772563 -130.686166) (xy 80.832954 -130.724112)
			(xy 80.888716 -130.768581) (xy 80.939149 -130.819014) (xy 80.983618 -130.874776) (xy 81.021564 -130.935167)
			(xy 81.052509 -130.999426) (xy 81.076066 -131.066746) (xy 81.091936 -131.136281) (xy 81.099922 -131.207155)
			(xy 81.099922 -131.260189) (xy 81.950298 -131.260189) (xy 81.950298 -131.188867) (xy 81.958284 -131.117993)
			(xy 81.974154 -131.048458) (xy 81.997711 -130.981138) (xy 82.028656 -130.916879) (xy 82.066602 -130.856488)
			(xy 82.111071 -130.800726) (xy 82.161504 -130.750293) (xy 82.217266 -130.705824) (xy 82.277657 -130.667878)
			(xy 82.341916 -130.636933) (xy 82.409236 -130.613376) (xy 82.478771 -130.597506) (xy 82.549645 -130.58952)
			(xy 82.585306 -130.58902) (xy 82.620967 -130.58952) (xy 82.691841 -130.597506) (xy 82.761376 -130.613376)
			(xy 82.828696 -130.636933) (xy 82.892955 -130.667878) (xy 82.953346 -130.705824) (xy 83.009108 -130.750293)
			(xy 83.059541 -130.800726) (xy 83.10401 -130.856488) (xy 83.141956 -130.916879) (xy 83.172901 -130.981138)
			(xy 83.196458 -131.048458) (xy 83.212328 -131.117993) (xy 83.220314 -131.188867) (xy 83.220314 -131.260189)
			(xy 83.212328 -131.331063) (xy 83.196458 -131.400598) (xy 83.172901 -131.467918) (xy 83.141956 -131.532177)
			(xy 83.10401 -131.592568) (xy 83.059541 -131.64833) (xy 83.009108 -131.698763) (xy 82.953346 -131.743232)
			(xy 82.892955 -131.781178) (xy 82.828696 -131.812123) (xy 82.761376 -131.83568) (xy 82.691841 -131.85155)
			(xy 82.620967 -131.859536) (xy 82.549645 -131.859536) (xy 82.478771 -131.85155) (xy 82.409236 -131.83568)
			(xy 82.341916 -131.812123) (xy 82.277657 -131.781178) (xy 82.217266 -131.743232) (xy 82.161504 -131.698763)
			(xy 82.111071 -131.64833) (xy 82.066602 -131.592568) (xy 82.028656 -131.532177) (xy 81.997711 -131.467918)
			(xy 81.974154 -131.400598) (xy 81.958284 -131.331063) (xy 81.950298 -131.260189) (xy 81.099922 -131.260189)
			(xy 81.099922 -131.278477) (xy 81.091936 -131.349351) (xy 81.076066 -131.418886) (xy 81.052509 -131.486206)
			(xy 81.021564 -131.550465) (xy 80.983618 -131.610856) (xy 80.939149 -131.666618) (xy 80.888716 -131.717051)
			(xy 80.832954 -131.76152) (xy 80.772563 -131.799466) (xy 80.708304 -131.830411) (xy 80.640984 -131.853968)
			(xy 80.571449 -131.869838) (xy 80.500575 -131.877824) (xy 80.429253 -131.877824) (xy 80.358379 -131.869838)
			(xy 80.288844 -131.853968) (xy 80.221524 -131.830411) (xy 80.157265 -131.799466) (xy 80.096874 -131.76152)
			(xy 80.041112 -131.717051) (xy 79.990679 -131.666618) (xy 79.94621 -131.610856) (xy 79.908264 -131.550465)
			(xy 79.877319 -131.486206) (xy 79.853762 -131.418886) (xy 79.837892 -131.349351) (xy 79.829906 -131.278477)
			(xy 78.85004 -131.278477) (xy 78.834516 -131.346496) (xy 78.810959 -131.413816) (xy 78.780014 -131.478075)
			(xy 78.742068 -131.538466) (xy 78.697599 -131.594228) (xy 78.647166 -131.644661) (xy 78.591404 -131.68913)
			(xy 78.531013 -131.727076) (xy 78.466754 -131.758021) (xy 78.399434 -131.781578) (xy 78.329899 -131.797448)
			(xy 78.259025 -131.805434) (xy 78.187703 -131.805434) (xy 78.116829 -131.797448) (xy 78.047294 -131.781578)
			(xy 77.979974 -131.758021) (xy 77.915715 -131.727076) (xy 77.855324 -131.68913) (xy 77.799562 -131.644661)
			(xy 77.749129 -131.594228) (xy 77.70466 -131.538466) (xy 77.666714 -131.478075) (xy 77.635769 -131.413816)
			(xy 77.612212 -131.346496) (xy 77.596342 -131.276961) (xy 77.588356 -131.206087) (xy 76.968258 -131.206087)
			(xy 76.96342 -131.249021) (xy 76.94755 -131.318556) (xy 76.923993 -131.385876) (xy 76.893048 -131.450135)
			(xy 76.855102 -131.510526) (xy 76.810633 -131.566288) (xy 76.7602 -131.616721) (xy 76.704438 -131.66119)
			(xy 76.644047 -131.699136) (xy 76.579788 -131.730081) (xy 76.512468 -131.753638) (xy 76.442933 -131.769508)
			(xy 76.372059 -131.777494) (xy 76.300737 -131.777494) (xy 76.229863 -131.769508) (xy 76.160328 -131.753638)
			(xy 76.093008 -131.730081) (xy 76.028749 -131.699136) (xy 75.968358 -131.66119) (xy 75.912596 -131.616721)
			(xy 75.862163 -131.566288) (xy 75.817694 -131.510526) (xy 75.779748 -131.450135) (xy 75.748803 -131.385876)
			(xy 75.725246 -131.318556) (xy 75.709376 -131.249021) (xy 75.70139 -131.178147) (xy 74.947385 -131.178147)
			(xy 74.947534 -131.179469) (xy 74.947534 -131.250791) (xy 74.939548 -131.321665) (xy 74.923678 -131.3912)
			(xy 74.900121 -131.45852) (xy 74.869176 -131.522779) (xy 74.83123 -131.58317) (xy 74.786761 -131.638932)
			(xy 74.736328 -131.689365) (xy 74.680566 -131.733834) (xy 74.620175 -131.77178) (xy 74.555916 -131.802725)
			(xy 74.488596 -131.826282) (xy 74.419061 -131.842152) (xy 74.348187 -131.850138) (xy 74.276865 -131.850138)
			(xy 74.205991 -131.842152) (xy 74.136456 -131.826282) (xy 74.069136 -131.802725) (xy 74.004877 -131.77178)
			(xy 73.944486 -131.733834) (xy 73.888724 -131.689365) (xy 73.838291 -131.638932) (xy 73.793822 -131.58317)
			(xy 73.755876 -131.522779) (xy 73.724931 -131.45852) (xy 73.701374 -131.3912) (xy 73.685504 -131.321665)
			(xy 73.677518 -131.250791) (xy 28.884372 -131.250791) (xy 28.884372 -133.213703) (xy 73.677518 -133.213703)
			(xy 73.677518 -133.142381) (xy 73.685504 -133.071507) (xy 73.701374 -133.001972) (xy 73.724931 -132.934652)
			(xy 73.755876 -132.870393) (xy 73.793822 -132.810002) (xy 73.838291 -132.75424) (xy 73.888724 -132.703807)
			(xy 73.944486 -132.659338) (xy 74.004877 -132.621392) (xy 74.069136 -132.590447) (xy 74.136456 -132.56689)
			(xy 74.205991 -132.55102) (xy 74.276865 -132.543034) (xy 74.312526 -132.542534) (xy 74.348187 -132.543034)
			(xy 74.419061 -132.55102) (xy 74.488596 -132.56689) (xy 74.555916 -132.590447) (xy 74.620175 -132.621392)
			(xy 74.680566 -132.659338) (xy 74.736328 -132.703807) (xy 74.786761 -132.75424) (xy 74.83123 -132.810002)
			(xy 74.869176 -132.870393) (xy 74.900121 -132.934652) (xy 74.923678 -133.001972) (xy 74.939548 -133.071507)
			(xy 74.947385 -133.141059) (xy 75.70139 -133.141059) (xy 75.70139 -133.069737) (xy 75.709376 -132.998863)
			(xy 75.725246 -132.929328) (xy 75.748803 -132.862008) (xy 75.779748 -132.797749) (xy 75.817694 -132.737358)
			(xy 75.862163 -132.681596) (xy 75.912596 -132.631163) (xy 75.968358 -132.586694) (xy 76.028749 -132.548748)
			(xy 76.093008 -132.517803) (xy 76.160328 -132.494246) (xy 76.229863 -132.478376) (xy 76.300737 -132.47039)
			(xy 76.336398 -132.46989) (xy 76.372059 -132.47039) (xy 76.442933 -132.478376) (xy 76.512468 -132.494246)
			(xy 76.579788 -132.517803) (xy 76.644047 -132.548748) (xy 76.704438 -132.586694) (xy 76.7602 -132.631163)
			(xy 76.810633 -132.681596) (xy 76.855102 -132.737358) (xy 76.893048 -132.797749) (xy 76.923993 -132.862008)
			(xy 76.94755 -132.929328) (xy 76.96342 -132.998863) (xy 76.971406 -133.069737) (xy 76.971406 -133.141059)
			(xy 76.968258 -133.168999) (xy 77.588356 -133.168999) (xy 77.588356 -133.097677) (xy 77.596342 -133.026803)
			(xy 77.612212 -132.957268) (xy 77.635769 -132.889948) (xy 77.666714 -132.825689) (xy 77.70466 -132.765298)
			(xy 77.749129 -132.709536) (xy 77.799562 -132.659103) (xy 77.855324 -132.614634) (xy 77.915715 -132.576688)
			(xy 77.979974 -132.545743) (xy 78.047294 -132.522186) (xy 78.116829 -132.506316) (xy 78.187703 -132.49833)
			(xy 78.223364 -132.49783) (xy 78.259025 -132.49833) (xy 78.329899 -132.506316) (xy 78.399434 -132.522186)
			(xy 78.466754 -132.545743) (xy 78.531013 -132.576688) (xy 78.591404 -132.614634) (xy 78.647166 -132.659103)
			(xy 78.697599 -132.709536) (xy 78.742068 -132.765298) (xy 78.780014 -132.825689) (xy 78.810959 -132.889948)
			(xy 78.834516 -132.957268) (xy 78.850386 -133.026803) (xy 78.858372 -133.097677) (xy 78.858372 -133.168999)
			(xy 78.850386 -133.239873) (xy 78.85004 -133.241389) (xy 79.829906 -133.241389) (xy 79.829906 -133.170067)
			(xy 79.837892 -133.099193) (xy 79.853762 -133.029658) (xy 79.877319 -132.962338) (xy 79.908264 -132.898079)
			(xy 79.94621 -132.837688) (xy 79.990679 -132.781926) (xy 80.041112 -132.731493) (xy 80.096874 -132.687024)
			(xy 80.157265 -132.649078) (xy 80.221524 -132.618133) (xy 80.288844 -132.594576) (xy 80.358379 -132.578706)
			(xy 80.429253 -132.57072) (xy 80.464914 -132.57022) (xy 80.500575 -132.57072) (xy 80.571449 -132.578706)
			(xy 80.640984 -132.594576) (xy 80.708304 -132.618133) (xy 80.772563 -132.649078) (xy 80.832954 -132.687024)
			(xy 80.888716 -132.731493) (xy 80.939149 -132.781926) (xy 80.983618 -132.837688) (xy 81.021564 -132.898079)
			(xy 81.052509 -132.962338) (xy 81.076066 -133.029658) (xy 81.091936 -133.099193) (xy 81.099922 -133.170067)
			(xy 81.099922 -133.223101) (xy 81.950298 -133.223101) (xy 81.950298 -133.151779) (xy 81.958284 -133.080905)
			(xy 81.974154 -133.01137) (xy 81.997711 -132.94405) (xy 82.028656 -132.879791) (xy 82.066602 -132.8194)
			(xy 82.111071 -132.763638) (xy 82.161504 -132.713205) (xy 82.217266 -132.668736) (xy 82.277657 -132.63079)
			(xy 82.341916 -132.599845) (xy 82.409236 -132.576288) (xy 82.478771 -132.560418) (xy 82.549645 -132.552432)
			(xy 82.585306 -132.551932) (xy 82.620967 -132.552432) (xy 82.691841 -132.560418) (xy 82.761376 -132.576288)
			(xy 82.828696 -132.599845) (xy 82.892955 -132.63079) (xy 82.953346 -132.668736) (xy 83.009108 -132.713205)
			(xy 83.059541 -132.763638) (xy 83.10401 -132.8194) (xy 83.141956 -132.879791) (xy 83.172901 -132.94405)
			(xy 83.196458 -133.01137) (xy 83.212328 -133.080905) (xy 83.220314 -133.151779) (xy 83.220314 -133.223101)
			(xy 83.212328 -133.293975) (xy 83.196458 -133.36351) (xy 83.172901 -133.43083) (xy 83.141956 -133.495089)
			(xy 83.10401 -133.55548) (xy 83.059541 -133.611242) (xy 83.009108 -133.661675) (xy 82.953346 -133.706144)
			(xy 82.892955 -133.74409) (xy 82.828696 -133.775035) (xy 82.761376 -133.798592) (xy 82.691841 -133.814462)
			(xy 82.620967 -133.822448) (xy 82.549645 -133.822448) (xy 82.478771 -133.814462) (xy 82.409236 -133.798592)
			(xy 82.341916 -133.775035) (xy 82.277657 -133.74409) (xy 82.217266 -133.706144) (xy 82.161504 -133.661675)
			(xy 82.111071 -133.611242) (xy 82.066602 -133.55548) (xy 82.028656 -133.495089) (xy 81.997711 -133.43083)
			(xy 81.974154 -133.36351) (xy 81.958284 -133.293975) (xy 81.950298 -133.223101) (xy 81.099922 -133.223101)
			(xy 81.099922 -133.241389) (xy 81.091936 -133.312263) (xy 81.076066 -133.381798) (xy 81.052509 -133.449118)
			(xy 81.021564 -133.513377) (xy 80.983618 -133.573768) (xy 80.939149 -133.62953) (xy 80.888716 -133.679963)
			(xy 80.832954 -133.724432) (xy 80.772563 -133.762378) (xy 80.708304 -133.793323) (xy 80.640984 -133.81688)
			(xy 80.571449 -133.83275) (xy 80.500575 -133.840736) (xy 80.429253 -133.840736) (xy 80.358379 -133.83275)
			(xy 80.288844 -133.81688) (xy 80.221524 -133.793323) (xy 80.157265 -133.762378) (xy 80.096874 -133.724432)
			(xy 80.041112 -133.679963) (xy 79.990679 -133.62953) (xy 79.94621 -133.573768) (xy 79.908264 -133.513377)
			(xy 79.877319 -133.449118) (xy 79.853762 -133.381798) (xy 79.837892 -133.312263) (xy 79.829906 -133.241389)
			(xy 78.85004 -133.241389) (xy 78.834516 -133.309408) (xy 78.810959 -133.376728) (xy 78.780014 -133.440987)
			(xy 78.742068 -133.501378) (xy 78.697599 -133.55714) (xy 78.647166 -133.607573) (xy 78.591404 -133.652042)
			(xy 78.531013 -133.689988) (xy 78.466754 -133.720933) (xy 78.399434 -133.74449) (xy 78.329899 -133.76036)
			(xy 78.259025 -133.768346) (xy 78.187703 -133.768346) (xy 78.116829 -133.76036) (xy 78.047294 -133.74449)
			(xy 77.979974 -133.720933) (xy 77.915715 -133.689988) (xy 77.855324 -133.652042) (xy 77.799562 -133.607573)
			(xy 77.749129 -133.55714) (xy 77.70466 -133.501378) (xy 77.666714 -133.440987) (xy 77.635769 -133.376728)
			(xy 77.612212 -133.309408) (xy 77.596342 -133.239873) (xy 77.588356 -133.168999) (xy 76.968258 -133.168999)
			(xy 76.96342 -133.211933) (xy 76.94755 -133.281468) (xy 76.923993 -133.348788) (xy 76.893048 -133.413047)
			(xy 76.855102 -133.473438) (xy 76.810633 -133.5292) (xy 76.7602 -133.579633) (xy 76.704438 -133.624102)
			(xy 76.644047 -133.662048) (xy 76.579788 -133.692993) (xy 76.512468 -133.71655) (xy 76.442933 -133.73242)
			(xy 76.372059 -133.740406) (xy 76.300737 -133.740406) (xy 76.229863 -133.73242) (xy 76.160328 -133.71655)
			(xy 76.093008 -133.692993) (xy 76.028749 -133.662048) (xy 75.968358 -133.624102) (xy 75.912596 -133.579633)
			(xy 75.862163 -133.5292) (xy 75.817694 -133.473438) (xy 75.779748 -133.413047) (xy 75.748803 -133.348788)
			(xy 75.725246 -133.281468) (xy 75.709376 -133.211933) (xy 75.70139 -133.141059) (xy 74.947385 -133.141059)
			(xy 74.947534 -133.142381) (xy 74.947534 -133.213703) (xy 74.939548 -133.284577) (xy 74.923678 -133.354112)
			(xy 74.900121 -133.421432) (xy 74.869176 -133.485691) (xy 74.83123 -133.546082) (xy 74.786761 -133.601844)
			(xy 74.736328 -133.652277) (xy 74.680566 -133.696746) (xy 74.620175 -133.734692) (xy 74.555916 -133.765637)
			(xy 74.488596 -133.789194) (xy 74.419061 -133.805064) (xy 74.348187 -133.81305) (xy 74.276865 -133.81305)
			(xy 74.205991 -133.805064) (xy 74.136456 -133.789194) (xy 74.069136 -133.765637) (xy 74.004877 -133.734692)
			(xy 73.944486 -133.696746) (xy 73.888724 -133.652277) (xy 73.838291 -133.601844) (xy 73.793822 -133.546082)
			(xy 73.755876 -133.485691) (xy 73.724931 -133.421432) (xy 73.701374 -133.354112) (xy 73.685504 -133.284577)
			(xy 73.677518 -133.213703) (xy 28.884372 -133.213703) (xy 28.884372 -135.357209) (xy 73.677518 -135.357209)
			(xy 73.677518 -135.285887) (xy 73.685504 -135.215013) (xy 73.701374 -135.145478) (xy 73.724931 -135.078158)
			(xy 73.755876 -135.013899) (xy 73.793822 -134.953508) (xy 73.838291 -134.897746) (xy 73.888724 -134.847313)
			(xy 73.944486 -134.802844) (xy 74.004877 -134.764898) (xy 74.069136 -134.733953) (xy 74.136456 -134.710396)
			(xy 74.205991 -134.694526) (xy 74.276865 -134.68654) (xy 74.312526 -134.68604) (xy 74.348187 -134.68654)
			(xy 74.419061 -134.694526) (xy 74.488596 -134.710396) (xy 74.555916 -134.733953) (xy 74.620175 -134.764898)
			(xy 74.680566 -134.802844) (xy 74.736328 -134.847313) (xy 74.786761 -134.897746) (xy 74.83123 -134.953508)
			(xy 74.869176 -135.013899) (xy 74.900121 -135.078158) (xy 74.923678 -135.145478) (xy 74.939548 -135.215013)
			(xy 74.947385 -135.284565) (xy 75.70139 -135.284565) (xy 75.70139 -135.213243) (xy 75.709376 -135.142369)
			(xy 75.725246 -135.072834) (xy 75.748803 -135.005514) (xy 75.779748 -134.941255) (xy 75.817694 -134.880864)
			(xy 75.862163 -134.825102) (xy 75.912596 -134.774669) (xy 75.968358 -134.7302) (xy 76.028749 -134.692254)
			(xy 76.093008 -134.661309) (xy 76.160328 -134.637752) (xy 76.229863 -134.621882) (xy 76.300737 -134.613896)
			(xy 76.336398 -134.613396) (xy 76.372059 -134.613896) (xy 76.442933 -134.621882) (xy 76.512468 -134.637752)
			(xy 76.579788 -134.661309) (xy 76.644047 -134.692254) (xy 76.704438 -134.7302) (xy 76.7602 -134.774669)
			(xy 76.810633 -134.825102) (xy 76.855102 -134.880864) (xy 76.893048 -134.941255) (xy 76.923993 -135.005514)
			(xy 76.94755 -135.072834) (xy 76.96342 -135.142369) (xy 76.971406 -135.213243) (xy 76.971406 -135.284565)
			(xy 76.968258 -135.312505) (xy 77.588356 -135.312505) (xy 77.588356 -135.241183) (xy 77.596342 -135.170309)
			(xy 77.612212 -135.100774) (xy 77.635769 -135.033454) (xy 77.666714 -134.969195) (xy 77.70466 -134.908804)
			(xy 77.749129 -134.853042) (xy 77.799562 -134.802609) (xy 77.855324 -134.75814) (xy 77.915715 -134.720194)
			(xy 77.979974 -134.689249) (xy 78.047294 -134.665692) (xy 78.116829 -134.649822) (xy 78.187703 -134.641836)
			(xy 78.223364 -134.641336) (xy 78.259025 -134.641836) (xy 78.329899 -134.649822) (xy 78.399434 -134.665692)
			(xy 78.466754 -134.689249) (xy 78.531013 -134.720194) (xy 78.591404 -134.75814) (xy 78.647166 -134.802609)
			(xy 78.697599 -134.853042) (xy 78.742068 -134.908804) (xy 78.780014 -134.969195) (xy 78.810959 -135.033454)
			(xy 78.834516 -135.100774) (xy 78.850386 -135.170309) (xy 78.858372 -135.241183) (xy 78.858372 -135.312505)
			(xy 78.850386 -135.383379) (xy 78.85004 -135.384895) (xy 79.829906 -135.384895) (xy 79.829906 -135.313573)
			(xy 79.837892 -135.242699) (xy 79.853762 -135.173164) (xy 79.877319 -135.105844) (xy 79.908264 -135.041585)
			(xy 79.94621 -134.981194) (xy 79.990679 -134.925432) (xy 80.041112 -134.874999) (xy 80.096874 -134.83053)
			(xy 80.157265 -134.792584) (xy 80.221524 -134.761639) (xy 80.288844 -134.738082) (xy 80.358379 -134.722212)
			(xy 80.429253 -134.714226) (xy 80.464914 -134.713726) (xy 80.500575 -134.714226) (xy 80.571449 -134.722212)
			(xy 80.640984 -134.738082) (xy 80.708304 -134.761639) (xy 80.772563 -134.792584) (xy 80.832954 -134.83053)
			(xy 80.888716 -134.874999) (xy 80.939149 -134.925432) (xy 80.983618 -134.981194) (xy 81.021564 -135.041585)
			(xy 81.052509 -135.105844) (xy 81.076066 -135.173164) (xy 81.091936 -135.242699) (xy 81.099922 -135.313573)
			(xy 81.099922 -135.366607) (xy 81.950298 -135.366607) (xy 81.950298 -135.295285) (xy 81.958284 -135.224411)
			(xy 81.974154 -135.154876) (xy 81.997711 -135.087556) (xy 82.028656 -135.023297) (xy 82.066602 -134.962906)
			(xy 82.111071 -134.907144) (xy 82.161504 -134.856711) (xy 82.217266 -134.812242) (xy 82.277657 -134.774296)
			(xy 82.341916 -134.743351) (xy 82.409236 -134.719794) (xy 82.478771 -134.703924) (xy 82.549645 -134.695938)
			(xy 82.585306 -134.695438) (xy 82.620967 -134.695938) (xy 82.691841 -134.703924) (xy 82.761376 -134.719794)
			(xy 82.828696 -134.743351) (xy 82.892955 -134.774296) (xy 82.953346 -134.812242) (xy 83.009108 -134.856711)
			(xy 83.059541 -134.907144) (xy 83.10401 -134.962906) (xy 83.141956 -135.023297) (xy 83.172901 -135.087556)
			(xy 83.196458 -135.154876) (xy 83.212328 -135.224411) (xy 83.220314 -135.295285) (xy 83.220314 -135.366607)
			(xy 83.212328 -135.437481) (xy 83.196458 -135.507016) (xy 83.172901 -135.574336) (xy 83.141956 -135.638595)
			(xy 83.10401 -135.698986) (xy 83.059541 -135.754748) (xy 83.009108 -135.805181) (xy 82.953346 -135.84965)
			(xy 82.892955 -135.887596) (xy 82.828696 -135.918541) (xy 82.761376 -135.942098) (xy 82.691841 -135.957968)
			(xy 82.620967 -135.965954) (xy 82.549645 -135.965954) (xy 82.478771 -135.957968) (xy 82.409236 -135.942098)
			(xy 82.341916 -135.918541) (xy 82.277657 -135.887596) (xy 82.217266 -135.84965) (xy 82.161504 -135.805181)
			(xy 82.111071 -135.754748) (xy 82.066602 -135.698986) (xy 82.028656 -135.638595) (xy 81.997711 -135.574336)
			(xy 81.974154 -135.507016) (xy 81.958284 -135.437481) (xy 81.950298 -135.366607) (xy 81.099922 -135.366607)
			(xy 81.099922 -135.384895) (xy 81.091936 -135.455769) (xy 81.076066 -135.525304) (xy 81.052509 -135.592624)
			(xy 81.021564 -135.656883) (xy 80.983618 -135.717274) (xy 80.939149 -135.773036) (xy 80.888716 -135.823469)
			(xy 80.832954 -135.867938) (xy 80.772563 -135.905884) (xy 80.708304 -135.936829) (xy 80.640984 -135.960386)
			(xy 80.571449 -135.976256) (xy 80.500575 -135.984242) (xy 80.429253 -135.984242) (xy 80.358379 -135.976256)
			(xy 80.288844 -135.960386) (xy 80.221524 -135.936829) (xy 80.157265 -135.905884) (xy 80.096874 -135.867938)
			(xy 80.041112 -135.823469) (xy 79.990679 -135.773036) (xy 79.94621 -135.717274) (xy 79.908264 -135.656883)
			(xy 79.877319 -135.592624) (xy 79.853762 -135.525304) (xy 79.837892 -135.455769) (xy 79.829906 -135.384895)
			(xy 78.85004 -135.384895) (xy 78.834516 -135.452914) (xy 78.810959 -135.520234) (xy 78.780014 -135.584493)
			(xy 78.742068 -135.644884) (xy 78.697599 -135.700646) (xy 78.647166 -135.751079) (xy 78.591404 -135.795548)
			(xy 78.531013 -135.833494) (xy 78.466754 -135.864439) (xy 78.399434 -135.887996) (xy 78.329899 -135.903866)
			(xy 78.259025 -135.911852) (xy 78.187703 -135.911852) (xy 78.116829 -135.903866) (xy 78.047294 -135.887996)
			(xy 77.979974 -135.864439) (xy 77.915715 -135.833494) (xy 77.855324 -135.795548) (xy 77.799562 -135.751079)
			(xy 77.749129 -135.700646) (xy 77.70466 -135.644884) (xy 77.666714 -135.584493) (xy 77.635769 -135.520234)
			(xy 77.612212 -135.452914) (xy 77.596342 -135.383379) (xy 77.588356 -135.312505) (xy 76.968258 -135.312505)
			(xy 76.96342 -135.355439) (xy 76.94755 -135.424974) (xy 76.923993 -135.492294) (xy 76.893048 -135.556553)
			(xy 76.855102 -135.616944) (xy 76.810633 -135.672706) (xy 76.7602 -135.723139) (xy 76.704438 -135.767608)
			(xy 76.644047 -135.805554) (xy 76.579788 -135.836499) (xy 76.512468 -135.860056) (xy 76.442933 -135.875926)
			(xy 76.372059 -135.883912) (xy 76.300737 -135.883912) (xy 76.229863 -135.875926) (xy 76.160328 -135.860056)
			(xy 76.093008 -135.836499) (xy 76.028749 -135.805554) (xy 75.968358 -135.767608) (xy 75.912596 -135.723139)
			(xy 75.862163 -135.672706) (xy 75.817694 -135.616944) (xy 75.779748 -135.556553) (xy 75.748803 -135.492294)
			(xy 75.725246 -135.424974) (xy 75.709376 -135.355439) (xy 75.70139 -135.284565) (xy 74.947385 -135.284565)
			(xy 74.947534 -135.285887) (xy 74.947534 -135.357209) (xy 74.939548 -135.428083) (xy 74.923678 -135.497618)
			(xy 74.900121 -135.564938) (xy 74.869176 -135.629197) (xy 74.83123 -135.689588) (xy 74.786761 -135.74535)
			(xy 74.736328 -135.795783) (xy 74.680566 -135.840252) (xy 74.620175 -135.878198) (xy 74.555916 -135.909143)
			(xy 74.488596 -135.9327) (xy 74.419061 -135.94857) (xy 74.348187 -135.956556) (xy 74.276865 -135.956556)
			(xy 74.205991 -135.94857) (xy 74.136456 -135.9327) (xy 74.069136 -135.909143) (xy 74.004877 -135.878198)
			(xy 73.944486 -135.840252) (xy 73.888724 -135.795783) (xy 73.838291 -135.74535) (xy 73.793822 -135.689588)
			(xy 73.755876 -135.629197) (xy 73.724931 -135.564938) (xy 73.701374 -135.497618) (xy 73.685504 -135.428083)
			(xy 73.677518 -135.357209) (xy 28.884372 -135.357209) (xy 28.884372 -140.231042) (xy 39.818568 -140.231042)
			(xy 39.824577 -140.115104) (xy 39.83857 -139.999857) (xy 39.860481 -139.885851) (xy 39.890206 -139.773627)
			(xy 39.927602 -139.663721) (xy 39.972491 -139.556658) (xy 40.02466 -139.452946) (xy 40.08386 -139.353081)
			(xy 40.149809 -139.257538) (xy 40.222192 -139.166772) (xy 40.300665 -139.081217) (xy 40.384853 -139.001279)
			(xy 40.474355 -138.92734) (xy 40.568746 -138.859752) (xy 40.667574 -138.798838) (xy 40.77037 -138.744886)
			(xy 40.876643 -138.698156) (xy 40.985887 -138.658868) (xy 41.09758 -138.627211) (xy 41.211192 -138.603335)
			(xy 41.32618 -138.587354) (xy 41.441997 -138.579345) (xy 41.500044 -138.578844) (xy 41.558091 -138.579345)
			(xy 41.673908 -138.587354) (xy 41.788896 -138.603335) (xy 41.902508 -138.627211) (xy 42.014201 -138.658868)
			(xy 42.123445 -138.698156) (xy 42.229718 -138.744886) (xy 42.332514 -138.798838) (xy 42.431342 -138.859752)
			(xy 42.475123 -138.891101) (xy 63.648083 -138.891101) (xy 63.654132 -138.815531) (xy 63.668179 -138.741033)
			(xy 63.690065 -138.66845) (xy 63.719542 -138.598604) (xy 63.756277 -138.532287) (xy 63.799852 -138.470251)
			(xy 63.849774 -138.413198) (xy 63.905478 -138.361774) (xy 63.966333 -138.316563) (xy 64.031648 -138.278076)
			(xy 64.100684 -138.24675) (xy 64.172659 -138.22294) (xy 64.246757 -138.206915) (xy 64.322138 -138.198856)
			(xy 64.360044 -138.198352) (xy 64.39795 -138.198856) (xy 64.473331 -138.206915) (xy 64.547429 -138.22294)
			(xy 64.619404 -138.24675) (xy 64.68844 -138.278076) (xy 64.753755 -138.316563) (xy 64.81461 -138.361774)
			(xy 64.870314 -138.413198) (xy 64.920236 -138.470251) (xy 64.963811 -138.532287) (xy 65.000546 -138.598604)
			(xy 65.030023 -138.66845) (xy 65.051909 -138.741033) (xy 65.065956 -138.815531) (xy 65.072005 -138.891101)
			(xy 66.188083 -138.891101) (xy 66.194132 -138.815531) (xy 66.208179 -138.741033) (xy 66.230065 -138.66845)
			(xy 66.259542 -138.598604) (xy 66.296277 -138.532287) (xy 66.339852 -138.470251) (xy 66.389774 -138.413198)
			(xy 66.445478 -138.361774) (xy 66.506333 -138.316563) (xy 66.571648 -138.278076) (xy 66.640684 -138.24675)
			(xy 66.712659 -138.22294) (xy 66.786757 -138.206915) (xy 66.862138 -138.198856) (xy 66.900044 -138.198352)
			(xy 66.93795 -138.198856) (xy 67.013331 -138.206915) (xy 67.087429 -138.22294) (xy 67.159404 -138.24675)
			(xy 67.22844 -138.278076) (xy 67.293755 -138.316563) (xy 67.35461 -138.361774) (xy 67.410314 -138.413198)
			(xy 67.460236 -138.470251) (xy 67.503811 -138.532287) (xy 67.540546 -138.598604) (xy 67.570023 -138.66845)
			(xy 67.591909 -138.741033) (xy 67.605956 -138.815531) (xy 67.612005 -138.891101) (xy 68.728083 -138.891101)
			(xy 68.734132 -138.815531) (xy 68.748179 -138.741033) (xy 68.770065 -138.66845) (xy 68.799542 -138.598604)
			(xy 68.836277 -138.532287) (xy 68.879852 -138.470251) (xy 68.929774 -138.413198) (xy 68.985478 -138.361774)
			(xy 69.046333 -138.316563) (xy 69.111648 -138.278076) (xy 69.180684 -138.24675) (xy 69.252659 -138.22294)
			(xy 69.326757 -138.206915) (xy 69.402138 -138.198856) (xy 69.440044 -138.198352) (xy 69.47795 -138.198856)
			(xy 69.553331 -138.206915) (xy 69.627429 -138.22294) (xy 69.699404 -138.24675) (xy 69.76844 -138.278076)
			(xy 69.833755 -138.316563) (xy 69.89461 -138.361774) (xy 69.950314 -138.413198) (xy 70.000236 -138.470251)
			(xy 70.043811 -138.532287) (xy 70.080546 -138.598604) (xy 70.110023 -138.66845) (xy 70.131909 -138.741033)
			(xy 70.145956 -138.815531) (xy 70.152005 -138.891101) (xy 71.268083 -138.891101) (xy 71.274132 -138.815531)
			(xy 71.288179 -138.741033) (xy 71.310065 -138.66845) (xy 71.339542 -138.598604) (xy 71.376277 -138.532287)
			(xy 71.419852 -138.470251) (xy 71.469774 -138.413198) (xy 71.525478 -138.361774) (xy 71.586333 -138.316563)
			(xy 71.651648 -138.278076) (xy 71.720684 -138.24675) (xy 71.792659 -138.22294) (xy 71.866757 -138.206915)
			(xy 71.942138 -138.198856) (xy 71.980044 -138.198352) (xy 72.01795 -138.198856) (xy 72.093331 -138.206915)
			(xy 72.167429 -138.22294) (xy 72.239404 -138.24675) (xy 72.30844 -138.278076) (xy 72.373755 -138.316563)
			(xy 72.43461 -138.361774) (xy 72.490314 -138.413198) (xy 72.540236 -138.470251) (xy 72.583811 -138.532287)
			(xy 72.620546 -138.598604) (xy 72.650023 -138.66845) (xy 72.671909 -138.741033) (xy 72.685956 -138.815531)
			(xy 72.692005 -138.891101) (xy 73.808083 -138.891101) (xy 73.814132 -138.815531) (xy 73.828179 -138.741033)
			(xy 73.850065 -138.66845) (xy 73.879542 -138.598604) (xy 73.916277 -138.532287) (xy 73.959852 -138.470251)
			(xy 74.009774 -138.413198) (xy 74.065478 -138.361774) (xy 74.126333 -138.316563) (xy 74.191648 -138.278076)
			(xy 74.260684 -138.24675) (xy 74.332659 -138.22294) (xy 74.406757 -138.206915) (xy 74.482138 -138.198856)
			(xy 74.520044 -138.198352) (xy 74.55795 -138.198856) (xy 74.633331 -138.206915) (xy 74.707429 -138.22294)
			(xy 74.779404 -138.24675) (xy 74.84844 -138.278076) (xy 74.913755 -138.316563) (xy 74.97461 -138.361774)
			(xy 75.030314 -138.413198) (xy 75.080236 -138.470251) (xy 75.123811 -138.532287) (xy 75.160546 -138.598604)
			(xy 75.190023 -138.66845) (xy 75.211909 -138.741033) (xy 75.225956 -138.815531) (xy 75.232005 -138.891101)
			(xy 76.348083 -138.891101) (xy 76.354132 -138.815531) (xy 76.368179 -138.741033) (xy 76.390065 -138.66845)
			(xy 76.419542 -138.598604) (xy 76.456277 -138.532287) (xy 76.499852 -138.470251) (xy 76.549774 -138.413198)
			(xy 76.605478 -138.361774) (xy 76.666333 -138.316563) (xy 76.731648 -138.278076) (xy 76.800684 -138.24675)
			(xy 76.872659 -138.22294) (xy 76.946757 -138.206915) (xy 77.022138 -138.198856) (xy 77.060044 -138.198352)
			(xy 77.09795 -138.198856) (xy 77.173331 -138.206915) (xy 77.247429 -138.22294) (xy 77.319404 -138.24675)
			(xy 77.38844 -138.278076) (xy 77.453755 -138.316563) (xy 77.51461 -138.361774) (xy 77.570314 -138.413198)
			(xy 77.620236 -138.470251) (xy 77.663811 -138.532287) (xy 77.700546 -138.598604) (xy 77.730023 -138.66845)
			(xy 77.751909 -138.741033) (xy 77.765956 -138.815531) (xy 77.772005 -138.891101) (xy 78.888083 -138.891101)
			(xy 78.894132 -138.815531) (xy 78.908179 -138.741033) (xy 78.930065 -138.66845) (xy 78.959542 -138.598604)
			(xy 78.996277 -138.532287) (xy 79.039852 -138.470251) (xy 79.089774 -138.413198) (xy 79.145478 -138.361774)
			(xy 79.206333 -138.316563) (xy 79.271648 -138.278076) (xy 79.340684 -138.24675) (xy 79.412659 -138.22294)
			(xy 79.486757 -138.206915) (xy 79.562138 -138.198856) (xy 79.600044 -138.198352) (xy 79.63795 -138.198856)
			(xy 79.713331 -138.206915) (xy 79.787429 -138.22294) (xy 79.859404 -138.24675) (xy 79.92844 -138.278076)
			(xy 79.993755 -138.316563) (xy 80.05461 -138.361774) (xy 80.110314 -138.413198) (xy 80.160236 -138.470251)
			(xy 80.203811 -138.532287) (xy 80.240546 -138.598604) (xy 80.270023 -138.66845) (xy 80.291909 -138.741033)
			(xy 80.305956 -138.815531) (xy 80.312005 -138.891101) (xy 81.428083 -138.891101) (xy 81.434132 -138.815531)
			(xy 81.448179 -138.741033) (xy 81.470065 -138.66845) (xy 81.499542 -138.598604) (xy 81.536277 -138.532287)
			(xy 81.579852 -138.470251) (xy 81.629774 -138.413198) (xy 81.685478 -138.361774) (xy 81.746333 -138.316563)
			(xy 81.811648 -138.278076) (xy 81.880684 -138.24675) (xy 81.952659 -138.22294) (xy 82.026757 -138.206915)
			(xy 82.102138 -138.198856) (xy 82.140044 -138.198352) (xy 82.17795 -138.198856) (xy 82.253331 -138.206915)
			(xy 82.327429 -138.22294) (xy 82.399404 -138.24675) (xy 82.46844 -138.278076) (xy 82.533755 -138.316563)
			(xy 82.59461 -138.361774) (xy 82.650314 -138.413198) (xy 82.700236 -138.470251) (xy 82.743811 -138.532287)
			(xy 82.780546 -138.598604) (xy 82.810023 -138.66845) (xy 82.831909 -138.741033) (xy 82.845956 -138.815531)
			(xy 82.852005 -138.891101) (xy 82.849986 -138.966885) (xy 82.839924 -139.042025) (xy 82.821932 -139.11567)
			(xy 82.796214 -139.186986) (xy 82.763062 -139.255163) (xy 82.72285 -139.319431) (xy 82.676035 -139.37906)
			(xy 82.623147 -139.433376) (xy 82.564785 -139.481762) (xy 82.50161 -139.52367) (xy 82.434339 -139.558626)
			(xy 82.363734 -139.586233) (xy 82.290593 -139.606179) (xy 82.215748 -139.618238) (xy 82.140044 -139.622273)
			(xy 82.06434 -139.618238) (xy 81.989495 -139.606179) (xy 81.916354 -139.586233) (xy 81.845749 -139.558626)
			(xy 81.778478 -139.52367) (xy 81.715303 -139.481762) (xy 81.656941 -139.433376) (xy 81.604053 -139.37906)
			(xy 81.557238 -139.319431) (xy 81.517026 -139.255163) (xy 81.483874 -139.186986) (xy 81.458156 -139.11567)
			(xy 81.440164 -139.042025) (xy 81.430102 -138.966885) (xy 81.428083 -138.891101) (xy 80.312005 -138.891101)
			(xy 80.309986 -138.966885) (xy 80.299924 -139.042025) (xy 80.281932 -139.11567) (xy 80.256214 -139.186986)
			(xy 80.223062 -139.255163) (xy 80.18285 -139.319431) (xy 80.136035 -139.37906) (xy 80.083147 -139.433376)
			(xy 80.024785 -139.481762) (xy 79.96161 -139.52367) (xy 79.894339 -139.558626) (xy 79.823734 -139.586233)
			(xy 79.750593 -139.606179) (xy 79.675748 -139.618238) (xy 79.600044 -139.622273) (xy 79.52434 -139.618238)
			(xy 79.449495 -139.606179) (xy 79.376354 -139.586233) (xy 79.305749 -139.558626) (xy 79.238478 -139.52367)
			(xy 79.175303 -139.481762) (xy 79.116941 -139.433376) (xy 79.064053 -139.37906) (xy 79.017238 -139.319431)
			(xy 78.977026 -139.255163) (xy 78.943874 -139.186986) (xy 78.918156 -139.11567) (xy 78.900164 -139.042025)
			(xy 78.890102 -138.966885) (xy 78.888083 -138.891101) (xy 77.772005 -138.891101) (xy 77.769986 -138.966885)
			(xy 77.759924 -139.042025) (xy 77.741932 -139.11567) (xy 77.716214 -139.186986) (xy 77.683062 -139.255163)
			(xy 77.64285 -139.319431) (xy 77.596035 -139.37906) (xy 77.543147 -139.433376) (xy 77.484785 -139.481762)
			(xy 77.42161 -139.52367) (xy 77.354339 -139.558626) (xy 77.283734 -139.586233) (xy 77.210593 -139.606179)
			(xy 77.135748 -139.618238) (xy 77.060044 -139.622273) (xy 76.98434 -139.618238) (xy 76.909495 -139.606179)
			(xy 76.836354 -139.586233) (xy 76.765749 -139.558626) (xy 76.698478 -139.52367) (xy 76.635303 -139.481762)
			(xy 76.576941 -139.433376) (xy 76.524053 -139.37906) (xy 76.477238 -139.319431) (xy 76.437026 -139.255163)
			(xy 76.403874 -139.186986) (xy 76.378156 -139.11567) (xy 76.360164 -139.042025) (xy 76.350102 -138.966885)
			(xy 76.348083 -138.891101) (xy 75.232005 -138.891101) (xy 75.229986 -138.966885) (xy 75.219924 -139.042025)
			(xy 75.201932 -139.11567) (xy 75.176214 -139.186986) (xy 75.143062 -139.255163) (xy 75.10285 -139.319431)
			(xy 75.056035 -139.37906) (xy 75.003147 -139.433376) (xy 74.944785 -139.481762) (xy 74.88161 -139.52367)
			(xy 74.814339 -139.558626) (xy 74.743734 -139.586233) (xy 74.670593 -139.606179) (xy 74.595748 -139.618238)
			(xy 74.520044 -139.622273) (xy 74.44434 -139.618238) (xy 74.369495 -139.606179) (xy 74.296354 -139.586233)
			(xy 74.225749 -139.558626) (xy 74.158478 -139.52367) (xy 74.095303 -139.481762) (xy 74.036941 -139.433376)
			(xy 73.984053 -139.37906) (xy 73.937238 -139.319431) (xy 73.897026 -139.255163) (xy 73.863874 -139.186986)
			(xy 73.838156 -139.11567) (xy 73.820164 -139.042025) (xy 73.810102 -138.966885) (xy 73.808083 -138.891101)
			(xy 72.692005 -138.891101) (xy 72.689986 -138.966885) (xy 72.679924 -139.042025) (xy 72.661932 -139.11567)
			(xy 72.636214 -139.186986) (xy 72.603062 -139.255163) (xy 72.56285 -139.319431) (xy 72.516035 -139.37906)
			(xy 72.463147 -139.433376) (xy 72.404785 -139.481762) (xy 72.34161 -139.52367) (xy 72.274339 -139.558626)
			(xy 72.203734 -139.586233) (xy 72.130593 -139.606179) (xy 72.055748 -139.618238) (xy 71.980044 -139.622273)
			(xy 71.90434 -139.618238) (xy 71.829495 -139.606179) (xy 71.756354 -139.586233) (xy 71.685749 -139.558626)
			(xy 71.618478 -139.52367) (xy 71.555303 -139.481762) (xy 71.496941 -139.433376) (xy 71.444053 -139.37906)
			(xy 71.397238 -139.319431) (xy 71.357026 -139.255163) (xy 71.323874 -139.186986) (xy 71.298156 -139.11567)
			(xy 71.280164 -139.042025) (xy 71.270102 -138.966885) (xy 71.268083 -138.891101) (xy 70.152005 -138.891101)
			(xy 70.149986 -138.966885) (xy 70.139924 -139.042025) (xy 70.121932 -139.11567) (xy 70.096214 -139.186986)
			(xy 70.063062 -139.255163) (xy 70.02285 -139.319431) (xy 69.976035 -139.37906) (xy 69.923147 -139.433376)
			(xy 69.864785 -139.481762) (xy 69.80161 -139.52367) (xy 69.734339 -139.558626) (xy 69.663734 -139.586233)
			(xy 69.590593 -139.606179) (xy 69.515748 -139.618238) (xy 69.440044 -139.622273) (xy 69.36434 -139.618238)
			(xy 69.289495 -139.606179) (xy 69.216354 -139.586233) (xy 69.145749 -139.558626) (xy 69.078478 -139.52367)
			(xy 69.015303 -139.481762) (xy 68.956941 -139.433376) (xy 68.904053 -139.37906) (xy 68.857238 -139.319431)
			(xy 68.817026 -139.255163) (xy 68.783874 -139.186986) (xy 68.758156 -139.11567) (xy 68.740164 -139.042025)
			(xy 68.730102 -138.966885) (xy 68.728083 -138.891101) (xy 67.612005 -138.891101) (xy 67.609986 -138.966885)
			(xy 67.599924 -139.042025) (xy 67.581932 -139.11567) (xy 67.556214 -139.186986) (xy 67.523062 -139.255163)
			(xy 67.48285 -139.319431) (xy 67.436035 -139.37906) (xy 67.383147 -139.433376) (xy 67.324785 -139.481762)
			(xy 67.26161 -139.52367) (xy 67.194339 -139.558626) (xy 67.123734 -139.586233) (xy 67.050593 -139.606179)
			(xy 66.975748 -139.618238) (xy 66.900044 -139.622273) (xy 66.82434 -139.618238) (xy 66.749495 -139.606179)
			(xy 66.676354 -139.586233) (xy 66.605749 -139.558626) (xy 66.538478 -139.52367) (xy 66.475303 -139.481762)
			(xy 66.416941 -139.433376) (xy 66.364053 -139.37906) (xy 66.317238 -139.319431) (xy 66.277026 -139.255163)
			(xy 66.243874 -139.186986) (xy 66.218156 -139.11567) (xy 66.200164 -139.042025) (xy 66.190102 -138.966885)
			(xy 66.188083 -138.891101) (xy 65.072005 -138.891101) (xy 65.069986 -138.966885) (xy 65.059924 -139.042025)
			(xy 65.041932 -139.11567) (xy 65.016214 -139.186986) (xy 64.983062 -139.255163) (xy 64.94285 -139.319431)
			(xy 64.896035 -139.37906) (xy 64.843147 -139.433376) (xy 64.784785 -139.481762) (xy 64.72161 -139.52367)
			(xy 64.654339 -139.558626) (xy 64.583734 -139.586233) (xy 64.510593 -139.606179) (xy 64.435748 -139.618238)
			(xy 64.360044 -139.622273) (xy 64.28434 -139.618238) (xy 64.209495 -139.606179) (xy 64.136354 -139.586233)
			(xy 64.065749 -139.558626) (xy 63.998478 -139.52367) (xy 63.935303 -139.481762) (xy 63.876941 -139.433376)
			(xy 63.824053 -139.37906) (xy 63.777238 -139.319431) (xy 63.737026 -139.255163) (xy 63.703874 -139.186986)
			(xy 63.678156 -139.11567) (xy 63.660164 -139.042025) (xy 63.650102 -138.966885) (xy 63.648083 -138.891101)
			(xy 42.475123 -138.891101) (xy 42.525733 -138.92734) (xy 42.615235 -139.001279) (xy 42.699423 -139.081217)
			(xy 42.777896 -139.166772) (xy 42.850279 -139.257538) (xy 42.916228 -139.353081) (xy 42.975428 -139.452946)
			(xy 43.027597 -139.556658) (xy 43.072486 -139.663721) (xy 43.109882 -139.773627) (xy 43.139607 -139.885851)
			(xy 43.161518 -139.999857) (xy 43.175511 -140.115104) (xy 43.18152 -140.231042) (xy 43.179517 -140.347118)
			(xy 43.169509 -140.46278) (xy 43.151546 -140.577475) (xy 43.125713 -140.690658) (xy 43.092133 -140.801789)
			(xy 43.050965 -140.910338) (xy 43.002407 -141.015788) (xy 42.94669 -141.117637) (xy 42.884078 -141.2154)
			(xy 42.814871 -141.30861) (xy 42.739398 -141.396823) (xy 42.658019 -141.479619) (xy 42.571122 -141.556603)
			(xy 42.526271 -141.591121) (xy 63.648083 -141.591121) (xy 63.654132 -141.515551) (xy 63.668179 -141.441053)
			(xy 63.690065 -141.36847) (xy 63.719542 -141.298624) (xy 63.756277 -141.232307) (xy 63.799852 -141.170271)
			(xy 63.849774 -141.113218) (xy 63.905478 -141.061794) (xy 63.966333 -141.016583) (xy 64.031648 -140.978096)
			(xy 64.100684 -140.94677) (xy 64.172659 -140.92296) (xy 64.246757 -140.906935) (xy 64.322138 -140.898876)
			(xy 64.360044 -140.898372) (xy 64.39795 -140.898876) (xy 64.473331 -140.906935) (xy 64.547429 -140.92296)
			(xy 64.619404 -140.94677) (xy 64.68844 -140.978096) (xy 64.753755 -141.016583) (xy 64.81461 -141.061794)
			(xy 64.870314 -141.113218) (xy 64.920236 -141.170271) (xy 64.963811 -141.232307) (xy 65.000546 -141.298624)
			(xy 65.030023 -141.36847) (xy 65.051909 -141.441053) (xy 65.065956 -141.515551) (xy 65.072005 -141.591121)
			(xy 66.188083 -141.591121) (xy 66.194132 -141.515551) (xy 66.208179 -141.441053) (xy 66.230065 -141.36847)
			(xy 66.259542 -141.298624) (xy 66.296277 -141.232307) (xy 66.339852 -141.170271) (xy 66.389774 -141.113218)
			(xy 66.445478 -141.061794) (xy 66.506333 -141.016583) (xy 66.571648 -140.978096) (xy 66.640684 -140.94677)
			(xy 66.712659 -140.92296) (xy 66.786757 -140.906935) (xy 66.862138 -140.898876) (xy 66.900044 -140.898372)
			(xy 66.93795 -140.898876) (xy 67.013331 -140.906935) (xy 67.087429 -140.92296) (xy 67.159404 -140.94677)
			(xy 67.22844 -140.978096) (xy 67.293755 -141.016583) (xy 67.35461 -141.061794) (xy 67.410314 -141.113218)
			(xy 67.460236 -141.170271) (xy 67.503811 -141.232307) (xy 67.540546 -141.298624) (xy 67.570023 -141.36847)
			(xy 67.591909 -141.441053) (xy 67.605956 -141.515551) (xy 67.612005 -141.591121) (xy 68.728083 -141.591121)
			(xy 68.734132 -141.515551) (xy 68.748179 -141.441053) (xy 68.770065 -141.36847) (xy 68.799542 -141.298624)
			(xy 68.836277 -141.232307) (xy 68.879852 -141.170271) (xy 68.929774 -141.113218) (xy 68.985478 -141.061794)
			(xy 69.046333 -141.016583) (xy 69.111648 -140.978096) (xy 69.180684 -140.94677) (xy 69.252659 -140.92296)
			(xy 69.326757 -140.906935) (xy 69.402138 -140.898876) (xy 69.440044 -140.898372) (xy 69.47795 -140.898876)
			(xy 69.553331 -140.906935) (xy 69.627429 -140.92296) (xy 69.699404 -140.94677) (xy 69.76844 -140.978096)
			(xy 69.833755 -141.016583) (xy 69.89461 -141.061794) (xy 69.950314 -141.113218) (xy 70.000236 -141.170271)
			(xy 70.043811 -141.232307) (xy 70.080546 -141.298624) (xy 70.110023 -141.36847) (xy 70.131909 -141.441053)
			(xy 70.145956 -141.515551) (xy 70.152005 -141.591121) (xy 71.268083 -141.591121) (xy 71.274132 -141.515551)
			(xy 71.288179 -141.441053) (xy 71.310065 -141.36847) (xy 71.339542 -141.298624) (xy 71.376277 -141.232307)
			(xy 71.419852 -141.170271) (xy 71.469774 -141.113218) (xy 71.525478 -141.061794) (xy 71.586333 -141.016583)
			(xy 71.651648 -140.978096) (xy 71.720684 -140.94677) (xy 71.792659 -140.92296) (xy 71.866757 -140.906935)
			(xy 71.942138 -140.898876) (xy 71.980044 -140.898372) (xy 72.01795 -140.898876) (xy 72.093331 -140.906935)
			(xy 72.167429 -140.92296) (xy 72.239404 -140.94677) (xy 72.30844 -140.978096) (xy 72.373755 -141.016583)
			(xy 72.43461 -141.061794) (xy 72.490314 -141.113218) (xy 72.540236 -141.170271) (xy 72.583811 -141.232307)
			(xy 72.620546 -141.298624) (xy 72.650023 -141.36847) (xy 72.671909 -141.441053) (xy 72.685956 -141.515551)
			(xy 72.692005 -141.591121) (xy 73.808083 -141.591121) (xy 73.814132 -141.515551) (xy 73.828179 -141.441053)
			(xy 73.850065 -141.36847) (xy 73.879542 -141.298624) (xy 73.916277 -141.232307) (xy 73.959852 -141.170271)
			(xy 74.009774 -141.113218) (xy 74.065478 -141.061794) (xy 74.126333 -141.016583) (xy 74.191648 -140.978096)
			(xy 74.260684 -140.94677) (xy 74.332659 -140.92296) (xy 74.406757 -140.906935) (xy 74.482138 -140.898876)
			(xy 74.520044 -140.898372) (xy 74.55795 -140.898876) (xy 74.633331 -140.906935) (xy 74.707429 -140.92296)
			(xy 74.779404 -140.94677) (xy 74.84844 -140.978096) (xy 74.913755 -141.016583) (xy 74.97461 -141.061794)
			(xy 75.030314 -141.113218) (xy 75.080236 -141.170271) (xy 75.123811 -141.232307) (xy 75.160546 -141.298624)
			(xy 75.190023 -141.36847) (xy 75.211909 -141.441053) (xy 75.225956 -141.515551) (xy 75.232005 -141.591121)
			(xy 76.348083 -141.591121) (xy 76.354132 -141.515551) (xy 76.368179 -141.441053) (xy 76.390065 -141.36847)
			(xy 76.419542 -141.298624) (xy 76.456277 -141.232307) (xy 76.499852 -141.170271) (xy 76.549774 -141.113218)
			(xy 76.605478 -141.061794) (xy 76.666333 -141.016583) (xy 76.731648 -140.978096) (xy 76.800684 -140.94677)
			(xy 76.872659 -140.92296) (xy 76.946757 -140.906935) (xy 77.022138 -140.898876) (xy 77.060044 -140.898372)
			(xy 77.09795 -140.898876) (xy 77.173331 -140.906935) (xy 77.247429 -140.92296) (xy 77.319404 -140.94677)
			(xy 77.38844 -140.978096) (xy 77.453755 -141.016583) (xy 77.51461 -141.061794) (xy 77.570314 -141.113218)
			(xy 77.620236 -141.170271) (xy 77.663811 -141.232307) (xy 77.700546 -141.298624) (xy 77.730023 -141.36847)
			(xy 77.751909 -141.441053) (xy 77.765956 -141.515551) (xy 77.772005 -141.591121) (xy 78.888083 -141.591121)
			(xy 78.894132 -141.515551) (xy 78.908179 -141.441053) (xy 78.930065 -141.36847) (xy 78.959542 -141.298624)
			(xy 78.996277 -141.232307) (xy 79.039852 -141.170271) (xy 79.089774 -141.113218) (xy 79.145478 -141.061794)
			(xy 79.206333 -141.016583) (xy 79.271648 -140.978096) (xy 79.340684 -140.94677) (xy 79.412659 -140.92296)
			(xy 79.486757 -140.906935) (xy 79.562138 -140.898876) (xy 79.600044 -140.898372) (xy 79.63795 -140.898876)
			(xy 79.713331 -140.906935) (xy 79.787429 -140.92296) (xy 79.859404 -140.94677) (xy 79.92844 -140.978096)
			(xy 79.993755 -141.016583) (xy 80.05461 -141.061794) (xy 80.110314 -141.113218) (xy 80.160236 -141.170271)
			(xy 80.203811 -141.232307) (xy 80.240546 -141.298624) (xy 80.270023 -141.36847) (xy 80.291909 -141.441053)
			(xy 80.305956 -141.515551) (xy 80.312005 -141.591121) (xy 81.428083 -141.591121) (xy 81.434132 -141.515551)
			(xy 81.448179 -141.441053) (xy 81.470065 -141.36847) (xy 81.499542 -141.298624) (xy 81.536277 -141.232307)
			(xy 81.579852 -141.170271) (xy 81.629774 -141.113218) (xy 81.685478 -141.061794) (xy 81.746333 -141.016583)
			(xy 81.811648 -140.978096) (xy 81.880684 -140.94677) (xy 81.952659 -140.92296) (xy 82.026757 -140.906935)
			(xy 82.102138 -140.898876) (xy 82.140044 -140.898372) (xy 82.17795 -140.898876) (xy 82.253331 -140.906935)
			(xy 82.327429 -140.92296) (xy 82.399404 -140.94677) (xy 82.46844 -140.978096) (xy 82.533755 -141.016583)
			(xy 82.59461 -141.061794) (xy 82.650314 -141.113218) (xy 82.700236 -141.170271) (xy 82.743811 -141.232307)
			(xy 82.780546 -141.298624) (xy 82.810023 -141.36847) (xy 82.831909 -141.441053) (xy 82.845956 -141.515551)
			(xy 82.852005 -141.591121) (xy 82.849986 -141.666905) (xy 82.839924 -141.742045) (xy 82.821932 -141.81569)
			(xy 82.796214 -141.887006) (xy 82.763062 -141.955183) (xy 82.72285 -142.019451) (xy 82.676035 -142.07908)
			(xy 82.623147 -142.133396) (xy 82.564785 -142.181782) (xy 82.50161 -142.22369) (xy 82.434339 -142.258646)
			(xy 82.363734 -142.286253) (xy 82.290593 -142.306199) (xy 82.215748 -142.318258) (xy 82.140044 -142.322293)
			(xy 82.06434 -142.318258) (xy 81.989495 -142.306199) (xy 81.916354 -142.286253) (xy 81.845749 -142.258646)
			(xy 81.778478 -142.22369) (xy 81.715303 -142.181782) (xy 81.656941 -142.133396) (xy 81.604053 -142.07908)
			(xy 81.557238 -142.019451) (xy 81.517026 -141.955183) (xy 81.483874 -141.887006) (xy 81.458156 -141.81569)
			(xy 81.440164 -141.742045) (xy 81.430102 -141.666905) (xy 81.428083 -141.591121) (xy 80.312005 -141.591121)
			(xy 80.309986 -141.666905) (xy 80.299924 -141.742045) (xy 80.281932 -141.81569) (xy 80.256214 -141.887006)
			(xy 80.223062 -141.955183) (xy 80.18285 -142.019451) (xy 80.136035 -142.07908) (xy 80.083147 -142.133396)
			(xy 80.024785 -142.181782) (xy 79.96161 -142.22369) (xy 79.894339 -142.258646) (xy 79.823734 -142.286253)
			(xy 79.750593 -142.306199) (xy 79.675748 -142.318258) (xy 79.600044 -142.322293) (xy 79.52434 -142.318258)
			(xy 79.449495 -142.306199) (xy 79.376354 -142.286253) (xy 79.305749 -142.258646) (xy 79.238478 -142.22369)
			(xy 79.175303 -142.181782) (xy 79.116941 -142.133396) (xy 79.064053 -142.07908) (xy 79.017238 -142.019451)
			(xy 78.977026 -141.955183) (xy 78.943874 -141.887006) (xy 78.918156 -141.81569) (xy 78.900164 -141.742045)
			(xy 78.890102 -141.666905) (xy 78.888083 -141.591121) (xy 77.772005 -141.591121) (xy 77.769986 -141.666905)
			(xy 77.759924 -141.742045) (xy 77.741932 -141.81569) (xy 77.716214 -141.887006) (xy 77.683062 -141.955183)
			(xy 77.64285 -142.019451) (xy 77.596035 -142.07908) (xy 77.543147 -142.133396) (xy 77.484785 -142.181782)
			(xy 77.42161 -142.22369) (xy 77.354339 -142.258646) (xy 77.283734 -142.286253) (xy 77.210593 -142.306199)
			(xy 77.135748 -142.318258) (xy 77.060044 -142.322293) (xy 76.98434 -142.318258) (xy 76.909495 -142.306199)
			(xy 76.836354 -142.286253) (xy 76.765749 -142.258646) (xy 76.698478 -142.22369) (xy 76.635303 -142.181782)
			(xy 76.576941 -142.133396) (xy 76.524053 -142.07908) (xy 76.477238 -142.019451) (xy 76.437026 -141.955183)
			(xy 76.403874 -141.887006) (xy 76.378156 -141.81569) (xy 76.360164 -141.742045) (xy 76.350102 -141.666905)
			(xy 76.348083 -141.591121) (xy 75.232005 -141.591121) (xy 75.229986 -141.666905) (xy 75.219924 -141.742045)
			(xy 75.201932 -141.81569) (xy 75.176214 -141.887006) (xy 75.143062 -141.955183) (xy 75.10285 -142.019451)
			(xy 75.056035 -142.07908) (xy 75.003147 -142.133396) (xy 74.944785 -142.181782) (xy 74.88161 -142.22369)
			(xy 74.814339 -142.258646) (xy 74.743734 -142.286253) (xy 74.670593 -142.306199) (xy 74.595748 -142.318258)
			(xy 74.520044 -142.322293) (xy 74.44434 -142.318258) (xy 74.369495 -142.306199) (xy 74.296354 -142.286253)
			(xy 74.225749 -142.258646) (xy 74.158478 -142.22369) (xy 74.095303 -142.181782) (xy 74.036941 -142.133396)
			(xy 73.984053 -142.07908) (xy 73.937238 -142.019451) (xy 73.897026 -141.955183) (xy 73.863874 -141.887006)
			(xy 73.838156 -141.81569) (xy 73.820164 -141.742045) (xy 73.810102 -141.666905) (xy 73.808083 -141.591121)
			(xy 72.692005 -141.591121) (xy 72.689986 -141.666905) (xy 72.679924 -141.742045) (xy 72.661932 -141.81569)
			(xy 72.636214 -141.887006) (xy 72.603062 -141.955183) (xy 72.56285 -142.019451) (xy 72.516035 -142.07908)
			(xy 72.463147 -142.133396) (xy 72.404785 -142.181782) (xy 72.34161 -142.22369) (xy 72.274339 -142.258646)
			(xy 72.203734 -142.286253) (xy 72.130593 -142.306199) (xy 72.055748 -142.318258) (xy 71.980044 -142.322293)
			(xy 71.90434 -142.318258) (xy 71.829495 -142.306199) (xy 71.756354 -142.286253) (xy 71.685749 -142.258646)
			(xy 71.618478 -142.22369) (xy 71.555303 -142.181782) (xy 71.496941 -142.133396) (xy 71.444053 -142.07908)
			(xy 71.397238 -142.019451) (xy 71.357026 -141.955183) (xy 71.323874 -141.887006) (xy 71.298156 -141.81569)
			(xy 71.280164 -141.742045) (xy 71.270102 -141.666905) (xy 71.268083 -141.591121) (xy 70.152005 -141.591121)
			(xy 70.149986 -141.666905) (xy 70.139924 -141.742045) (xy 70.121932 -141.81569) (xy 70.096214 -141.887006)
			(xy 70.063062 -141.955183) (xy 70.02285 -142.019451) (xy 69.976035 -142.07908) (xy 69.923147 -142.133396)
			(xy 69.864785 -142.181782) (xy 69.80161 -142.22369) (xy 69.734339 -142.258646) (xy 69.663734 -142.286253)
			(xy 69.590593 -142.306199) (xy 69.515748 -142.318258) (xy 69.440044 -142.322293) (xy 69.36434 -142.318258)
			(xy 69.289495 -142.306199) (xy 69.216354 -142.286253) (xy 69.145749 -142.258646) (xy 69.078478 -142.22369)
			(xy 69.015303 -142.181782) (xy 68.956941 -142.133396) (xy 68.904053 -142.07908) (xy 68.857238 -142.019451)
			(xy 68.817026 -141.955183) (xy 68.783874 -141.887006) (xy 68.758156 -141.81569) (xy 68.740164 -141.742045)
			(xy 68.730102 -141.666905) (xy 68.728083 -141.591121) (xy 67.612005 -141.591121) (xy 67.609986 -141.666905)
			(xy 67.599924 -141.742045) (xy 67.581932 -141.81569) (xy 67.556214 -141.887006) (xy 67.523062 -141.955183)
			(xy 67.48285 -142.019451) (xy 67.436035 -142.07908) (xy 67.383147 -142.133396) (xy 67.324785 -142.181782)
			(xy 67.26161 -142.22369) (xy 67.194339 -142.258646) (xy 67.123734 -142.286253) (xy 67.050593 -142.306199)
			(xy 66.975748 -142.318258) (xy 66.900044 -142.322293) (xy 66.82434 -142.318258) (xy 66.749495 -142.306199)
			(xy 66.676354 -142.286253) (xy 66.605749 -142.258646) (xy 66.538478 -142.22369) (xy 66.475303 -142.181782)
			(xy 66.416941 -142.133396) (xy 66.364053 -142.07908) (xy 66.317238 -142.019451) (xy 66.277026 -141.955183)
			(xy 66.243874 -141.887006) (xy 66.218156 -141.81569) (xy 66.200164 -141.742045) (xy 66.190102 -141.666905)
			(xy 66.188083 -141.591121) (xy 65.072005 -141.591121) (xy 65.069986 -141.666905) (xy 65.059924 -141.742045)
			(xy 65.041932 -141.81569) (xy 65.016214 -141.887006) (xy 64.983062 -141.955183) (xy 64.94285 -142.019451)
			(xy 64.896035 -142.07908) (xy 64.843147 -142.133396) (xy 64.784785 -142.181782) (xy 64.72161 -142.22369)
			(xy 64.654339 -142.258646) (xy 64.583734 -142.286253) (xy 64.510593 -142.306199) (xy 64.435748 -142.318258)
			(xy 64.360044 -142.322293) (xy 64.28434 -142.318258) (xy 64.209495 -142.306199) (xy 64.136354 -142.286253)
			(xy 64.065749 -142.258646) (xy 63.998478 -142.22369) (xy 63.935303 -142.181782) (xy 63.876941 -142.133396)
			(xy 63.824053 -142.07908) (xy 63.777238 -142.019451) (xy 63.737026 -141.955183) (xy 63.703874 -141.887006)
			(xy 63.678156 -141.81569) (xy 63.660164 -141.742045) (xy 63.650102 -141.666905) (xy 63.648083 -141.591121)
			(xy 42.526271 -141.591121) (xy 42.479121 -141.627408) (xy 42.382454 -141.691698) (xy 42.281582 -141.749165)
			(xy 42.176985 -141.799536) (xy 42.069162 -141.842571) (xy 41.958628 -141.878065) (xy 41.845908 -141.905848)
			(xy 41.73154 -141.925788) (xy 41.616068 -141.93779) (xy 41.500044 -141.941797) (xy 41.38402 -141.93779)
			(xy 41.268548 -141.925788) (xy 41.15418 -141.905848) (xy 41.04146 -141.878065) (xy 40.930926 -141.842571)
			(xy 40.823103 -141.799536) (xy 40.718506 -141.749165) (xy 40.617634 -141.691698) (xy 40.520967 -141.627408)
			(xy 40.428966 -141.556603) (xy 40.342069 -141.479619) (xy 40.26069 -141.396823) (xy 40.185217 -141.30861)
			(xy 40.11601 -141.2154) (xy 40.053398 -141.117637) (xy 39.997681 -141.015788) (xy 39.949123 -140.910338)
			(xy 39.907955 -140.801789) (xy 39.874375 -140.690658) (xy 39.848542 -140.577475) (xy 39.830579 -140.46278)
			(xy 39.820571 -140.347118) (xy 39.818568 -140.231042) (xy 28.884372 -140.231042) (xy 28.884372 -143.833358)
			(xy 29.519874 -143.833358) (xy 29.519874 -143.746458) (xy 29.527892 -143.659929) (xy 29.54386 -143.574509)
			(xy 29.567641 -143.490927) (xy 29.599033 -143.409895) (xy 29.637767 -143.332106) (xy 29.683514 -143.258222)
			(xy 29.735883 -143.188875) (xy 29.794427 -143.124655) (xy 29.858647 -143.066111) (xy 29.927994 -143.013742)
			(xy 30.001878 -142.967995) (xy 30.079667 -142.929261) (xy 30.160699 -142.897869) (xy 30.244281 -142.874088)
			(xy 30.329701 -142.85812) (xy 30.41623 -142.850102) (xy 30.45968 -142.8496) (xy 30.50313 -142.850102)
			(xy 30.589659 -142.85812) (xy 30.675079 -142.874088) (xy 30.758661 -142.897869) (xy 30.839693 -142.929261)
			(xy 30.917482 -142.967995) (xy 30.991366 -143.013742) (xy 31.060713 -143.066111) (xy 31.124933 -143.124655)
			(xy 31.183477 -143.188875) (xy 31.235846 -143.258222) (xy 31.281593 -143.332106) (xy 31.320327 -143.409895)
			(xy 31.351719 -143.490927) (xy 31.3755 -143.574509) (xy 31.391468 -143.659929) (xy 31.399486 -143.746458)
			(xy 31.399486 -143.833358) (xy 34.599874 -143.833358) (xy 34.599874 -143.746458) (xy 34.607892 -143.659929)
			(xy 34.62386 -143.574509) (xy 34.647641 -143.490927) (xy 34.679033 -143.409895) (xy 34.717767 -143.332106)
			(xy 34.763514 -143.258222) (xy 34.815883 -143.188875) (xy 34.874427 -143.124655) (xy 34.938647 -143.066111)
			(xy 35.007994 -143.013742) (xy 35.081878 -142.967995) (xy 35.159667 -142.929261) (xy 35.240699 -142.897869)
			(xy 35.324281 -142.874088) (xy 35.409701 -142.85812) (xy 35.49623 -142.850102) (xy 35.53968 -142.8496)
			(xy 35.58313 -142.850102) (xy 35.669659 -142.85812) (xy 35.755079 -142.874088) (xy 35.838661 -142.897869)
			(xy 35.919693 -142.929261) (xy 35.997482 -142.967995) (xy 36.071366 -143.013742) (xy 36.140713 -143.066111)
			(xy 36.204933 -143.124655) (xy 36.263477 -143.188875) (xy 36.315846 -143.258222) (xy 36.361593 -143.332106)
			(xy 36.400327 -143.409895) (xy 36.431719 -143.490927) (xy 36.4555 -143.574509) (xy 36.471468 -143.659929)
			(xy 36.479486 -143.746458) (xy 36.479486 -143.833358) (xy 36.471468 -143.919887) (xy 36.4555 -144.005307)
			(xy 36.431719 -144.088889) (xy 36.400327 -144.169921) (xy 36.361593 -144.24771) (xy 36.315846 -144.321594)
			(xy 36.263477 -144.390941) (xy 36.204933 -144.455161) (xy 36.140713 -144.513705) (xy 36.071366 -144.566074)
			(xy 35.997482 -144.611821) (xy 35.919693 -144.650555) (xy 35.838661 -144.681947) (xy 35.755079 -144.705728)
			(xy 35.669659 -144.721696) (xy 35.58313 -144.729714) (xy 35.49623 -144.729714) (xy 35.409701 -144.721696)
			(xy 35.324281 -144.705728) (xy 35.240699 -144.681947) (xy 35.159667 -144.650555) (xy 35.081878 -144.611821)
			(xy 35.007994 -144.566074) (xy 34.938647 -144.513705) (xy 34.874427 -144.455161) (xy 34.815883 -144.390941)
			(xy 34.763514 -144.321594) (xy 34.717767 -144.24771) (xy 34.679033 -144.169921) (xy 34.647641 -144.088889)
			(xy 34.62386 -144.005307) (xy 34.607892 -143.919887) (xy 34.599874 -143.833358) (xy 31.399486 -143.833358)
			(xy 31.391468 -143.919887) (xy 31.3755 -144.005307) (xy 31.351719 -144.088889) (xy 31.320327 -144.169921)
			(xy 31.281593 -144.24771) (xy 31.235846 -144.321594) (xy 31.183477 -144.390941) (xy 31.124933 -144.455161)
			(xy 31.060713 -144.513705) (xy 30.991366 -144.566074) (xy 30.917482 -144.611821) (xy 30.839693 -144.650555)
			(xy 30.758661 -144.681947) (xy 30.675079 -144.705728) (xy 30.589659 -144.721696) (xy 30.50313 -144.729714)
			(xy 30.41623 -144.729714) (xy 30.329701 -144.721696) (xy 30.244281 -144.705728) (xy 30.160699 -144.681947)
			(xy 30.079667 -144.650555) (xy 30.001878 -144.611821) (xy 29.927994 -144.566074) (xy 29.858647 -144.513705)
			(xy 29.794427 -144.455161) (xy 29.735883 -144.390941) (xy 29.683514 -144.321594) (xy 29.637767 -144.24771)
			(xy 29.599033 -144.169921) (xy 29.567641 -144.088889) (xy 29.54386 -144.005307) (xy 29.527892 -143.919887)
			(xy 29.519874 -143.833358) (xy 28.884372 -143.833358) (xy 28.884372 -146.373358) (xy 29.519874 -146.373358)
			(xy 29.519874 -146.286458) (xy 29.527892 -146.199929) (xy 29.54386 -146.114509) (xy 29.567641 -146.030927)
			(xy 29.599033 -145.949895) (xy 29.637767 -145.872106) (xy 29.683514 -145.798222) (xy 29.735883 -145.728875)
			(xy 29.794427 -145.664655) (xy 29.858647 -145.606111) (xy 29.927994 -145.553742) (xy 30.001878 -145.507995)
			(xy 30.079667 -145.469261) (xy 30.160699 -145.437869) (xy 30.244281 -145.414088) (xy 30.329701 -145.39812)
			(xy 30.41623 -145.390102) (xy 30.45968 -145.3896) (xy 30.50313 -145.390102) (xy 30.589659 -145.39812)
			(xy 30.675079 -145.414088) (xy 30.758661 -145.437869) (xy 30.839693 -145.469261) (xy 30.917482 -145.507995)
			(xy 30.991366 -145.553742) (xy 31.060713 -145.606111) (xy 31.124933 -145.664655) (xy 31.183477 -145.728875)
			(xy 31.235846 -145.798222) (xy 31.281593 -145.872106) (xy 31.320327 -145.949895) (xy 31.351719 -146.030927)
			(xy 31.3755 -146.114509) (xy 31.391468 -146.199929) (xy 31.399486 -146.286458) (xy 31.399486 -146.373358)
			(xy 34.599874 -146.373358) (xy 34.599874 -146.286458) (xy 34.607892 -146.199929) (xy 34.62386 -146.114509)
			(xy 34.647641 -146.030927) (xy 34.679033 -145.949895) (xy 34.717767 -145.872106) (xy 34.763514 -145.798222)
			(xy 34.815883 -145.728875) (xy 34.874427 -145.664655) (xy 34.938647 -145.606111) (xy 35.007994 -145.553742)
			(xy 35.081878 -145.507995) (xy 35.159667 -145.469261) (xy 35.240699 -145.437869) (xy 35.324281 -145.414088)
			(xy 35.409701 -145.39812) (xy 35.49623 -145.390102) (xy 35.53968 -145.3896) (xy 35.58313 -145.390102)
			(xy 35.669659 -145.39812) (xy 35.755079 -145.414088) (xy 35.838661 -145.437869) (xy 35.919693 -145.469261)
			(xy 35.953243 -145.485967) (xy 67.225156 -145.485967) (xy 67.225156 -145.414645) (xy 67.233142 -145.343771)
			(xy 67.249012 -145.274236) (xy 67.272569 -145.206916) (xy 67.303514 -145.142657) (xy 67.34146 -145.082266)
			(xy 67.385929 -145.026504) (xy 67.436362 -144.976071) (xy 67.492124 -144.931602) (xy 67.552515 -144.893656)
			(xy 67.616774 -144.862711) (xy 67.684094 -144.839154) (xy 67.753629 -144.823284) (xy 67.824503 -144.815298)
			(xy 67.860164 -144.814798) (xy 67.895825 -144.815298) (xy 67.966699 -144.823284) (xy 68.036234 -144.839154)
			(xy 68.103554 -144.862711) (xy 68.167813 -144.893656) (xy 68.228204 -144.931602) (xy 68.283966 -144.976071)
			(xy 68.334399 -145.026504) (xy 68.378868 -145.082266) (xy 68.416814 -145.142657) (xy 68.447759 -145.206916)
			(xy 68.471316 -145.274236) (xy 68.487186 -145.343771) (xy 68.495172 -145.414645) (xy 68.495172 -145.485967)
			(xy 70.216768 -145.485967) (xy 70.216768 -145.414645) (xy 70.224754 -145.343771) (xy 70.240624 -145.274236)
			(xy 70.264181 -145.206916) (xy 70.295126 -145.142657) (xy 70.333072 -145.082266) (xy 70.377541 -145.026504)
			(xy 70.427974 -144.976071) (xy 70.483736 -144.931602) (xy 70.544127 -144.893656) (xy 70.608386 -144.862711)
			(xy 70.675706 -144.839154) (xy 70.745241 -144.823284) (xy 70.816115 -144.815298) (xy 70.851776 -144.814798)
			(xy 70.887437 -144.815298) (xy 70.958311 -144.823284) (xy 71.027846 -144.839154) (xy 71.095166 -144.862711)
			(xy 71.159425 -144.893656) (xy 71.219816 -144.931602) (xy 71.275578 -144.976071) (xy 71.326011 -145.026504)
			(xy 71.37048 -145.082266) (xy 71.408426 -145.142657) (xy 71.439371 -145.206916) (xy 71.462928 -145.274236)
			(xy 71.478798 -145.343771) (xy 71.486784 -145.414645) (xy 71.486784 -145.485967) (xy 71.478798 -145.556841)
			(xy 71.462928 -145.626376) (xy 71.439371 -145.693696) (xy 71.408426 -145.757955) (xy 71.37048 -145.818346)
			(xy 71.326011 -145.874108) (xy 71.275578 -145.924541) (xy 71.219816 -145.96901) (xy 71.159425 -146.006956)
			(xy 71.095166 -146.037901) (xy 71.027846 -146.061458) (xy 70.958311 -146.077328) (xy 70.887437 -146.085314)
			(xy 70.816115 -146.085314) (xy 70.745241 -146.077328) (xy 70.675706 -146.061458) (xy 70.608386 -146.037901)
			(xy 70.544127 -146.006956) (xy 70.483736 -145.96901) (xy 70.427974 -145.924541) (xy 70.377541 -145.874108)
			(xy 70.333072 -145.818346) (xy 70.295126 -145.757955) (xy 70.264181 -145.693696) (xy 70.240624 -145.626376)
			(xy 70.224754 -145.556841) (xy 70.216768 -145.485967) (xy 68.495172 -145.485967) (xy 68.487186 -145.556841)
			(xy 68.471316 -145.626376) (xy 68.447759 -145.693696) (xy 68.416814 -145.757955) (xy 68.378868 -145.818346)
			(xy 68.334399 -145.874108) (xy 68.283966 -145.924541) (xy 68.228204 -145.96901) (xy 68.167813 -146.006956)
			(xy 68.103554 -146.037901) (xy 68.036234 -146.061458) (xy 67.966699 -146.077328) (xy 67.895825 -146.085314)
			(xy 67.824503 -146.085314) (xy 67.753629 -146.077328) (xy 67.684094 -146.061458) (xy 67.616774 -146.037901)
			(xy 67.552515 -146.006956) (xy 67.492124 -145.96901) (xy 67.436362 -145.924541) (xy 67.385929 -145.874108)
			(xy 67.34146 -145.818346) (xy 67.303514 -145.757955) (xy 67.272569 -145.693696) (xy 67.249012 -145.626376)
			(xy 67.233142 -145.556841) (xy 67.225156 -145.485967) (xy 35.953243 -145.485967) (xy 35.997482 -145.507995)
			(xy 36.071366 -145.553742) (xy 36.140713 -145.606111) (xy 36.204933 -145.664655) (xy 36.263477 -145.728875)
			(xy 36.315846 -145.798222) (xy 36.361593 -145.872106) (xy 36.400327 -145.949895) (xy 36.431719 -146.030927)
			(xy 36.4555 -146.114509) (xy 36.471468 -146.199929) (xy 36.479486 -146.286458) (xy 36.479486 -146.373358)
			(xy 36.475649 -146.414762) (xy 80.994757 -146.414762) (xy 81.000857 -146.359325) (xy 81.014963 -146.305368)
			(xy 81.036775 -146.254039) (xy 81.065829 -146.206433) (xy 81.101504 -146.163565) (xy 81.143041 -146.126348)
			(xy 81.189554 -146.095575) (xy 81.240051 -146.071903) (xy 81.293458 -146.055835) (xy 81.348634 -146.047715)
			(xy 81.37652 -146.047206) (xy 81.404406 -146.047715) (xy 81.459582 -146.055835) (xy 81.512989 -146.071903)
			(xy 81.563486 -146.095575) (xy 81.609999 -146.126348) (xy 81.651536 -146.163565) (xy 81.687211 -146.206433)
			(xy 81.716265 -146.254039) (xy 81.738077 -146.305368) (xy 81.752183 -146.359325) (xy 81.758283 -146.414762)
			(xy 81.756246 -146.470496) (xy 81.746116 -146.525339) (xy 81.728109 -146.578123) (xy 81.702608 -146.627723)
			(xy 81.670157 -146.673081) (xy 81.631448 -146.71323) (xy 81.587305 -146.747316) (xy 81.53867 -146.774612)
			(xy 81.486579 -146.794535) (xy 81.432142 -146.806661) (xy 81.37652 -146.810732) (xy 81.320898 -146.806661)
			(xy 81.266461 -146.794535) (xy 81.21437 -146.774612) (xy 81.165735 -146.747316) (xy 81.121592 -146.71323)
			(xy 81.082883 -146.673081) (xy 81.050432 -146.627723) (xy 81.024931 -146.578123) (xy 81.006924 -146.525339)
			(xy 80.996794 -146.470496) (xy 80.994757 -146.414762) (xy 36.475649 -146.414762) (xy 36.471468 -146.459887)
			(xy 36.4555 -146.545307) (xy 36.431719 -146.628889) (xy 36.400327 -146.709921) (xy 36.361593 -146.78771)
			(xy 36.315846 -146.861594) (xy 36.263477 -146.930941) (xy 36.204933 -146.995161) (xy 36.140713 -147.053705)
			(xy 36.071366 -147.106074) (xy 35.997482 -147.151821) (xy 35.919693 -147.190555) (xy 35.838661 -147.221947)
			(xy 35.755079 -147.245728) (xy 35.669659 -147.261696) (xy 35.58313 -147.269714) (xy 35.49623 -147.269714)
			(xy 35.409701 -147.261696) (xy 35.324281 -147.245728) (xy 35.240699 -147.221947) (xy 35.159667 -147.190555)
			(xy 35.081878 -147.151821) (xy 35.007994 -147.106074) (xy 34.938647 -147.053705) (xy 34.874427 -146.995161)
			(xy 34.815883 -146.930941) (xy 34.763514 -146.861594) (xy 34.717767 -146.78771) (xy 34.679033 -146.709921)
			(xy 34.647641 -146.628889) (xy 34.62386 -146.545307) (xy 34.607892 -146.459887) (xy 34.599874 -146.373358)
			(xy 31.399486 -146.373358) (xy 31.391468 -146.459887) (xy 31.3755 -146.545307) (xy 31.351719 -146.628889)
			(xy 31.320327 -146.709921) (xy 31.281593 -146.78771) (xy 31.235846 -146.861594) (xy 31.183477 -146.930941)
			(xy 31.124933 -146.995161) (xy 31.060713 -147.053705) (xy 30.991366 -147.106074) (xy 30.917482 -147.151821)
			(xy 30.839693 -147.190555) (xy 30.758661 -147.221947) (xy 30.675079 -147.245728) (xy 30.589659 -147.261696)
			(xy 30.50313 -147.269714) (xy 30.41623 -147.269714) (xy 30.329701 -147.261696) (xy 30.244281 -147.245728)
			(xy 30.160699 -147.221947) (xy 30.079667 -147.190555) (xy 30.001878 -147.151821) (xy 29.927994 -147.106074)
			(xy 29.858647 -147.053705) (xy 29.794427 -146.995161) (xy 29.735883 -146.930941) (xy 29.683514 -146.861594)
			(xy 29.637767 -146.78771) (xy 29.599033 -146.709921) (xy 29.567641 -146.628889) (xy 29.54386 -146.545307)
			(xy 29.527892 -146.459887) (xy 29.519874 -146.373358) (xy 28.884372 -146.373358) (xy 28.884372 -147.721421)
			(xy 67.225156 -147.721421) (xy 67.225156 -147.650099) (xy 67.233142 -147.579225) (xy 67.249012 -147.50969)
			(xy 67.272569 -147.44237) (xy 67.303514 -147.378111) (xy 67.34146 -147.31772) (xy 67.385929 -147.261958)
			(xy 67.436362 -147.211525) (xy 67.492124 -147.167056) (xy 67.552515 -147.12911) (xy 67.616774 -147.098165)
			(xy 67.684094 -147.074608) (xy 67.753629 -147.058738) (xy 67.824503 -147.050752) (xy 67.860164 -147.050252)
			(xy 67.895825 -147.050752) (xy 67.966699 -147.058738) (xy 68.036234 -147.074608) (xy 68.103554 -147.098165)
			(xy 68.167813 -147.12911) (xy 68.228204 -147.167056) (xy 68.283966 -147.211525) (xy 68.334399 -147.261958)
			(xy 68.378868 -147.31772) (xy 68.416814 -147.378111) (xy 68.447759 -147.44237) (xy 68.471316 -147.50969)
			(xy 68.487186 -147.579225) (xy 68.495172 -147.650099) (xy 68.495172 -147.721421) (xy 70.216768 -147.721421)
			(xy 70.216768 -147.650099) (xy 70.224754 -147.579225) (xy 70.240624 -147.50969) (xy 70.264181 -147.44237)
			(xy 70.295126 -147.378111) (xy 70.333072 -147.31772) (xy 70.377541 -147.261958) (xy 70.427974 -147.211525)
			(xy 70.483736 -147.167056) (xy 70.544127 -147.12911) (xy 70.608386 -147.098165) (xy 70.675706 -147.074608)
			(xy 70.745241 -147.058738) (xy 70.816115 -147.050752) (xy 70.851776 -147.050252) (xy 70.887437 -147.050752)
			(xy 70.958311 -147.058738) (xy 71.027846 -147.074608) (xy 71.095166 -147.098165) (xy 71.159425 -147.12911)
			(xy 71.219816 -147.167056) (xy 71.275578 -147.211525) (xy 71.326011 -147.261958) (xy 71.37048 -147.31772)
			(xy 71.408426 -147.378111) (xy 71.439371 -147.44237) (xy 71.462928 -147.50969) (xy 71.478798 -147.579225)
			(xy 71.486784 -147.650099) (xy 71.486784 -147.721421) (xy 71.478798 -147.792295) (xy 71.467399 -147.842242)
			(xy 80.721707 -147.842242) (xy 80.727807 -147.786805) (xy 80.741913 -147.732848) (xy 80.763725 -147.681519)
			(xy 80.792779 -147.633913) (xy 80.828454 -147.591045) (xy 80.869991 -147.553828) (xy 80.916504 -147.523055)
			(xy 80.967001 -147.499383) (xy 81.020408 -147.483315) (xy 81.075584 -147.475195) (xy 81.10347 -147.474686)
			(xy 81.131356 -147.475195) (xy 81.186532 -147.483315) (xy 81.239939 -147.499383) (xy 81.290436 -147.523055)
			(xy 81.336949 -147.553828) (xy 81.378486 -147.591045) (xy 81.414161 -147.633913) (xy 81.443215 -147.681519)
			(xy 81.465027 -147.732848) (xy 81.479133 -147.786805) (xy 81.485233 -147.842242) (xy 81.483196 -147.897976)
			(xy 81.473066 -147.952819) (xy 81.455059 -148.005603) (xy 81.429558 -148.055203) (xy 81.397107 -148.100561)
			(xy 81.358398 -148.14071) (xy 81.314255 -148.174796) (xy 81.26562 -148.202092) (xy 81.213529 -148.222015)
			(xy 81.159092 -148.234141) (xy 81.10347 -148.238212) (xy 81.047848 -148.234141) (xy 80.993411 -148.222015)
			(xy 80.94132 -148.202092) (xy 80.892685 -148.174796) (xy 80.848542 -148.14071) (xy 80.809833 -148.100561)
			(xy 80.777382 -148.055203) (xy 80.751881 -148.005603) (xy 80.733874 -147.952819) (xy 80.723744 -147.897976)
			(xy 80.721707 -147.842242) (xy 71.467399 -147.842242) (xy 71.462928 -147.86183) (xy 71.439371 -147.92915)
			(xy 71.408426 -147.993409) (xy 71.37048 -148.0538) (xy 71.326011 -148.109562) (xy 71.275578 -148.159995)
			(xy 71.219816 -148.204464) (xy 71.159425 -148.24241) (xy 71.095166 -148.273355) (xy 71.027846 -148.296912)
			(xy 70.958311 -148.312782) (xy 70.887437 -148.320768) (xy 70.816115 -148.320768) (xy 70.745241 -148.312782)
			(xy 70.675706 -148.296912) (xy 70.608386 -148.273355) (xy 70.544127 -148.24241) (xy 70.483736 -148.204464)
			(xy 70.427974 -148.159995) (xy 70.377541 -148.109562) (xy 70.333072 -148.0538) (xy 70.295126 -147.993409)
			(xy 70.264181 -147.92915) (xy 70.240624 -147.86183) (xy 70.224754 -147.792295) (xy 70.216768 -147.721421)
			(xy 68.495172 -147.721421) (xy 68.487186 -147.792295) (xy 68.471316 -147.86183) (xy 68.447759 -147.92915)
			(xy 68.416814 -147.993409) (xy 68.378868 -148.0538) (xy 68.334399 -148.109562) (xy 68.283966 -148.159995)
			(xy 68.228204 -148.204464) (xy 68.167813 -148.24241) (xy 68.103554 -148.273355) (xy 68.036234 -148.296912)
			(xy 67.966699 -148.312782) (xy 67.895825 -148.320768) (xy 67.824503 -148.320768) (xy 67.753629 -148.312782)
			(xy 67.684094 -148.296912) (xy 67.616774 -148.273355) (xy 67.552515 -148.24241) (xy 67.492124 -148.204464)
			(xy 67.436362 -148.159995) (xy 67.385929 -148.109562) (xy 67.34146 -148.0538) (xy 67.303514 -147.993409)
			(xy 67.272569 -147.92915) (xy 67.249012 -147.86183) (xy 67.233142 -147.792295) (xy 67.225156 -147.721421)
			(xy 28.884372 -147.721421) (xy 28.884372 -148.913358) (xy 29.519874 -148.913358) (xy 29.519874 -148.826458)
			(xy 29.527892 -148.739929) (xy 29.54386 -148.654509) (xy 29.567641 -148.570927) (xy 29.599033 -148.489895)
			(xy 29.637767 -148.412106) (xy 29.683514 -148.338222) (xy 29.735883 -148.268875) (xy 29.794427 -148.204655)
			(xy 29.858647 -148.146111) (xy 29.927994 -148.093742) (xy 30.001878 -148.047995) (xy 30.079667 -148.009261)
			(xy 30.160699 -147.977869) (xy 30.244281 -147.954088) (xy 30.329701 -147.93812) (xy 30.41623 -147.930102)
			(xy 30.45968 -147.9296) (xy 30.50313 -147.930102) (xy 30.589659 -147.93812) (xy 30.675079 -147.954088)
			(xy 30.758661 -147.977869) (xy 30.839693 -148.009261) (xy 30.917482 -148.047995) (xy 30.991366 -148.093742)
			(xy 31.060713 -148.146111) (xy 31.124933 -148.204655) (xy 31.183477 -148.268875) (xy 31.235846 -148.338222)
			(xy 31.281593 -148.412106) (xy 31.320327 -148.489895) (xy 31.351719 -148.570927) (xy 31.3755 -148.654509)
			(xy 31.391468 -148.739929) (xy 31.399486 -148.826458) (xy 31.399486 -148.913358) (xy 34.599874 -148.913358)
			(xy 34.599874 -148.826458) (xy 34.607892 -148.739929) (xy 34.62386 -148.654509) (xy 34.647641 -148.570927)
			(xy 34.679033 -148.489895) (xy 34.717767 -148.412106) (xy 34.763514 -148.338222) (xy 34.815883 -148.268875)
			(xy 34.874427 -148.204655) (xy 34.938647 -148.146111) (xy 35.007994 -148.093742) (xy 35.081878 -148.047995)
			(xy 35.159667 -148.009261) (xy 35.240699 -147.977869) (xy 35.324281 -147.954088) (xy 35.409701 -147.93812)
			(xy 35.49623 -147.930102) (xy 35.53968 -147.9296) (xy 35.58313 -147.930102) (xy 35.669659 -147.93812)
			(xy 35.755079 -147.954088) (xy 35.838661 -147.977869) (xy 35.919693 -148.009261) (xy 35.997482 -148.047995)
			(xy 36.071366 -148.093742) (xy 36.140713 -148.146111) (xy 36.204933 -148.204655) (xy 36.263477 -148.268875)
			(xy 36.315846 -148.338222) (xy 36.361593 -148.412106) (xy 36.400327 -148.489895) (xy 36.431719 -148.570927)
			(xy 36.4555 -148.654509) (xy 36.471468 -148.739929) (xy 36.479486 -148.826458) (xy 36.479486 -148.913358)
			(xy 36.471468 -148.999887) (xy 36.4555 -149.085307) (xy 36.431719 -149.168889) (xy 36.400327 -149.249921)
			(xy 36.361593 -149.32771) (xy 36.315874 -149.401548) (xy 80.320133 -149.401548) (xy 80.326233 -149.346111)
			(xy 80.340339 -149.292154) (xy 80.362151 -149.240825) (xy 80.391205 -149.193219) (xy 80.42688 -149.150351)
			(xy 80.468417 -149.113134) (xy 80.51493 -149.082361) (xy 80.565427 -149.058689) (xy 80.618834 -149.042621)
			(xy 80.67401 -149.034501) (xy 80.701896 -149.033992) (xy 80.729782 -149.034501) (xy 80.784958 -149.042621)
			(xy 80.838365 -149.058689) (xy 80.888862 -149.082361) (xy 80.935375 -149.113134) (xy 80.976912 -149.150351)
			(xy 81.012587 -149.193219) (xy 81.041641 -149.240825) (xy 81.063453 -149.292154) (xy 81.077559 -149.346111)
			(xy 81.083659 -149.401548) (xy 81.081622 -149.457282) (xy 81.071492 -149.512125) (xy 81.053485 -149.564909)
			(xy 81.027984 -149.614509) (xy 81.015887 -149.631418) (xy 81.850991 -149.631418) (xy 81.857091 -149.575981)
			(xy 81.871197 -149.522024) (xy 81.893009 -149.470695) (xy 81.922063 -149.423089) (xy 81.957738 -149.380221)
			(xy 81.999275 -149.343004) (xy 82.045788 -149.312231) (xy 82.096285 -149.288559) (xy 82.149692 -149.272491)
			(xy 82.204868 -149.264371) (xy 82.232754 -149.263862) (xy 82.26064 -149.264371) (xy 82.315816 -149.272491)
			(xy 82.369223 -149.288559) (xy 82.41972 -149.312231) (xy 82.466233 -149.343004) (xy 82.50777 -149.380221)
			(xy 82.543445 -149.423089) (xy 82.572499 -149.470695) (xy 82.594311 -149.522024) (xy 82.608417 -149.575981)
			(xy 82.614517 -149.631418) (xy 82.61248 -149.687152) (xy 82.60235 -149.741995) (xy 82.584343 -149.794779)
			(xy 82.558842 -149.844379) (xy 82.526391 -149.889737) (xy 82.487682 -149.929886) (xy 82.443539 -149.963972)
			(xy 82.394904 -149.991268) (xy 82.342813 -150.011191) (xy 82.288376 -150.023317) (xy 82.232754 -150.027388)
			(xy 82.177132 -150.023317) (xy 82.122695 -150.011191) (xy 82.070604 -149.991268) (xy 82.021969 -149.963972)
			(xy 81.977826 -149.929886) (xy 81.939117 -149.889737) (xy 81.906666 -149.844379) (xy 81.881165 -149.794779)
			(xy 81.863158 -149.741995) (xy 81.853028 -149.687152) (xy 81.850991 -149.631418) (xy 81.015887 -149.631418)
			(xy 80.995533 -149.659867) (xy 80.956824 -149.700016) (xy 80.912681 -149.734102) (xy 80.864046 -149.761398)
			(xy 80.811955 -149.781321) (xy 80.757518 -149.793447) (xy 80.701896 -149.797518) (xy 80.646274 -149.793447)
			(xy 80.591837 -149.781321) (xy 80.539746 -149.761398) (xy 80.491111 -149.734102) (xy 80.446968 -149.700016)
			(xy 80.408259 -149.659867) (xy 80.375808 -149.614509) (xy 80.350307 -149.564909) (xy 80.3323 -149.512125)
			(xy 80.32217 -149.457282) (xy 80.320133 -149.401548) (xy 36.315874 -149.401548) (xy 36.315846 -149.401594)
			(xy 36.263477 -149.470941) (xy 36.204933 -149.535161) (xy 36.140713 -149.593705) (xy 36.071366 -149.646074)
			(xy 35.997482 -149.691821) (xy 35.919693 -149.730555) (xy 35.838661 -149.761947) (xy 35.755079 -149.785728)
			(xy 35.669659 -149.801696) (xy 35.58313 -149.809714) (xy 35.49623 -149.809714) (xy 35.409701 -149.801696)
			(xy 35.324281 -149.785728) (xy 35.240699 -149.761947) (xy 35.159667 -149.730555) (xy 35.081878 -149.691821)
			(xy 35.007994 -149.646074) (xy 34.938647 -149.593705) (xy 34.874427 -149.535161) (xy 34.815883 -149.470941)
			(xy 34.763514 -149.401594) (xy 34.717767 -149.32771) (xy 34.679033 -149.249921) (xy 34.647641 -149.168889)
			(xy 34.62386 -149.085307) (xy 34.607892 -148.999887) (xy 34.599874 -148.913358) (xy 31.399486 -148.913358)
			(xy 31.391468 -148.999887) (xy 31.3755 -149.085307) (xy 31.351719 -149.168889) (xy 31.320327 -149.249921)
			(xy 31.281593 -149.32771) (xy 31.235846 -149.401594) (xy 31.183477 -149.470941) (xy 31.124933 -149.535161)
			(xy 31.060713 -149.593705) (xy 30.991366 -149.646074) (xy 30.917482 -149.691821) (xy 30.839693 -149.730555)
			(xy 30.758661 -149.761947) (xy 30.675079 -149.785728) (xy 30.589659 -149.801696) (xy 30.50313 -149.809714)
			(xy 30.41623 -149.809714) (xy 30.329701 -149.801696) (xy 30.244281 -149.785728) (xy 30.160699 -149.761947)
			(xy 30.079667 -149.730555) (xy 30.001878 -149.691821) (xy 29.927994 -149.646074) (xy 29.858647 -149.593705)
			(xy 29.794427 -149.535161) (xy 29.735883 -149.470941) (xy 29.683514 -149.401594) (xy 29.637767 -149.32771)
			(xy 29.599033 -149.249921) (xy 29.567641 -149.168889) (xy 29.54386 -149.085307) (xy 29.527892 -148.999887)
			(xy 29.519874 -148.913358) (xy 28.884372 -148.913358) (xy 28.884372 -150.389691) (xy 67.225156 -150.389691)
			(xy 67.225156 -150.318369) (xy 67.233142 -150.247495) (xy 67.249012 -150.17796) (xy 67.272569 -150.11064)
			(xy 67.303514 -150.046381) (xy 67.34146 -149.98599) (xy 67.385929 -149.930228) (xy 67.436362 -149.879795)
			(xy 67.492124 -149.835326) (xy 67.552515 -149.79738) (xy 67.616774 -149.766435) (xy 67.684094 -149.742878)
			(xy 67.753629 -149.727008) (xy 67.824503 -149.719022) (xy 67.860164 -149.718522) (xy 67.895825 -149.719022)
			(xy 67.966699 -149.727008) (xy 68.036234 -149.742878) (xy 68.103554 -149.766435) (xy 68.167813 -149.79738)
			(xy 68.228204 -149.835326) (xy 68.283966 -149.879795) (xy 68.334399 -149.930228) (xy 68.378868 -149.98599)
			(xy 68.416814 -150.046381) (xy 68.447759 -150.11064) (xy 68.471316 -150.17796) (xy 68.487186 -150.247495)
			(xy 68.495172 -150.318369) (xy 68.495172 -150.389691) (xy 70.216768 -150.389691) (xy 70.216768 -150.318369)
			(xy 70.224754 -150.247495) (xy 70.240624 -150.17796) (xy 70.264181 -150.11064) (xy 70.295126 -150.046381)
			(xy 70.333072 -149.98599) (xy 70.377541 -149.930228) (xy 70.427974 -149.879795) (xy 70.483736 -149.835326)
			(xy 70.544127 -149.79738) (xy 70.608386 -149.766435) (xy 70.675706 -149.742878) (xy 70.745241 -149.727008)
			(xy 70.816115 -149.719022) (xy 70.851776 -149.718522) (xy 70.887437 -149.719022) (xy 70.958311 -149.727008)
			(xy 71.027846 -149.742878) (xy 71.095166 -149.766435) (xy 71.159425 -149.79738) (xy 71.219816 -149.835326)
			(xy 71.275578 -149.879795) (xy 71.326011 -149.930228) (xy 71.37048 -149.98599) (xy 71.408426 -150.046381)
			(xy 71.439371 -150.11064) (xy 71.462928 -150.17796) (xy 71.478798 -150.247495) (xy 71.486784 -150.318369)
			(xy 71.486784 -150.389691) (xy 71.478798 -150.460565) (xy 71.462928 -150.5301) (xy 71.439371 -150.59742)
			(xy 71.408426 -150.661679) (xy 71.389457 -150.691868) (xy 80.860645 -150.691868) (xy 80.866745 -150.636431)
			(xy 80.880851 -150.582474) (xy 80.902663 -150.531145) (xy 80.931717 -150.483539) (xy 80.967392 -150.440671)
			(xy 81.008929 -150.403454) (xy 81.055442 -150.372681) (xy 81.105939 -150.349009) (xy 81.159346 -150.332941)
			(xy 81.214522 -150.324821) (xy 81.242408 -150.324312) (xy 81.270294 -150.324821) (xy 81.32547 -150.332941)
			(xy 81.378877 -150.349009) (xy 81.429374 -150.372681) (xy 81.475887 -150.403454) (xy 81.517424 -150.440671)
			(xy 81.553099 -150.483539) (xy 81.582153 -150.531145) (xy 81.603965 -150.582474) (xy 81.618071 -150.636431)
			(xy 81.624171 -150.691868) (xy 81.622134 -150.747602) (xy 81.612004 -150.802445) (xy 81.593997 -150.855229)
			(xy 81.568496 -150.904829) (xy 81.536045 -150.950187) (xy 81.497336 -150.990336) (xy 81.453193 -151.024422)
			(xy 81.404558 -151.051718) (xy 81.352467 -151.071641) (xy 81.29803 -151.083767) (xy 81.242408 -151.087838)
			(xy 81.186786 -151.083767) (xy 81.132349 -151.071641) (xy 81.080258 -151.051718) (xy 81.031623 -151.024422)
			(xy 80.98748 -150.990336) (xy 80.948771 -150.950187) (xy 80.91632 -150.904829) (xy 80.890819 -150.855229)
			(xy 80.872812 -150.802445) (xy 80.862682 -150.747602) (xy 80.860645 -150.691868) (xy 71.389457 -150.691868)
			(xy 71.37048 -150.72207) (xy 71.326011 -150.777832) (xy 71.275578 -150.828265) (xy 71.219816 -150.872734)
			(xy 71.159425 -150.91068) (xy 71.095166 -150.941625) (xy 71.027846 -150.965182) (xy 70.958311 -150.981052)
			(xy 70.887437 -150.989038) (xy 70.816115 -150.989038) (xy 70.745241 -150.981052) (xy 70.675706 -150.965182)
			(xy 70.608386 -150.941625) (xy 70.544127 -150.91068) (xy 70.483736 -150.872734) (xy 70.427974 -150.828265)
			(xy 70.377541 -150.777832) (xy 70.333072 -150.72207) (xy 70.295126 -150.661679) (xy 70.264181 -150.59742)
			(xy 70.240624 -150.5301) (xy 70.224754 -150.460565) (xy 70.216768 -150.389691) (xy 68.495172 -150.389691)
			(xy 68.487186 -150.460565) (xy 68.471316 -150.5301) (xy 68.447759 -150.59742) (xy 68.416814 -150.661679)
			(xy 68.378868 -150.72207) (xy 68.334399 -150.777832) (xy 68.283966 -150.828265) (xy 68.228204 -150.872734)
			(xy 68.167813 -150.91068) (xy 68.103554 -150.941625) (xy 68.036234 -150.965182) (xy 67.966699 -150.981052)
			(xy 67.895825 -150.989038) (xy 67.824503 -150.989038) (xy 67.753629 -150.981052) (xy 67.684094 -150.965182)
			(xy 67.616774 -150.941625) (xy 67.552515 -150.91068) (xy 67.492124 -150.872734) (xy 67.436362 -150.828265)
			(xy 67.385929 -150.777832) (xy 67.34146 -150.72207) (xy 67.303514 -150.661679) (xy 67.272569 -150.59742)
			(xy 67.249012 -150.5301) (xy 67.233142 -150.460565) (xy 67.225156 -150.389691) (xy 28.884372 -150.389691)
			(xy 28.884372 -151.453358) (xy 29.519874 -151.453358) (xy 29.519874 -151.366458) (xy 29.527892 -151.279929)
			(xy 29.54386 -151.194509) (xy 29.567641 -151.110927) (xy 29.599033 -151.029895) (xy 29.637767 -150.952106)
			(xy 29.683514 -150.878222) (xy 29.735883 -150.808875) (xy 29.794427 -150.744655) (xy 29.858647 -150.686111)
			(xy 29.927994 -150.633742) (xy 30.001878 -150.587995) (xy 30.079667 -150.549261) (xy 30.160699 -150.517869)
			(xy 30.244281 -150.494088) (xy 30.329701 -150.47812) (xy 30.41623 -150.470102) (xy 30.45968 -150.4696)
			(xy 30.50313 -150.470102) (xy 30.589659 -150.47812) (xy 30.675079 -150.494088) (xy 30.758661 -150.517869)
			(xy 30.839693 -150.549261) (xy 30.917482 -150.587995) (xy 30.991366 -150.633742) (xy 31.060713 -150.686111)
			(xy 31.124933 -150.744655) (xy 31.183477 -150.808875) (xy 31.235846 -150.878222) (xy 31.281593 -150.952106)
			(xy 31.320327 -151.029895) (xy 31.351719 -151.110927) (xy 31.3755 -151.194509) (xy 31.391468 -151.279929)
			(xy 31.399486 -151.366458) (xy 31.399486 -151.453358) (xy 34.599874 -151.453358) (xy 34.599874 -151.366458)
			(xy 34.607892 -151.279929) (xy 34.62386 -151.194509) (xy 34.647641 -151.110927) (xy 34.679033 -151.029895)
			(xy 34.717767 -150.952106) (xy 34.763514 -150.878222) (xy 34.815883 -150.808875) (xy 34.874427 -150.744655)
			(xy 34.938647 -150.686111) (xy 35.007994 -150.633742) (xy 35.081878 -150.587995) (xy 35.159667 -150.549261)
			(xy 35.240699 -150.517869) (xy 35.324281 -150.494088) (xy 35.409701 -150.47812) (xy 35.49623 -150.470102)
			(xy 35.53968 -150.4696) (xy 35.58313 -150.470102) (xy 35.669659 -150.47812) (xy 35.755079 -150.494088)
			(xy 35.838661 -150.517869) (xy 35.919693 -150.549261) (xy 35.997482 -150.587995) (xy 36.071366 -150.633742)
			(xy 36.140713 -150.686111) (xy 36.204933 -150.744655) (xy 36.263477 -150.808875) (xy 36.315846 -150.878222)
			(xy 36.361593 -150.952106) (xy 36.400327 -151.029895) (xy 36.431719 -151.110927) (xy 36.4555 -151.194509)
			(xy 36.471468 -151.279929) (xy 36.479486 -151.366458) (xy 36.479486 -151.453358) (xy 36.471468 -151.539887)
			(xy 36.4555 -151.625307) (xy 36.431719 -151.708889) (xy 36.400327 -151.789921) (xy 36.361593 -151.86771)
			(xy 36.315846 -151.941594) (xy 36.297736 -151.965575) (xy 51.668162 -151.965575) (xy 51.668162 -151.884465)
			(xy 51.676112 -151.803746) (xy 51.691935 -151.724195) (xy 51.71548 -151.646579) (xy 51.746519 -151.571643)
			(xy 51.784754 -151.500111) (xy 51.829816 -151.432671) (xy 51.881271 -151.369972) (xy 51.938624 -151.312619)
			(xy 52.001323 -151.261164) (xy 52.068763 -151.216102) (xy 52.140295 -151.177867) (xy 52.215231 -151.146828)
			(xy 52.292847 -151.123283) (xy 52.372398 -151.10746) (xy 52.453117 -151.09951) (xy 52.493672 -151.099012)
			(xy 52.534227 -151.09951) (xy 52.614946 -151.10746) (xy 52.694497 -151.123283) (xy 52.772113 -151.146828)
			(xy 52.847049 -151.177867) (xy 52.918581 -151.216102) (xy 52.986021 -151.261164) (xy 53.04872 -151.312619)
			(xy 53.106073 -151.369972) (xy 53.157528 -151.432671) (xy 53.20259 -151.500111) (xy 53.240825 -151.571643)
			(xy 53.271864 -151.646579) (xy 53.295409 -151.724195) (xy 53.311232 -151.803746) (xy 53.319182 -151.884465)
			(xy 53.319182 -151.965575) (xy 53.311232 -152.046294) (xy 53.295409 -152.125845) (xy 53.271864 -152.203461)
			(xy 53.240825 -152.278397) (xy 53.20259 -152.349929) (xy 53.157528 -152.417369) (xy 53.106073 -152.480068)
			(xy 53.04872 -152.537421) (xy 52.986021 -152.588876) (xy 52.918581 -152.633938) (xy 52.847049 -152.672173)
			(xy 52.772113 -152.703212) (xy 52.694497 -152.726757) (xy 52.614946 -152.74258) (xy 52.534227 -152.75053)
			(xy 52.453117 -152.75053) (xy 52.372398 -152.74258) (xy 52.292847 -152.726757) (xy 52.215231 -152.703212)
			(xy 52.140295 -152.672173) (xy 52.068763 -152.633938) (xy 52.001323 -152.588876) (xy 51.938624 -152.537421)
			(xy 51.881271 -152.480068) (xy 51.829816 -152.417369) (xy 51.784754 -152.349929) (xy 51.746519 -152.278397)
			(xy 51.71548 -152.203461) (xy 51.691935 -152.125845) (xy 51.676112 -152.046294) (xy 51.668162 -151.965575)
			(xy 36.297736 -151.965575) (xy 36.263477 -152.010941) (xy 36.204933 -152.075161) (xy 36.140713 -152.133705)
			(xy 36.071366 -152.186074) (xy 35.997482 -152.231821) (xy 35.919693 -152.270555) (xy 35.838661 -152.301947)
			(xy 35.755079 -152.325728) (xy 35.669659 -152.341696) (xy 35.58313 -152.349714) (xy 35.49623 -152.349714)
			(xy 35.409701 -152.341696) (xy 35.324281 -152.325728) (xy 35.240699 -152.301947) (xy 35.159667 -152.270555)
			(xy 35.081878 -152.231821) (xy 35.007994 -152.186074) (xy 34.938647 -152.133705) (xy 34.874427 -152.075161)
			(xy 34.815883 -152.010941) (xy 34.763514 -151.941594) (xy 34.717767 -151.86771) (xy 34.679033 -151.789921)
			(xy 34.647641 -151.708889) (xy 34.62386 -151.625307) (xy 34.607892 -151.539887) (xy 34.599874 -151.453358)
			(xy 31.399486 -151.453358) (xy 31.391468 -151.539887) (xy 31.3755 -151.625307) (xy 31.351719 -151.708889)
			(xy 31.320327 -151.789921) (xy 31.281593 -151.86771) (xy 31.235846 -151.941594) (xy 31.183477 -152.010941)
			(xy 31.124933 -152.075161) (xy 31.060713 -152.133705) (xy 30.991366 -152.186074) (xy 30.917482 -152.231821)
			(xy 30.839693 -152.270555) (xy 30.758661 -152.301947) (xy 30.675079 -152.325728) (xy 30.589659 -152.341696)
			(xy 30.50313 -152.349714) (xy 30.41623 -152.349714) (xy 30.329701 -152.341696) (xy 30.244281 -152.325728)
			(xy 30.160699 -152.301947) (xy 30.079667 -152.270555) (xy 30.001878 -152.231821) (xy 29.927994 -152.186074)
			(xy 29.858647 -152.133705) (xy 29.794427 -152.075161) (xy 29.735883 -152.010941) (xy 29.683514 -151.941594)
			(xy 29.637767 -151.86771) (xy 29.599033 -151.789921) (xy 29.567641 -151.708889) (xy 29.54386 -151.625307)
			(xy 29.527892 -151.539887) (xy 29.519874 -151.453358) (xy 28.884372 -151.453358) (xy 28.884372 -152.761289)
			(xy 67.225156 -152.761289) (xy 67.225156 -152.689967) (xy 67.233142 -152.619093) (xy 67.249012 -152.549558)
			(xy 67.272569 -152.482238) (xy 67.303514 -152.417979) (xy 67.34146 -152.357588) (xy 67.385929 -152.301826)
			(xy 67.436362 -152.251393) (xy 67.492124 -152.206924) (xy 67.552515 -152.168978) (xy 67.616774 -152.138033)
			(xy 67.684094 -152.114476) (xy 67.753629 -152.098606) (xy 67.824503 -152.09062) (xy 67.860164 -152.09012)
			(xy 67.895825 -152.09062) (xy 67.966699 -152.098606) (xy 68.036234 -152.114476) (xy 68.103554 -152.138033)
			(xy 68.167813 -152.168978) (xy 68.228204 -152.206924) (xy 68.283966 -152.251393) (xy 68.334399 -152.301826)
			(xy 68.378868 -152.357588) (xy 68.416814 -152.417979) (xy 68.447759 -152.482238) (xy 68.471316 -152.549558)
			(xy 68.487186 -152.619093) (xy 68.495172 -152.689967) (xy 68.495172 -152.761289) (xy 70.216768 -152.761289)
			(xy 70.216768 -152.689967) (xy 70.224754 -152.619093) (xy 70.240624 -152.549558) (xy 70.264181 -152.482238)
			(xy 70.295126 -152.417979) (xy 70.333072 -152.357588) (xy 70.377541 -152.301826) (xy 70.427974 -152.251393)
			(xy 70.483736 -152.206924) (xy 70.544127 -152.168978) (xy 70.608386 -152.138033) (xy 70.675706 -152.114476)
			(xy 70.745241 -152.098606) (xy 70.816115 -152.09062) (xy 70.851776 -152.09012) (xy 70.887437 -152.09062)
			(xy 70.958311 -152.098606) (xy 71.027846 -152.114476) (xy 71.095166 -152.138033) (xy 71.104363 -152.142462)
			(xy 81.340705 -152.142462) (xy 81.346805 -152.087025) (xy 81.360911 -152.033068) (xy 81.382723 -151.981739)
			(xy 81.411777 -151.934133) (xy 81.447452 -151.891265) (xy 81.488989 -151.854048) (xy 81.535502 -151.823275)
			(xy 81.585999 -151.799603) (xy 81.639406 -151.783535) (xy 81.694582 -151.775415) (xy 81.722468 -151.774906)
			(xy 81.750354 -151.775415) (xy 81.80553 -151.783535) (xy 81.858937 -151.799603) (xy 81.909434 -151.823275)
			(xy 81.955947 -151.854048) (xy 81.997484 -151.891265) (xy 82.033159 -151.934133) (xy 82.062213 -151.981739)
			(xy 82.084025 -152.033068) (xy 82.098131 -152.087025) (xy 82.104231 -152.142462) (xy 82.102194 -152.198196)
			(xy 82.092064 -152.253039) (xy 82.074057 -152.305823) (xy 82.048556 -152.355423) (xy 82.016105 -152.400781)
			(xy 81.977396 -152.44093) (xy 81.933253 -152.475016) (xy 81.884618 -152.502312) (xy 81.832527 -152.522235)
			(xy 81.77809 -152.534361) (xy 81.722468 -152.538432) (xy 81.666846 -152.534361) (xy 81.612409 -152.522235)
			(xy 81.560318 -152.502312) (xy 81.511683 -152.475016) (xy 81.46754 -152.44093) (xy 81.428831 -152.400781)
			(xy 81.39638 -152.355423) (xy 81.370879 -152.305823) (xy 81.352872 -152.253039) (xy 81.342742 -152.198196)
			(xy 81.340705 -152.142462) (xy 71.104363 -152.142462) (xy 71.159425 -152.168978) (xy 71.219816 -152.206924)
			(xy 71.275578 -152.251393) (xy 71.326011 -152.301826) (xy 71.37048 -152.357588) (xy 71.408426 -152.417979)
			(xy 71.439371 -152.482238) (xy 71.462928 -152.549558) (xy 71.478798 -152.619093) (xy 71.486784 -152.689967)
			(xy 71.486784 -152.761289) (xy 71.478798 -152.832163) (xy 71.462928 -152.901698) (xy 71.439371 -152.969018)
			(xy 71.408426 -153.033277) (xy 71.37048 -153.093668) (xy 71.326011 -153.14943) (xy 71.275578 -153.199863)
			(xy 71.219816 -153.244332) (xy 71.159425 -153.282278) (xy 71.095166 -153.313223) (xy 71.027846 -153.33678)
			(xy 70.958311 -153.35265) (xy 70.887437 -153.360636) (xy 70.816115 -153.360636) (xy 70.745241 -153.35265)
			(xy 70.675706 -153.33678) (xy 70.608386 -153.313223) (xy 70.544127 -153.282278) (xy 70.483736 -153.244332)
			(xy 70.427974 -153.199863) (xy 70.377541 -153.14943) (xy 70.333072 -153.093668) (xy 70.295126 -153.033277)
			(xy 70.264181 -152.969018) (xy 70.240624 -152.901698) (xy 70.224754 -152.832163) (xy 70.216768 -152.761289)
			(xy 68.495172 -152.761289) (xy 68.487186 -152.832163) (xy 68.471316 -152.901698) (xy 68.447759 -152.969018)
			(xy 68.416814 -153.033277) (xy 68.378868 -153.093668) (xy 68.334399 -153.14943) (xy 68.283966 -153.199863)
			(xy 68.228204 -153.244332) (xy 68.167813 -153.282278) (xy 68.103554 -153.313223) (xy 68.036234 -153.33678)
			(xy 67.966699 -153.35265) (xy 67.895825 -153.360636) (xy 67.824503 -153.360636) (xy 67.753629 -153.35265)
			(xy 67.684094 -153.33678) (xy 67.616774 -153.313223) (xy 67.552515 -153.282278) (xy 67.492124 -153.244332)
			(xy 67.436362 -153.199863) (xy 67.385929 -153.14943) (xy 67.34146 -153.093668) (xy 67.303514 -153.033277)
			(xy 67.272569 -152.969018) (xy 67.249012 -152.901698) (xy 67.233142 -152.832163) (xy 67.225156 -152.761289)
			(xy 28.884372 -152.761289) (xy 28.884372 -153.993358) (xy 29.519874 -153.993358) (xy 29.519874 -153.906458)
			(xy 29.527892 -153.819929) (xy 29.54386 -153.734509) (xy 29.567641 -153.650927) (xy 29.599033 -153.569895)
			(xy 29.637767 -153.492106) (xy 29.683514 -153.418222) (xy 29.735883 -153.348875) (xy 29.794427 -153.284655)
			(xy 29.858647 -153.226111) (xy 29.927994 -153.173742) (xy 30.001878 -153.127995) (xy 30.079667 -153.089261)
			(xy 30.160699 -153.057869) (xy 30.244281 -153.034088) (xy 30.329701 -153.01812) (xy 30.41623 -153.010102)
			(xy 30.45968 -153.0096) (xy 30.50313 -153.010102) (xy 30.589659 -153.01812) (xy 30.675079 -153.034088)
			(xy 30.758661 -153.057869) (xy 30.839693 -153.089261) (xy 30.917482 -153.127995) (xy 30.991366 -153.173742)
			(xy 31.060713 -153.226111) (xy 31.124933 -153.284655) (xy 31.183477 -153.348875) (xy 31.235846 -153.418222)
			(xy 31.281593 -153.492106) (xy 31.320327 -153.569895) (xy 31.351719 -153.650927) (xy 31.3755 -153.734509)
			(xy 31.391468 -153.819929) (xy 31.399486 -153.906458) (xy 31.399486 -153.993358) (xy 34.599874 -153.993358)
			(xy 34.599874 -153.906458) (xy 34.607892 -153.819929) (xy 34.62386 -153.734509) (xy 34.647641 -153.650927)
			(xy 34.679033 -153.569895) (xy 34.717767 -153.492106) (xy 34.763514 -153.418222) (xy 34.815883 -153.348875)
			(xy 34.874427 -153.284655) (xy 34.938647 -153.226111) (xy 35.007994 -153.173742) (xy 35.081878 -153.127995)
			(xy 35.159667 -153.089261) (xy 35.240699 -153.057869) (xy 35.324281 -153.034088) (xy 35.409701 -153.01812)
			(xy 35.49623 -153.010102) (xy 35.53968 -153.0096) (xy 35.58313 -153.010102) (xy 35.669659 -153.01812)
			(xy 35.755079 -153.034088) (xy 35.838661 -153.057869) (xy 35.919693 -153.089261) (xy 35.997482 -153.127995)
			(xy 36.071366 -153.173742) (xy 36.140713 -153.226111) (xy 36.204933 -153.284655) (xy 36.263477 -153.348875)
			(xy 36.315846 -153.418222) (xy 36.361593 -153.492106) (xy 36.400327 -153.569895) (xy 36.430586 -153.648003)
			(xy 39.31208 -153.648003) (xy 39.31208 -153.576681) (xy 39.320066 -153.505807) (xy 39.335936 -153.436272)
			(xy 39.359493 -153.368952) (xy 39.390438 -153.304693) (xy 39.428384 -153.244302) (xy 39.472853 -153.18854)
			(xy 39.523286 -153.138107) (xy 39.579048 -153.093638) (xy 39.639439 -153.055692) (xy 39.703698 -153.024747)
			(xy 39.771018 -153.00119) (xy 39.840553 -152.98532) (xy 39.911427 -152.977334) (xy 39.947088 -152.976834)
			(xy 39.982749 -152.977334) (xy 40.053623 -152.98532) (xy 40.123158 -153.00119) (xy 40.190478 -153.024747)
			(xy 40.254737 -153.055692) (xy 40.315128 -153.093638) (xy 40.37089 -153.138107) (xy 40.421323 -153.18854)
			(xy 40.465792 -153.244302) (xy 40.503738 -153.304693) (xy 40.534683 -153.368952) (xy 40.55824 -153.436272)
			(xy 40.57411 -153.505807) (xy 40.582096 -153.576681) (xy 40.582096 -153.648003) (xy 40.57411 -153.718877)
			(xy 40.55824 -153.788412) (xy 40.534683 -153.855732) (xy 40.503738 -153.919991) (xy 40.465792 -153.980382)
			(xy 40.421323 -154.036144) (xy 40.37089 -154.086577) (xy 40.315128 -154.131046) (xy 40.254737 -154.168992)
			(xy 40.190478 -154.199937) (xy 40.123158 -154.223494) (xy 40.053623 -154.239364) (xy 39.982749 -154.24735)
			(xy 39.911427 -154.24735) (xy 39.840553 -154.239364) (xy 39.771018 -154.223494) (xy 39.703698 -154.199937)
			(xy 39.639439 -154.168992) (xy 39.579048 -154.131046) (xy 39.523286 -154.086577) (xy 39.472853 -154.036144)
			(xy 39.428384 -153.980382) (xy 39.390438 -153.919991) (xy 39.359493 -153.855732) (xy 39.335936 -153.788412)
			(xy 39.320066 -153.718877) (xy 39.31208 -153.648003) (xy 36.430586 -153.648003) (xy 36.431719 -153.650927)
			(xy 36.4555 -153.734509) (xy 36.471468 -153.819929) (xy 36.479486 -153.906458) (xy 36.479486 -153.993358)
			(xy 36.471468 -154.079887) (xy 36.4555 -154.165307) (xy 36.431719 -154.248889) (xy 36.400327 -154.329921)
			(xy 36.361593 -154.40771) (xy 36.315846 -154.481594) (xy 36.263477 -154.550941) (xy 36.204933 -154.615161)
			(xy 36.140713 -154.673705) (xy 36.073846 -154.724201) (xy 67.225156 -154.724201) (xy 67.225156 -154.652879)
			(xy 67.233142 -154.582005) (xy 67.249012 -154.51247) (xy 67.272569 -154.44515) (xy 67.303514 -154.380891)
			(xy 67.34146 -154.3205) (xy 67.385929 -154.264738) (xy 67.436362 -154.214305) (xy 67.492124 -154.169836)
			(xy 67.552515 -154.13189) (xy 67.616774 -154.100945) (xy 67.684094 -154.077388) (xy 67.753629 -154.061518)
			(xy 67.824503 -154.053532) (xy 67.860164 -154.053032) (xy 67.895825 -154.053532) (xy 67.966699 -154.061518)
			(xy 68.036234 -154.077388) (xy 68.103554 -154.100945) (xy 68.167813 -154.13189) (xy 68.228204 -154.169836)
			(xy 68.283966 -154.214305) (xy 68.334399 -154.264738) (xy 68.378868 -154.3205) (xy 68.416814 -154.380891)
			(xy 68.447759 -154.44515) (xy 68.471316 -154.51247) (xy 68.487186 -154.582005) (xy 68.495172 -154.652879)
			(xy 68.495172 -154.724201) (xy 70.216768 -154.724201) (xy 70.216768 -154.652879) (xy 70.224754 -154.582005)
			(xy 70.240624 -154.51247) (xy 70.264181 -154.44515) (xy 70.295126 -154.380891) (xy 70.333072 -154.3205)
			(xy 70.377541 -154.264738) (xy 70.427974 -154.214305) (xy 70.483736 -154.169836) (xy 70.544127 -154.13189)
			(xy 70.608386 -154.100945) (xy 70.675706 -154.077388) (xy 70.745241 -154.061518) (xy 70.816115 -154.053532)
			(xy 70.851776 -154.053032) (xy 70.887437 -154.053532) (xy 70.958311 -154.061518) (xy 71.027846 -154.077388)
			(xy 71.095166 -154.100945) (xy 71.159425 -154.13189) (xy 71.219816 -154.169836) (xy 71.275578 -154.214305)
			(xy 71.326011 -154.264738) (xy 71.37048 -154.3205) (xy 71.408426 -154.380891) (xy 71.439371 -154.44515)
			(xy 71.462928 -154.51247) (xy 71.478798 -154.582005) (xy 71.486784 -154.652879) (xy 71.486784 -154.724201)
			(xy 71.478798 -154.795075) (xy 71.462928 -154.86461) (xy 71.439371 -154.93193) (xy 71.408426 -154.996189)
			(xy 71.37048 -155.05658) (xy 71.326011 -155.112342) (xy 71.275578 -155.162775) (xy 71.219816 -155.207244)
			(xy 71.159425 -155.24519) (xy 71.095166 -155.276135) (xy 71.027846 -155.299692) (xy 70.958311 -155.315562)
			(xy 70.887437 -155.323548) (xy 70.816115 -155.323548) (xy 70.745241 -155.315562) (xy 70.675706 -155.299692)
			(xy 70.608386 -155.276135) (xy 70.544127 -155.24519) (xy 70.483736 -155.207244) (xy 70.427974 -155.162775)
			(xy 70.377541 -155.112342) (xy 70.333072 -155.05658) (xy 70.295126 -154.996189) (xy 70.264181 -154.93193)
			(xy 70.240624 -154.86461) (xy 70.224754 -154.795075) (xy 70.216768 -154.724201) (xy 68.495172 -154.724201)
			(xy 68.487186 -154.795075) (xy 68.471316 -154.86461) (xy 68.447759 -154.93193) (xy 68.416814 -154.996189)
			(xy 68.378868 -155.05658) (xy 68.334399 -155.112342) (xy 68.283966 -155.162775) (xy 68.228204 -155.207244)
			(xy 68.167813 -155.24519) (xy 68.103554 -155.276135) (xy 68.036234 -155.299692) (xy 67.966699 -155.315562)
			(xy 67.895825 -155.323548) (xy 67.824503 -155.323548) (xy 67.753629 -155.315562) (xy 67.684094 -155.299692)
			(xy 67.616774 -155.276135) (xy 67.552515 -155.24519) (xy 67.492124 -155.207244) (xy 67.436362 -155.162775)
			(xy 67.385929 -155.112342) (xy 67.34146 -155.05658) (xy 67.303514 -154.996189) (xy 67.272569 -154.93193)
			(xy 67.249012 -154.86461) (xy 67.233142 -154.795075) (xy 67.225156 -154.724201) (xy 36.073846 -154.724201)
			(xy 36.071366 -154.726074) (xy 35.997482 -154.771821) (xy 35.919693 -154.810555) (xy 35.838661 -154.841947)
			(xy 35.755079 -154.865728) (xy 35.669659 -154.881696) (xy 35.58313 -154.889714) (xy 35.49623 -154.889714)
			(xy 35.409701 -154.881696) (xy 35.324281 -154.865728) (xy 35.240699 -154.841947) (xy 35.159667 -154.810555)
			(xy 35.081878 -154.771821) (xy 35.007994 -154.726074) (xy 34.938647 -154.673705) (xy 34.874427 -154.615161)
			(xy 34.815883 -154.550941) (xy 34.763514 -154.481594) (xy 34.717767 -154.40771) (xy 34.679033 -154.329921)
			(xy 34.647641 -154.248889) (xy 34.62386 -154.165307) (xy 34.607892 -154.079887) (xy 34.599874 -153.993358)
			(xy 31.399486 -153.993358) (xy 31.391468 -154.079887) (xy 31.3755 -154.165307) (xy 31.351719 -154.248889)
			(xy 31.320327 -154.329921) (xy 31.281593 -154.40771) (xy 31.235846 -154.481594) (xy 31.183477 -154.550941)
			(xy 31.124933 -154.615161) (xy 31.060713 -154.673705) (xy 30.991366 -154.726074) (xy 30.917482 -154.771821)
			(xy 30.839693 -154.810555) (xy 30.758661 -154.841947) (xy 30.675079 -154.865728) (xy 30.589659 -154.881696)
			(xy 30.50313 -154.889714) (xy 30.41623 -154.889714) (xy 30.329701 -154.881696) (xy 30.244281 -154.865728)
			(xy 30.160699 -154.841947) (xy 30.079667 -154.810555) (xy 30.001878 -154.771821) (xy 29.927994 -154.726074)
			(xy 29.858647 -154.673705) (xy 29.794427 -154.615161) (xy 29.735883 -154.550941) (xy 29.683514 -154.481594)
			(xy 29.637767 -154.40771) (xy 29.599033 -154.329921) (xy 29.567641 -154.248889) (xy 29.54386 -154.165307)
			(xy 29.527892 -154.079887) (xy 29.519874 -153.993358) (xy 28.884372 -153.993358) (xy 28.884372 -156.533358)
			(xy 29.519874 -156.533358) (xy 29.519874 -156.446458) (xy 29.527892 -156.359929) (xy 29.54386 -156.274509)
			(xy 29.567641 -156.190927) (xy 29.599033 -156.109895) (xy 29.637767 -156.032106) (xy 29.683514 -155.958222)
			(xy 29.735883 -155.888875) (xy 29.794427 -155.824655) (xy 29.858647 -155.766111) (xy 29.927994 -155.713742)
			(xy 30.001878 -155.667995) (xy 30.079667 -155.629261) (xy 30.160699 -155.597869) (xy 30.244281 -155.574088)
			(xy 30.329701 -155.55812) (xy 30.41623 -155.550102) (xy 30.45968 -155.5496) (xy 30.50313 -155.550102)
			(xy 30.589659 -155.55812) (xy 30.675079 -155.574088) (xy 30.758661 -155.597869) (xy 30.839693 -155.629261)
			(xy 30.917482 -155.667995) (xy 30.991366 -155.713742) (xy 31.060713 -155.766111) (xy 31.124933 -155.824655)
			(xy 31.183477 -155.888875) (xy 31.235846 -155.958222) (xy 31.281593 -156.032106) (xy 31.320327 -156.109895)
			(xy 31.351719 -156.190927) (xy 31.3755 -156.274509) (xy 31.391468 -156.359929) (xy 31.399486 -156.446458)
			(xy 31.399486 -156.533358) (xy 34.599874 -156.533358) (xy 34.599874 -156.446458) (xy 34.607892 -156.359929)
			(xy 34.62386 -156.274509) (xy 34.647641 -156.190927) (xy 34.679033 -156.109895) (xy 34.717767 -156.032106)
			(xy 34.763514 -155.958222) (xy 34.815883 -155.888875) (xy 34.874427 -155.824655) (xy 34.938647 -155.766111)
			(xy 35.007994 -155.713742) (xy 35.081878 -155.667995) (xy 35.159667 -155.629261) (xy 35.240699 -155.597869)
			(xy 35.324281 -155.574088) (xy 35.409701 -155.55812) (xy 35.49623 -155.550102) (xy 35.53968 -155.5496)
			(xy 35.58313 -155.550102) (xy 35.669659 -155.55812) (xy 35.755079 -155.574088) (xy 35.838661 -155.597869)
			(xy 35.919693 -155.629261) (xy 35.997482 -155.667995) (xy 36.071366 -155.713742) (xy 36.140713 -155.766111)
			(xy 36.204933 -155.824655) (xy 36.258538 -155.883457) (xy 39.31208 -155.883457) (xy 39.31208 -155.812135)
			(xy 39.320066 -155.741261) (xy 39.335936 -155.671726) (xy 39.359493 -155.604406) (xy 39.390438 -155.540147)
			(xy 39.428384 -155.479756) (xy 39.472853 -155.423994) (xy 39.523286 -155.373561) (xy 39.579048 -155.329092)
			(xy 39.639439 -155.291146) (xy 39.703698 -155.260201) (xy 39.771018 -155.236644) (xy 39.840553 -155.220774)
			(xy 39.911427 -155.212788) (xy 39.947088 -155.212288) (xy 39.982749 -155.212788) (xy 40.053623 -155.220774)
			(xy 40.123158 -155.236644) (xy 40.190478 -155.260201) (xy 40.254737 -155.291146) (xy 40.315128 -155.329092)
			(xy 40.37089 -155.373561) (xy 40.421323 -155.423994) (xy 40.465792 -155.479756) (xy 40.503738 -155.540147)
			(xy 40.534683 -155.604406) (xy 40.55824 -155.671726) (xy 40.57411 -155.741261) (xy 40.582096 -155.812135)
			(xy 40.582096 -155.883457) (xy 40.57411 -155.954331) (xy 40.55824 -156.023866) (xy 40.534683 -156.091186)
			(xy 40.503738 -156.155445) (xy 40.465792 -156.215836) (xy 40.421323 -156.271598) (xy 40.37089 -156.322031)
			(xy 40.315128 -156.3665) (xy 40.254737 -156.404446) (xy 40.190478 -156.435391) (xy 40.123158 -156.458948)
			(xy 40.053623 -156.474818) (xy 39.982749 -156.482804) (xy 39.911427 -156.482804) (xy 39.840553 -156.474818)
			(xy 39.771018 -156.458948) (xy 39.703698 -156.435391) (xy 39.639439 -156.404446) (xy 39.579048 -156.3665)
			(xy 39.523286 -156.322031) (xy 39.472853 -156.271598) (xy 39.428384 -156.215836) (xy 39.390438 -156.155445)
			(xy 39.359493 -156.091186) (xy 39.335936 -156.023866) (xy 39.320066 -155.954331) (xy 39.31208 -155.883457)
			(xy 36.258538 -155.883457) (xy 36.263477 -155.888875) (xy 36.315846 -155.958222) (xy 36.361593 -156.032106)
			(xy 36.400327 -156.109895) (xy 36.431719 -156.190927) (xy 36.4555 -156.274509) (xy 36.471468 -156.359929)
			(xy 36.479486 -156.446458) (xy 36.479486 -156.533358) (xy 36.471468 -156.619887) (xy 36.4555 -156.705307)
			(xy 36.431719 -156.788889) (xy 36.401185 -156.867707) (xy 67.225156 -156.867707) (xy 67.225156 -156.796385)
			(xy 67.233142 -156.725511) (xy 67.249012 -156.655976) (xy 67.272569 -156.588656) (xy 67.303514 -156.524397)
			(xy 67.34146 -156.464006) (xy 67.385929 -156.408244) (xy 67.436362 -156.357811) (xy 67.492124 -156.313342)
			(xy 67.552515 -156.275396) (xy 67.616774 -156.244451) (xy 67.684094 -156.220894) (xy 67.753629 -156.205024)
			(xy 67.824503 -156.197038) (xy 67.860164 -156.196538) (xy 67.895825 -156.197038) (xy 67.966699 -156.205024)
			(xy 68.036234 -156.220894) (xy 68.103554 -156.244451) (xy 68.167813 -156.275396) (xy 68.228204 -156.313342)
			(xy 68.283966 -156.357811) (xy 68.334399 -156.408244) (xy 68.378868 -156.464006) (xy 68.416814 -156.524397)
			(xy 68.447759 -156.588656) (xy 68.471316 -156.655976) (xy 68.487186 -156.725511) (xy 68.495172 -156.796385)
			(xy 68.495172 -156.867707) (xy 70.216768 -156.867707) (xy 70.216768 -156.796385) (xy 70.224754 -156.725511)
			(xy 70.240624 -156.655976) (xy 70.264181 -156.588656) (xy 70.295126 -156.524397) (xy 70.333072 -156.464006)
			(xy 70.377541 -156.408244) (xy 70.427974 -156.357811) (xy 70.483736 -156.313342) (xy 70.544127 -156.275396)
			(xy 70.608386 -156.244451) (xy 70.675706 -156.220894) (xy 70.745241 -156.205024) (xy 70.816115 -156.197038)
			(xy 70.851776 -156.196538) (xy 70.887437 -156.197038) (xy 70.958311 -156.205024) (xy 71.027846 -156.220894)
			(xy 71.095166 -156.244451) (xy 71.159425 -156.275396) (xy 71.219816 -156.313342) (xy 71.275578 -156.357811)
			(xy 71.326011 -156.408244) (xy 71.37048 -156.464006) (xy 71.408426 -156.524397) (xy 71.439371 -156.588656)
			(xy 71.462928 -156.655976) (xy 71.478798 -156.725511) (xy 71.486784 -156.796385) (xy 71.486784 -156.867707)
			(xy 71.478798 -156.938581) (xy 71.462928 -157.008116) (xy 71.439371 -157.075436) (xy 71.408426 -157.139695)
			(xy 71.37048 -157.200086) (xy 71.326011 -157.255848) (xy 71.275578 -157.306281) (xy 71.219816 -157.35075)
			(xy 71.159425 -157.388696) (xy 71.095166 -157.419641) (xy 71.027846 -157.443198) (xy 70.958311 -157.459068)
			(xy 70.887437 -157.467054) (xy 70.816115 -157.467054) (xy 70.745241 -157.459068) (xy 70.675706 -157.443198)
			(xy 70.608386 -157.419641) (xy 70.544127 -157.388696) (xy 70.483736 -157.35075) (xy 70.427974 -157.306281)
			(xy 70.377541 -157.255848) (xy 70.333072 -157.200086) (xy 70.295126 -157.139695) (xy 70.264181 -157.075436)
			(xy 70.240624 -157.008116) (xy 70.224754 -156.938581) (xy 70.216768 -156.867707) (xy 68.495172 -156.867707)
			(xy 68.487186 -156.938581) (xy 68.471316 -157.008116) (xy 68.447759 -157.075436) (xy 68.416814 -157.139695)
			(xy 68.378868 -157.200086) (xy 68.334399 -157.255848) (xy 68.283966 -157.306281) (xy 68.228204 -157.35075)
			(xy 68.167813 -157.388696) (xy 68.103554 -157.419641) (xy 68.036234 -157.443198) (xy 67.966699 -157.459068)
			(xy 67.895825 -157.467054) (xy 67.824503 -157.467054) (xy 67.753629 -157.459068) (xy 67.684094 -157.443198)
			(xy 67.616774 -157.419641) (xy 67.552515 -157.388696) (xy 67.492124 -157.35075) (xy 67.436362 -157.306281)
			(xy 67.385929 -157.255848) (xy 67.34146 -157.200086) (xy 67.303514 -157.139695) (xy 67.272569 -157.075436)
			(xy 67.249012 -157.008116) (xy 67.233142 -156.938581) (xy 67.225156 -156.867707) (xy 36.401185 -156.867707)
			(xy 36.400327 -156.869921) (xy 36.361593 -156.94771) (xy 36.315846 -157.021594) (xy 36.263477 -157.090941)
			(xy 36.204933 -157.155161) (xy 36.140713 -157.213705) (xy 36.071366 -157.266074) (xy 35.997482 -157.311821)
			(xy 35.919693 -157.350555) (xy 35.838661 -157.381947) (xy 35.755079 -157.405728) (xy 35.669659 -157.421696)
			(xy 35.58313 -157.429714) (xy 35.49623 -157.429714) (xy 35.409701 -157.421696) (xy 35.324281 -157.405728)
			(xy 35.240699 -157.381947) (xy 35.159667 -157.350555) (xy 35.081878 -157.311821) (xy 35.007994 -157.266074)
			(xy 34.938647 -157.213705) (xy 34.874427 -157.155161) (xy 34.815883 -157.090941) (xy 34.763514 -157.021594)
			(xy 34.717767 -156.94771) (xy 34.679033 -156.869921) (xy 34.647641 -156.788889) (xy 34.62386 -156.705307)
			(xy 34.607892 -156.619887) (xy 34.599874 -156.533358) (xy 31.399486 -156.533358) (xy 31.391468 -156.619887)
			(xy 31.3755 -156.705307) (xy 31.351719 -156.788889) (xy 31.320327 -156.869921) (xy 31.281593 -156.94771)
			(xy 31.235846 -157.021594) (xy 31.183477 -157.090941) (xy 31.124933 -157.155161) (xy 31.060713 -157.213705)
			(xy 30.991366 -157.266074) (xy 30.917482 -157.311821) (xy 30.839693 -157.350555) (xy 30.758661 -157.381947)
			(xy 30.675079 -157.405728) (xy 30.589659 -157.421696) (xy 30.50313 -157.429714) (xy 30.41623 -157.429714)
			(xy 30.329701 -157.421696) (xy 30.244281 -157.405728) (xy 30.160699 -157.381947) (xy 30.079667 -157.350555)
			(xy 30.001878 -157.311821) (xy 29.927994 -157.266074) (xy 29.858647 -157.213705) (xy 29.794427 -157.155161)
			(xy 29.735883 -157.090941) (xy 29.683514 -157.021594) (xy 29.637767 -156.94771) (xy 29.599033 -156.869921)
			(xy 29.567641 -156.788889) (xy 29.54386 -156.705307) (xy 29.527892 -156.619887) (xy 29.519874 -156.533358)
			(xy 28.884372 -156.533358) (xy 28.884372 -159.073358) (xy 29.519874 -159.073358) (xy 29.519874 -158.986458)
			(xy 29.527892 -158.899929) (xy 29.54386 -158.814509) (xy 29.567641 -158.730927) (xy 29.599033 -158.649895)
			(xy 29.637767 -158.572106) (xy 29.683514 -158.498222) (xy 29.735883 -158.428875) (xy 29.794427 -158.364655)
			(xy 29.858647 -158.306111) (xy 29.927994 -158.253742) (xy 30.001878 -158.207995) (xy 30.079667 -158.169261)
			(xy 30.160699 -158.137869) (xy 30.244281 -158.114088) (xy 30.329701 -158.09812) (xy 30.41623 -158.090102)
			(xy 30.45968 -158.0896) (xy 30.50313 -158.090102) (xy 30.589659 -158.09812) (xy 30.675079 -158.114088)
			(xy 30.758661 -158.137869) (xy 30.839693 -158.169261) (xy 30.917482 -158.207995) (xy 30.991366 -158.253742)
			(xy 31.060713 -158.306111) (xy 31.124933 -158.364655) (xy 31.183477 -158.428875) (xy 31.235846 -158.498222)
			(xy 31.281593 -158.572106) (xy 31.320327 -158.649895) (xy 31.351719 -158.730927) (xy 31.3755 -158.814509)
			(xy 31.391468 -158.899929) (xy 31.399486 -158.986458) (xy 31.399486 -159.073358) (xy 34.599874 -159.073358)
			(xy 34.599874 -158.986458) (xy 34.607892 -158.899929) (xy 34.62386 -158.814509) (xy 34.647641 -158.730927)
			(xy 34.679033 -158.649895) (xy 34.717767 -158.572106) (xy 34.763514 -158.498222) (xy 34.815883 -158.428875)
			(xy 34.874427 -158.364655) (xy 34.938647 -158.306111) (xy 35.007994 -158.253742) (xy 35.081878 -158.207995)
			(xy 35.159667 -158.169261) (xy 35.240699 -158.137869) (xy 35.324281 -158.114088) (xy 35.409701 -158.09812)
			(xy 35.49623 -158.090102) (xy 35.53968 -158.0896) (xy 35.58313 -158.090102) (xy 35.669659 -158.09812)
			(xy 35.755079 -158.114088) (xy 35.838661 -158.137869) (xy 35.919693 -158.169261) (xy 35.997482 -158.207995)
			(xy 36.071366 -158.253742) (xy 36.140713 -158.306111) (xy 36.204933 -158.364655) (xy 36.263477 -158.428875)
			(xy 36.315846 -158.498222) (xy 36.348975 -158.551727) (xy 39.31208 -158.551727) (xy 39.31208 -158.480405)
			(xy 39.320066 -158.409531) (xy 39.335936 -158.339996) (xy 39.359493 -158.272676) (xy 39.390438 -158.208417)
			(xy 39.428384 -158.148026) (xy 39.472853 -158.092264) (xy 39.523286 -158.041831) (xy 39.579048 -157.997362)
			(xy 39.639439 -157.959416) (xy 39.703698 -157.928471) (xy 39.771018 -157.904914) (xy 39.840553 -157.889044)
			(xy 39.911427 -157.881058) (xy 39.947088 -157.880558) (xy 39.982749 -157.881058) (xy 40.053623 -157.889044)
			(xy 40.123158 -157.904914) (xy 40.190478 -157.928471) (xy 40.254737 -157.959416) (xy 40.315128 -157.997362)
			(xy 40.37089 -158.041831) (xy 40.421323 -158.092264) (xy 40.465792 -158.148026) (xy 40.503738 -158.208417)
			(xy 40.534683 -158.272676) (xy 40.55824 -158.339996) (xy 40.57411 -158.409531) (xy 40.582096 -158.480405)
			(xy 40.582096 -158.551727) (xy 40.57411 -158.622601) (xy 40.55824 -158.692136) (xy 40.534683 -158.759456)
			(xy 40.503738 -158.823715) (xy 40.465792 -158.884106) (xy 40.421323 -158.939868) (xy 40.37089 -158.990301)
			(xy 40.315128 -159.03477) (xy 40.254737 -159.072716) (xy 40.190478 -159.103661) (xy 40.123158 -159.127218)
			(xy 40.053623 -159.143088) (xy 39.982749 -159.151074) (xy 39.911427 -159.151074) (xy 39.840553 -159.143088)
			(xy 39.771018 -159.127218) (xy 39.703698 -159.103661) (xy 39.639439 -159.072716) (xy 39.579048 -159.03477)
			(xy 39.523286 -158.990301) (xy 39.472853 -158.939868) (xy 39.428384 -158.884106) (xy 39.390438 -158.823715)
			(xy 39.359493 -158.759456) (xy 39.335936 -158.692136) (xy 39.320066 -158.622601) (xy 39.31208 -158.551727)
			(xy 36.348975 -158.551727) (xy 36.361593 -158.572106) (xy 36.400327 -158.649895) (xy 36.431719 -158.730927)
			(xy 36.4555 -158.814509) (xy 36.471468 -158.899929) (xy 36.479486 -158.986458) (xy 36.479486 -159.073358)
			(xy 36.471468 -159.159887) (xy 36.4555 -159.245307) (xy 36.431719 -159.328889) (xy 36.400327 -159.409921)
			(xy 36.361593 -159.48771) (xy 36.315846 -159.561594) (xy 36.263477 -159.630941) (xy 36.204933 -159.695161)
			(xy 36.140713 -159.753705) (xy 36.071366 -159.806074) (xy 35.997482 -159.851821) (xy 35.919693 -159.890555)
			(xy 35.838661 -159.921947) (xy 35.755079 -159.945728) (xy 35.669659 -159.961696) (xy 35.58313 -159.969714)
			(xy 35.49623 -159.969714) (xy 35.409701 -159.961696) (xy 35.324281 -159.945728) (xy 35.240699 -159.921947)
			(xy 35.159667 -159.890555) (xy 35.081878 -159.851821) (xy 35.007994 -159.806074) (xy 34.938647 -159.753705)
			(xy 34.874427 -159.695161) (xy 34.815883 -159.630941) (xy 34.763514 -159.561594) (xy 34.717767 -159.48771)
			(xy 34.679033 -159.409921) (xy 34.647641 -159.328889) (xy 34.62386 -159.245307) (xy 34.607892 -159.159887)
			(xy 34.599874 -159.073358) (xy 31.399486 -159.073358) (xy 31.391468 -159.159887) (xy 31.3755 -159.245307)
			(xy 31.351719 -159.328889) (xy 31.320327 -159.409921) (xy 31.281593 -159.48771) (xy 31.235846 -159.561594)
			(xy 31.183477 -159.630941) (xy 31.124933 -159.695161) (xy 31.060713 -159.753705) (xy 30.991366 -159.806074)
			(xy 30.917482 -159.851821) (xy 30.839693 -159.890555) (xy 30.758661 -159.921947) (xy 30.675079 -159.945728)
			(xy 30.589659 -159.961696) (xy 30.50313 -159.969714) (xy 30.41623 -159.969714) (xy 30.329701 -159.961696)
			(xy 30.244281 -159.945728) (xy 30.160699 -159.921947) (xy 30.079667 -159.890555) (xy 30.001878 -159.851821)
			(xy 29.927994 -159.806074) (xy 29.858647 -159.753705) (xy 29.794427 -159.695161) (xy 29.735883 -159.630941)
			(xy 29.683514 -159.561594) (xy 29.637767 -159.48771) (xy 29.599033 -159.409921) (xy 29.567641 -159.328889)
			(xy 29.54386 -159.245307) (xy 29.527892 -159.159887) (xy 29.519874 -159.073358) (xy 28.884372 -159.073358)
			(xy 28.884372 -161.613358) (xy 29.519874 -161.613358) (xy 29.519874 -161.526458) (xy 29.527892 -161.439929)
			(xy 29.54386 -161.354509) (xy 29.567641 -161.270927) (xy 29.599033 -161.189895) (xy 29.637767 -161.112106)
			(xy 29.683514 -161.038222) (xy 29.735883 -160.968875) (xy 29.794427 -160.904655) (xy 29.858647 -160.846111)
			(xy 29.927994 -160.793742) (xy 30.001878 -160.747995) (xy 30.079667 -160.709261) (xy 30.160699 -160.677869)
			(xy 30.244281 -160.654088) (xy 30.329701 -160.63812) (xy 30.41623 -160.630102) (xy 30.45968 -160.6296)
			(xy 30.50313 -160.630102) (xy 30.589659 -160.63812) (xy 30.675079 -160.654088) (xy 30.758661 -160.677869)
			(xy 30.839693 -160.709261) (xy 30.917482 -160.747995) (xy 30.991366 -160.793742) (xy 31.060713 -160.846111)
			(xy 31.124933 -160.904655) (xy 31.183477 -160.968875) (xy 31.235846 -161.038222) (xy 31.281593 -161.112106)
			(xy 31.320327 -161.189895) (xy 31.351719 -161.270927) (xy 31.3755 -161.354509) (xy 31.391468 -161.439929)
			(xy 31.399486 -161.526458) (xy 31.399486 -161.613358) (xy 34.599874 -161.613358) (xy 34.599874 -161.526458)
			(xy 34.607892 -161.439929) (xy 34.62386 -161.354509) (xy 34.647641 -161.270927) (xy 34.679033 -161.189895)
			(xy 34.717767 -161.112106) (xy 34.763514 -161.038222) (xy 34.815883 -160.968875) (xy 34.874427 -160.904655)
			(xy 34.938647 -160.846111) (xy 35.007994 -160.793742) (xy 35.081878 -160.747995) (xy 35.159667 -160.709261)
			(xy 35.240699 -160.677869) (xy 35.324281 -160.654088) (xy 35.409701 -160.63812) (xy 35.49623 -160.630102)
			(xy 35.53968 -160.6296) (xy 35.58313 -160.630102) (xy 35.669659 -160.63812) (xy 35.755079 -160.654088)
			(xy 35.838661 -160.677869) (xy 35.919693 -160.709261) (xy 35.997482 -160.747995) (xy 36.071366 -160.793742)
			(xy 36.140713 -160.846111) (xy 36.204933 -160.904655) (xy 36.221953 -160.923325) (xy 39.31208 -160.923325)
			(xy 39.31208 -160.852003) (xy 39.320066 -160.781129) (xy 39.335936 -160.711594) (xy 39.359493 -160.644274)
			(xy 39.390438 -160.580015) (xy 39.428384 -160.519624) (xy 39.472853 -160.463862) (xy 39.523286 -160.413429)
			(xy 39.579048 -160.36896) (xy 39.639439 -160.331014) (xy 39.703698 -160.300069) (xy 39.771018 -160.276512)
			(xy 39.840553 -160.260642) (xy 39.911427 -160.252656) (xy 39.947088 -160.252156) (xy 39.982749 -160.252656)
			(xy 40.053623 -160.260642) (xy 40.123158 -160.276512) (xy 40.190478 -160.300069) (xy 40.254737 -160.331014)
			(xy 40.315128 -160.36896) (xy 40.37089 -160.413429) (xy 40.421323 -160.463862) (xy 40.465792 -160.519624)
			(xy 40.503738 -160.580015) (xy 40.534683 -160.644274) (xy 40.55824 -160.711594) (xy 40.57411 -160.781129)
			(xy 40.582096 -160.852003) (xy 40.582096 -160.923325) (xy 40.57411 -160.994199) (xy 40.55824 -161.063734)
			(xy 40.534683 -161.131054) (xy 40.503738 -161.195313) (xy 40.465792 -161.255704) (xy 40.421323 -161.311466)
			(xy 40.37089 -161.361899) (xy 40.315128 -161.406368) (xy 40.254737 -161.444314) (xy 40.190478 -161.475259)
			(xy 40.123158 -161.498816) (xy 40.053623 -161.514686) (xy 39.982749 -161.522672) (xy 39.911427 -161.522672)
			(xy 39.840553 -161.514686) (xy 39.771018 -161.498816) (xy 39.703698 -161.475259) (xy 39.639439 -161.444314)
			(xy 39.579048 -161.406368) (xy 39.523286 -161.361899) (xy 39.472853 -161.311466) (xy 39.428384 -161.255704)
			(xy 39.390438 -161.195313) (xy 39.359493 -161.131054) (xy 39.335936 -161.063734) (xy 39.320066 -160.994199)
			(xy 39.31208 -160.923325) (xy 36.221953 -160.923325) (xy 36.263477 -160.968875) (xy 36.315846 -161.038222)
			(xy 36.361593 -161.112106) (xy 36.400327 -161.189895) (xy 36.431719 -161.270927) (xy 36.4555 -161.354509)
			(xy 36.471468 -161.439929) (xy 36.479486 -161.526458) (xy 36.479486 -161.613358) (xy 36.471468 -161.699887)
			(xy 36.4555 -161.785307) (xy 36.431719 -161.868889) (xy 36.400327 -161.949921) (xy 36.361593 -162.02771)
			(xy 36.315846 -162.101594) (xy 36.263477 -162.170941) (xy 36.204933 -162.235161) (xy 36.140713 -162.293705)
			(xy 36.071366 -162.346074) (xy 35.997482 -162.391821) (xy 35.919693 -162.430555) (xy 35.838661 -162.461947)
			(xy 35.755079 -162.485728) (xy 35.669659 -162.501696) (xy 35.58313 -162.509714) (xy 35.49623 -162.509714)
			(xy 35.409701 -162.501696) (xy 35.324281 -162.485728) (xy 35.240699 -162.461947) (xy 35.159667 -162.430555)
			(xy 35.081878 -162.391821) (xy 35.007994 -162.346074) (xy 34.938647 -162.293705) (xy 34.874427 -162.235161)
			(xy 34.815883 -162.170941) (xy 34.763514 -162.101594) (xy 34.717767 -162.02771) (xy 34.679033 -161.949921)
			(xy 34.647641 -161.868889) (xy 34.62386 -161.785307) (xy 34.607892 -161.699887) (xy 34.599874 -161.613358)
			(xy 31.399486 -161.613358) (xy 31.391468 -161.699887) (xy 31.3755 -161.785307) (xy 31.351719 -161.868889)
			(xy 31.320327 -161.949921) (xy 31.281593 -162.02771) (xy 31.235846 -162.101594) (xy 31.183477 -162.170941)
			(xy 31.124933 -162.235161) (xy 31.060713 -162.293705) (xy 30.991366 -162.346074) (xy 30.917482 -162.391821)
			(xy 30.839693 -162.430555) (xy 30.758661 -162.461947) (xy 30.675079 -162.485728) (xy 30.589659 -162.501696)
			(xy 30.50313 -162.509714) (xy 30.41623 -162.509714) (xy 30.329701 -162.501696) (xy 30.244281 -162.485728)
			(xy 30.160699 -162.461947) (xy 30.079667 -162.430555) (xy 30.001878 -162.391821) (xy 29.927994 -162.346074)
			(xy 29.858647 -162.293705) (xy 29.794427 -162.235161) (xy 29.735883 -162.170941) (xy 29.683514 -162.101594)
			(xy 29.637767 -162.02771) (xy 29.599033 -161.949921) (xy 29.567641 -161.868889) (xy 29.54386 -161.785307)
			(xy 29.527892 -161.699887) (xy 29.519874 -161.613358) (xy 28.884372 -161.613358) (xy 28.884372 -162.886237)
			(xy 39.31208 -162.886237) (xy 39.31208 -162.814915) (xy 39.320066 -162.744041) (xy 39.335936 -162.674506)
			(xy 39.359493 -162.607186) (xy 39.390438 -162.542927) (xy 39.428384 -162.482536) (xy 39.472853 -162.426774)
			(xy 39.523286 -162.376341) (xy 39.579048 -162.331872) (xy 39.639439 -162.293926) (xy 39.703698 -162.262981)
			(xy 39.771018 -162.239424) (xy 39.840553 -162.223554) (xy 39.911427 -162.215568) (xy 39.947088 -162.215068)
			(xy 39.982749 -162.215568) (xy 40.053623 -162.223554) (xy 40.123158 -162.239424) (xy 40.190478 -162.262981)
			(xy 40.254737 -162.293926) (xy 40.315128 -162.331872) (xy 40.37089 -162.376341) (xy 40.421323 -162.426774)
			(xy 40.465792 -162.482536) (xy 40.503738 -162.542927) (xy 40.534683 -162.607186) (xy 40.55824 -162.674506)
			(xy 40.57411 -162.744041) (xy 40.582096 -162.814915) (xy 40.582096 -162.886237) (xy 40.57411 -162.957111)
			(xy 40.55824 -163.026646) (xy 40.534683 -163.093966) (xy 40.503738 -163.158225) (xy 40.465792 -163.218616)
			(xy 40.421323 -163.274378) (xy 40.37089 -163.324811) (xy 40.315128 -163.36928) (xy 40.254737 -163.407226)
			(xy 40.190478 -163.438171) (xy 40.123158 -163.461728) (xy 40.053623 -163.477598) (xy 39.982749 -163.485584)
			(xy 39.911427 -163.485584) (xy 39.840553 -163.477598) (xy 39.771018 -163.461728) (xy 39.703698 -163.438171)
			(xy 39.639439 -163.407226) (xy 39.579048 -163.36928) (xy 39.523286 -163.324811) (xy 39.472853 -163.274378)
			(xy 39.428384 -163.218616) (xy 39.390438 -163.158225) (xy 39.359493 -163.093966) (xy 39.335936 -163.026646)
			(xy 39.320066 -162.957111) (xy 39.31208 -162.886237) (xy 28.884372 -162.886237) (xy 28.884372 -164.153358)
			(xy 29.519874 -164.153358) (xy 29.519874 -164.066458) (xy 29.527892 -163.979929) (xy 29.54386 -163.894509)
			(xy 29.567641 -163.810927) (xy 29.599033 -163.729895) (xy 29.637767 -163.652106) (xy 29.683514 -163.578222)
			(xy 29.735883 -163.508875) (xy 29.794427 -163.444655) (xy 29.858647 -163.386111) (xy 29.927994 -163.333742)
			(xy 30.001878 -163.287995) (xy 30.079667 -163.249261) (xy 30.160699 -163.217869) (xy 30.244281 -163.194088)
			(xy 30.329701 -163.17812) (xy 30.41623 -163.170102) (xy 30.45968 -163.1696) (xy 30.50313 -163.170102)
			(xy 30.589659 -163.17812) (xy 30.675079 -163.194088) (xy 30.758661 -163.217869) (xy 30.839693 -163.249261)
			(xy 30.917482 -163.287995) (xy 30.991366 -163.333742) (xy 31.060713 -163.386111) (xy 31.124933 -163.444655)
			(xy 31.183477 -163.508875) (xy 31.235846 -163.578222) (xy 31.281593 -163.652106) (xy 31.320327 -163.729895)
			(xy 31.351719 -163.810927) (xy 31.3755 -163.894509) (xy 31.391468 -163.979929) (xy 31.399486 -164.066458)
			(xy 31.399486 -164.153358) (xy 34.599874 -164.153358) (xy 34.599874 -164.066458) (xy 34.607892 -163.979929)
			(xy 34.62386 -163.894509) (xy 34.647641 -163.810927) (xy 34.679033 -163.729895) (xy 34.717767 -163.652106)
			(xy 34.763514 -163.578222) (xy 34.815883 -163.508875) (xy 34.874427 -163.444655) (xy 34.938647 -163.386111)
			(xy 35.007994 -163.333742) (xy 35.081878 -163.287995) (xy 35.159667 -163.249261) (xy 35.240699 -163.217869)
			(xy 35.324281 -163.194088) (xy 35.409701 -163.17812) (xy 35.49623 -163.170102) (xy 35.53968 -163.1696)
			(xy 35.58313 -163.170102) (xy 35.669659 -163.17812) (xy 35.755079 -163.194088) (xy 35.838661 -163.217869)
			(xy 35.919693 -163.249261) (xy 35.997482 -163.287995) (xy 36.071366 -163.333742) (xy 36.140713 -163.386111)
			(xy 36.204933 -163.444655) (xy 36.263477 -163.508875) (xy 36.315846 -163.578222) (xy 36.361593 -163.652106)
			(xy 36.400327 -163.729895) (xy 36.431719 -163.810927) (xy 36.4555 -163.894509) (xy 36.471468 -163.979929)
			(xy 36.479486 -164.066458) (xy 36.479486 -164.153358) (xy 36.471468 -164.239887) (xy 36.4555 -164.325307)
			(xy 36.431719 -164.408889) (xy 36.400327 -164.489921) (xy 36.361593 -164.56771) (xy 36.315846 -164.641594)
			(xy 36.263477 -164.710941) (xy 36.204933 -164.775161) (xy 36.140713 -164.833705) (xy 36.071366 -164.886074)
			(xy 35.997482 -164.931821) (xy 35.919693 -164.970555) (xy 35.838661 -165.001947) (xy 35.755079 -165.025728)
			(xy 35.733601 -165.029743) (xy 39.31208 -165.029743) (xy 39.31208 -164.958421) (xy 39.320066 -164.887547)
			(xy 39.335936 -164.818012) (xy 39.359493 -164.750692) (xy 39.390438 -164.686433) (xy 39.428384 -164.626042)
			(xy 39.472853 -164.57028) (xy 39.523286 -164.519847) (xy 39.579048 -164.475378) (xy 39.639439 -164.437432)
			(xy 39.703698 -164.406487) (xy 39.771018 -164.38293) (xy 39.840553 -164.36706) (xy 39.911427 -164.359074)
			(xy 39.947088 -164.358574) (xy 39.982749 -164.359074) (xy 40.053623 -164.36706) (xy 40.123158 -164.38293)
			(xy 40.190478 -164.406487) (xy 40.254737 -164.437432) (xy 40.315128 -164.475378) (xy 40.37089 -164.519847)
			(xy 40.421323 -164.57028) (xy 40.465792 -164.626042) (xy 40.503738 -164.686433) (xy 40.534683 -164.750692)
			(xy 40.55824 -164.818012) (xy 40.57411 -164.887547) (xy 40.582096 -164.958421) (xy 40.582096 -165.029743)
			(xy 40.57411 -165.100617) (xy 40.55824 -165.170152) (xy 40.534683 -165.237472) (xy 40.503738 -165.301731)
			(xy 40.465792 -165.362122) (xy 40.421323 -165.417884) (xy 40.37089 -165.468317) (xy 40.315128 -165.512786)
			(xy 40.254737 -165.550732) (xy 40.190478 -165.581677) (xy 40.123158 -165.605234) (xy 40.053623 -165.621104)
			(xy 39.982749 -165.62909) (xy 39.911427 -165.62909) (xy 39.840553 -165.621104) (xy 39.771018 -165.605234)
			(xy 39.703698 -165.581677) (xy 39.639439 -165.550732) (xy 39.579048 -165.512786) (xy 39.523286 -165.468317)
			(xy 39.472853 -165.417884) (xy 39.428384 -165.362122) (xy 39.390438 -165.301731) (xy 39.359493 -165.237472)
			(xy 39.335936 -165.170152) (xy 39.320066 -165.100617) (xy 39.31208 -165.029743) (xy 35.733601 -165.029743)
			(xy 35.669659 -165.041696) (xy 35.58313 -165.049714) (xy 35.49623 -165.049714) (xy 35.409701 -165.041696)
			(xy 35.324281 -165.025728) (xy 35.240699 -165.001947) (xy 35.159667 -164.970555) (xy 35.081878 -164.931821)
			(xy 35.007994 -164.886074) (xy 34.938647 -164.833705) (xy 34.874427 -164.775161) (xy 34.815883 -164.710941)
			(xy 34.763514 -164.641594) (xy 34.717767 -164.56771) (xy 34.679033 -164.489921) (xy 34.647641 -164.408889)
			(xy 34.62386 -164.325307) (xy 34.607892 -164.239887) (xy 34.599874 -164.153358) (xy 31.399486 -164.153358)
			(xy 31.391468 -164.239887) (xy 31.3755 -164.325307) (xy 31.351719 -164.408889) (xy 31.320327 -164.489921)
			(xy 31.281593 -164.56771) (xy 31.235846 -164.641594) (xy 31.183477 -164.710941) (xy 31.124933 -164.775161)
			(xy 31.060713 -164.833705) (xy 30.991366 -164.886074) (xy 30.917482 -164.931821) (xy 30.839693 -164.970555)
			(xy 30.758661 -165.001947) (xy 30.675079 -165.025728) (xy 30.589659 -165.041696) (xy 30.50313 -165.049714)
			(xy 30.41623 -165.049714) (xy 30.329701 -165.041696) (xy 30.244281 -165.025728) (xy 30.160699 -165.001947)
			(xy 30.079667 -164.970555) (xy 30.001878 -164.931821) (xy 29.927994 -164.886074) (xy 29.858647 -164.833705)
			(xy 29.794427 -164.775161) (xy 29.735883 -164.710941) (xy 29.683514 -164.641594) (xy 29.637767 -164.56771)
			(xy 29.599033 -164.489921) (xy 29.567641 -164.408889) (xy 29.54386 -164.325307) (xy 29.527892 -164.239887)
			(xy 29.519874 -164.153358) (xy 28.884372 -164.153358) (xy 28.884372 -166.693358) (xy 29.519874 -166.693358)
			(xy 29.519874 -166.606458) (xy 29.527892 -166.519929) (xy 29.54386 -166.434509) (xy 29.567641 -166.350927)
			(xy 29.599033 -166.269895) (xy 29.637767 -166.192106) (xy 29.683514 -166.118222) (xy 29.735883 -166.048875)
			(xy 29.794427 -165.984655) (xy 29.858647 -165.926111) (xy 29.927994 -165.873742) (xy 30.001878 -165.827995)
			(xy 30.079667 -165.789261) (xy 30.160699 -165.757869) (xy 30.244281 -165.734088) (xy 30.329701 -165.71812)
			(xy 30.41623 -165.710102) (xy 30.45968 -165.7096) (xy 30.50313 -165.710102) (xy 30.589659 -165.71812)
			(xy 30.675079 -165.734088) (xy 30.758661 -165.757869) (xy 30.839693 -165.789261) (xy 30.917482 -165.827995)
			(xy 30.991366 -165.873742) (xy 31.060713 -165.926111) (xy 31.124933 -165.984655) (xy 31.183477 -166.048875)
			(xy 31.235846 -166.118222) (xy 31.281593 -166.192106) (xy 31.320327 -166.269895) (xy 31.351719 -166.350927)
			(xy 31.3755 -166.434509) (xy 31.391468 -166.519929) (xy 31.399486 -166.606458) (xy 31.399486 -166.693358)
			(xy 34.599874 -166.693358) (xy 34.599874 -166.606458) (xy 34.607892 -166.519929) (xy 34.62386 -166.434509)
			(xy 34.647641 -166.350927) (xy 34.679033 -166.269895) (xy 34.717767 -166.192106) (xy 34.763514 -166.118222)
			(xy 34.815883 -166.048875) (xy 34.874427 -165.984655) (xy 34.938647 -165.926111) (xy 35.007994 -165.873742)
			(xy 35.081878 -165.827995) (xy 35.159667 -165.789261) (xy 35.240699 -165.757869) (xy 35.324281 -165.734088)
			(xy 35.409701 -165.71812) (xy 35.49623 -165.710102) (xy 35.53968 -165.7096) (xy 35.58313 -165.710102)
			(xy 35.669659 -165.71812) (xy 35.755079 -165.734088) (xy 35.838661 -165.757869) (xy 35.919693 -165.789261)
			(xy 35.997482 -165.827995) (xy 36.071366 -165.873742) (xy 36.140713 -165.926111) (xy 36.204933 -165.984655)
			(xy 36.263477 -166.048875) (xy 36.315846 -166.118222) (xy 36.361593 -166.192106) (xy 36.400327 -166.269895)
			(xy 36.431719 -166.350927) (xy 36.4555 -166.434509) (xy 36.471468 -166.519929) (xy 36.479486 -166.606458)
			(xy 36.479486 -166.693358) (xy 36.471468 -166.779887) (xy 36.4555 -166.865307) (xy 36.431719 -166.948889)
			(xy 36.400327 -167.029921) (xy 36.361593 -167.10771) (xy 36.315846 -167.181594) (xy 36.263477 -167.250941)
			(xy 36.204933 -167.315161) (xy 36.140713 -167.373705) (xy 36.071366 -167.426074) (xy 35.997482 -167.471821)
			(xy 35.919693 -167.510555) (xy 35.838661 -167.541947) (xy 35.755079 -167.565728) (xy 35.669659 -167.581696)
			(xy 35.58313 -167.589714) (xy 35.49623 -167.589714) (xy 35.409701 -167.581696) (xy 35.324281 -167.565728)
			(xy 35.240699 -167.541947) (xy 35.159667 -167.510555) (xy 35.081878 -167.471821) (xy 35.007994 -167.426074)
			(xy 34.938647 -167.373705) (xy 34.874427 -167.315161) (xy 34.815883 -167.250941) (xy 34.763514 -167.181594)
			(xy 34.717767 -167.10771) (xy 34.679033 -167.029921) (xy 34.647641 -166.948889) (xy 34.62386 -166.865307)
			(xy 34.607892 -166.779887) (xy 34.599874 -166.693358) (xy 31.399486 -166.693358) (xy 31.391468 -166.779887)
			(xy 31.3755 -166.865307) (xy 31.351719 -166.948889) (xy 31.320327 -167.029921) (xy 31.281593 -167.10771)
			(xy 31.235846 -167.181594) (xy 31.183477 -167.250941) (xy 31.124933 -167.315161) (xy 31.060713 -167.373705)
			(xy 30.991366 -167.426074) (xy 30.917482 -167.471821) (xy 30.839693 -167.510555) (xy 30.758661 -167.541947)
			(xy 30.675079 -167.565728) (xy 30.589659 -167.581696) (xy 30.50313 -167.589714) (xy 30.41623 -167.589714)
			(xy 30.329701 -167.581696) (xy 30.244281 -167.565728) (xy 30.160699 -167.541947) (xy 30.079667 -167.510555)
			(xy 30.001878 -167.471821) (xy 29.927994 -167.426074) (xy 29.858647 -167.373705) (xy 29.794427 -167.315161)
			(xy 29.735883 -167.250941) (xy 29.683514 -167.181594) (xy 29.637767 -167.10771) (xy 29.599033 -167.029921)
			(xy 29.567641 -166.948889) (xy 29.54386 -166.865307) (xy 29.527892 -166.779887) (xy 29.519874 -166.693358)
			(xy 28.884372 -166.693358) (xy 28.884372 -169.233358) (xy 29.519874 -169.233358) (xy 29.519874 -169.146458)
			(xy 29.527892 -169.059929) (xy 29.54386 -168.974509) (xy 29.567641 -168.890927) (xy 29.599033 -168.809895)
			(xy 29.637767 -168.732106) (xy 29.683514 -168.658222) (xy 29.735883 -168.588875) (xy 29.794427 -168.524655)
			(xy 29.858647 -168.466111) (xy 29.927994 -168.413742) (xy 30.001878 -168.367995) (xy 30.079667 -168.329261)
			(xy 30.160699 -168.297869) (xy 30.244281 -168.274088) (xy 30.329701 -168.25812) (xy 30.41623 -168.250102)
			(xy 30.45968 -168.2496) (xy 30.50313 -168.250102) (xy 30.589659 -168.25812) (xy 30.675079 -168.274088)
			(xy 30.758661 -168.297869) (xy 30.839693 -168.329261) (xy 30.917482 -168.367995) (xy 30.991366 -168.413742)
			(xy 31.060713 -168.466111) (xy 31.124933 -168.524655) (xy 31.183477 -168.588875) (xy 31.235846 -168.658222)
			(xy 31.281593 -168.732106) (xy 31.320327 -168.809895) (xy 31.351719 -168.890927) (xy 31.3755 -168.974509)
			(xy 31.391468 -169.059929) (xy 31.399486 -169.146458) (xy 31.399486 -169.233358) (xy 34.599874 -169.233358)
			(xy 34.599874 -169.146458) (xy 34.607892 -169.059929) (xy 34.62386 -168.974509) (xy 34.647641 -168.890927)
			(xy 34.679033 -168.809895) (xy 34.717767 -168.732106) (xy 34.763514 -168.658222) (xy 34.815883 -168.588875)
			(xy 34.874427 -168.524655) (xy 34.938647 -168.466111) (xy 35.007994 -168.413742) (xy 35.081878 -168.367995)
			(xy 35.159667 -168.329261) (xy 35.240699 -168.297869) (xy 35.324281 -168.274088) (xy 35.409701 -168.25812)
			(xy 35.49623 -168.250102) (xy 35.53968 -168.2496) (xy 35.58313 -168.250102) (xy 35.669659 -168.25812)
			(xy 35.755079 -168.274088) (xy 35.838661 -168.297869) (xy 35.919693 -168.329261) (xy 35.997482 -168.367995)
			(xy 36.071366 -168.413742) (xy 36.140713 -168.466111) (xy 36.204933 -168.524655) (xy 36.263477 -168.588875)
			(xy 36.315846 -168.658222) (xy 36.361593 -168.732106) (xy 36.400327 -168.809895) (xy 36.431719 -168.890927)
			(xy 36.4555 -168.974509) (xy 36.471468 -169.059929) (xy 36.479486 -169.146458) (xy 36.479486 -169.233358)
			(xy 36.471468 -169.319887) (xy 36.4555 -169.405307) (xy 36.431719 -169.488889) (xy 36.400327 -169.569921)
			(xy 36.361593 -169.64771) (xy 36.315846 -169.721594) (xy 36.263477 -169.790941) (xy 36.204933 -169.855161)
			(xy 36.140713 -169.913705) (xy 36.071366 -169.966074) (xy 35.997482 -170.011821) (xy 35.919693 -170.050555)
			(xy 35.838661 -170.081947) (xy 35.755079 -170.105728) (xy 35.669659 -170.121696) (xy 35.58313 -170.129714)
			(xy 35.49623 -170.129714) (xy 35.409701 -170.121696) (xy 35.324281 -170.105728) (xy 35.240699 -170.081947)
			(xy 35.159667 -170.050555) (xy 35.081878 -170.011821) (xy 35.007994 -169.966074) (xy 34.938647 -169.913705)
			(xy 34.874427 -169.855161) (xy 34.815883 -169.790941) (xy 34.763514 -169.721594) (xy 34.717767 -169.64771)
			(xy 34.679033 -169.569921) (xy 34.647641 -169.488889) (xy 34.62386 -169.405307) (xy 34.607892 -169.319887)
			(xy 34.599874 -169.233358) (xy 31.399486 -169.233358) (xy 31.391468 -169.319887) (xy 31.3755 -169.405307)
			(xy 31.351719 -169.488889) (xy 31.320327 -169.569921) (xy 31.281593 -169.64771) (xy 31.235846 -169.721594)
			(xy 31.183477 -169.790941) (xy 31.124933 -169.855161) (xy 31.060713 -169.913705) (xy 30.991366 -169.966074)
			(xy 30.917482 -170.011821) (xy 30.839693 -170.050555) (xy 30.758661 -170.081947) (xy 30.675079 -170.105728)
			(xy 30.589659 -170.121696) (xy 30.50313 -170.129714) (xy 30.41623 -170.129714) (xy 30.329701 -170.121696)
			(xy 30.244281 -170.105728) (xy 30.160699 -170.081947) (xy 30.079667 -170.050555) (xy 30.001878 -170.011821)
			(xy 29.927994 -169.966074) (xy 29.858647 -169.913705) (xy 29.794427 -169.855161) (xy 29.735883 -169.790941)
			(xy 29.683514 -169.721594) (xy 29.637767 -169.64771) (xy 29.599033 -169.569921) (xy 29.567641 -169.488889)
			(xy 29.54386 -169.405307) (xy 29.527892 -169.319887) (xy 29.519874 -169.233358) (xy 28.884372 -169.233358)
			(xy 28.884372 -170.773344) (xy 27.884386 -171.773358) (xy 29.519874 -171.773358) (xy 29.519874 -171.686458)
			(xy 29.527892 -171.599929) (xy 29.54386 -171.514509) (xy 29.567641 -171.430927) (xy 29.599033 -171.349895)
			(xy 29.637767 -171.272106) (xy 29.683514 -171.198222) (xy 29.735883 -171.128875) (xy 29.794427 -171.064655)
			(xy 29.858647 -171.006111) (xy 29.927994 -170.953742) (xy 30.001878 -170.907995) (xy 30.079667 -170.869261)
			(xy 30.160699 -170.837869) (xy 30.244281 -170.814088) (xy 30.329701 -170.79812) (xy 30.41623 -170.790102)
			(xy 30.45968 -170.7896) (xy 30.50313 -170.790102) (xy 30.589659 -170.79812) (xy 30.675079 -170.814088)
			(xy 30.758661 -170.837869) (xy 30.839693 -170.869261) (xy 30.917482 -170.907995) (xy 30.991366 -170.953742)
			(xy 31.060713 -171.006111) (xy 31.124933 -171.064655) (xy 31.183477 -171.128875) (xy 31.235846 -171.198222)
			(xy 31.281593 -171.272106) (xy 31.320327 -171.349895) (xy 31.351719 -171.430927) (xy 31.3755 -171.514509)
			(xy 31.391468 -171.599929) (xy 31.399486 -171.686458) (xy 31.399486 -171.773358) (xy 34.599874 -171.773358)
			(xy 34.599874 -171.686458) (xy 34.607892 -171.599929) (xy 34.62386 -171.514509) (xy 34.647641 -171.430927)
			(xy 34.679033 -171.349895) (xy 34.717767 -171.272106) (xy 34.763514 -171.198222) (xy 34.815883 -171.128875)
			(xy 34.874427 -171.064655) (xy 34.938647 -171.006111) (xy 35.007994 -170.953742) (xy 35.081878 -170.907995)
			(xy 35.159667 -170.869261) (xy 35.240699 -170.837869) (xy 35.324281 -170.814088) (xy 35.409701 -170.79812)
			(xy 35.49623 -170.790102) (xy 35.53968 -170.7896) (xy 35.58313 -170.790102) (xy 35.669659 -170.79812)
			(xy 35.755079 -170.814088) (xy 35.838661 -170.837869) (xy 35.919693 -170.869261) (xy 35.997482 -170.907995)
			(xy 36.071366 -170.953742) (xy 36.140713 -171.006111) (xy 36.204933 -171.064655) (xy 36.263477 -171.128875)
			(xy 36.315846 -171.198222) (xy 36.361593 -171.272106) (xy 36.400327 -171.349895) (xy 36.431719 -171.430927)
			(xy 36.4555 -171.514509) (xy 36.471468 -171.599929) (xy 36.479486 -171.686458) (xy 36.479486 -171.773358)
			(xy 36.471468 -171.859887) (xy 36.4555 -171.945307) (xy 36.431719 -172.028889) (xy 36.400327 -172.109921)
			(xy 36.361593 -172.18771) (xy 36.315846 -172.261594) (xy 36.263477 -172.330941) (xy 36.204933 -172.395161)
			(xy 36.140713 -172.453705) (xy 36.071366 -172.506074) (xy 35.997482 -172.551821) (xy 35.919693 -172.590555)
			(xy 35.838661 -172.621947) (xy 35.755079 -172.645728) (xy 35.669659 -172.661696) (xy 35.58313 -172.669714)
			(xy 35.49623 -172.669714) (xy 35.409701 -172.661696) (xy 35.324281 -172.645728) (xy 35.240699 -172.621947)
			(xy 35.159667 -172.590555) (xy 35.081878 -172.551821) (xy 35.007994 -172.506074) (xy 34.938647 -172.453705)
			(xy 34.874427 -172.395161) (xy 34.815883 -172.330941) (xy 34.763514 -172.261594) (xy 34.717767 -172.18771)
			(xy 34.679033 -172.109921) (xy 34.647641 -172.028889) (xy 34.62386 -171.945307) (xy 34.607892 -171.859887)
			(xy 34.599874 -171.773358) (xy 31.399486 -171.773358) (xy 31.391468 -171.859887) (xy 31.3755 -171.945307)
			(xy 31.351719 -172.028889) (xy 31.320327 -172.109921) (xy 31.281593 -172.18771) (xy 31.235846 -172.261594)
			(xy 31.183477 -172.330941) (xy 31.124933 -172.395161) (xy 31.060713 -172.453705) (xy 30.991366 -172.506074)
			(xy 30.917482 -172.551821) (xy 30.839693 -172.590555) (xy 30.758661 -172.621947) (xy 30.675079 -172.645728)
			(xy 30.589659 -172.661696) (xy 30.50313 -172.669714) (xy 30.41623 -172.669714) (xy 30.329701 -172.661696)
			(xy 30.244281 -172.645728) (xy 30.160699 -172.621947) (xy 30.079667 -172.590555) (xy 30.001878 -172.551821)
			(xy 29.927994 -172.506074) (xy 29.858647 -172.453705) (xy 29.794427 -172.395161) (xy 29.735883 -172.330941)
			(xy 29.683514 -172.261594) (xy 29.637767 -172.18771) (xy 29.599033 -172.109921) (xy 29.567641 -172.028889)
			(xy 29.54386 -171.945307) (xy 29.527892 -171.859887) (xy 29.519874 -171.773358) (xy 27.884386 -171.773358)
			(xy 26.479399 -173.178385) (xy 51.141874 -173.178385) (xy 51.141874 -173.097275) (xy 51.149824 -173.016556)
			(xy 51.165647 -172.937005) (xy 51.189192 -172.859389) (xy 51.220231 -172.784453) (xy 51.258466 -172.712921)
			(xy 51.303528 -172.645481) (xy 51.354983 -172.582782) (xy 51.412336 -172.525429) (xy 51.475035 -172.473974)
			(xy 51.542475 -172.428912) (xy 51.614007 -172.390677) (xy 51.688943 -172.359638) (xy 51.766559 -172.336093)
			(xy 51.84611 -172.32027) (xy 51.926829 -172.31232) (xy 51.967384 -172.311822) (xy 52.007939 -172.31232)
			(xy 52.088658 -172.32027) (xy 52.168209 -172.336093) (xy 52.245825 -172.359638) (xy 52.320761 -172.390677)
			(xy 52.392293 -172.428912) (xy 52.459733 -172.473974) (xy 52.522432 -172.525429) (xy 52.579785 -172.582782)
			(xy 52.63124 -172.645481) (xy 52.676302 -172.712921) (xy 52.714537 -172.784453) (xy 52.745576 -172.859389)
			(xy 52.769121 -172.937005) (xy 52.784944 -173.016556) (xy 52.792894 -173.097275) (xy 52.792894 -173.178385)
			(xy 52.784944 -173.259104) (xy 52.769121 -173.338655) (xy 52.745576 -173.416271) (xy 52.714537 -173.491207)
			(xy 52.676302 -173.562739) (xy 52.63124 -173.630179) (xy 52.579785 -173.692878) (xy 52.522432 -173.750231)
			(xy 52.459733 -173.801686) (xy 52.392293 -173.846748) (xy 52.320761 -173.884983) (xy 52.245825 -173.916022)
			(xy 52.168209 -173.939567) (xy 52.088658 -173.95539) (xy 52.007939 -173.96334) (xy 51.926829 -173.96334)
			(xy 51.84611 -173.95539) (xy 51.766559 -173.939567) (xy 51.688943 -173.916022) (xy 51.614007 -173.884983)
			(xy 51.542475 -173.846748) (xy 51.475035 -173.801686) (xy 51.412336 -173.750231) (xy 51.354983 -173.692878)
			(xy 51.303528 -173.630179) (xy 51.258466 -173.562739) (xy 51.220231 -173.491207) (xy 51.189192 -173.416271)
			(xy 51.165647 -173.338655) (xy 51.149824 -173.259104) (xy 51.141874 -173.178385) (xy 26.479399 -173.178385)
			(xy 19.922236 -179.735734) (xy 19.922236 -197.61581) (xy 20.041616 -197.73519) (xy 20.0537 -197.746675)
			(xy 20.082548 -197.763368) (xy 20.114735 -197.772023) (xy 20.148065 -197.77205) (xy 20.180265 -197.763446)
			(xy 20.209139 -197.746798) (xy 20.232719 -197.723242) (xy 20.249396 -197.694384) (xy 20.258033 -197.662193)
			(xy 20.258532 -197.645528) (xy 20.258532 -180.062632) (xy 25.5651 -174.756064) (xy 60.616338 -174.756064)
			(xy 60.632954 -174.75551) (xy 60.665057 -174.746919) (xy 60.693852 -174.73033) (xy 60.706 -174.71898)
			(xy 83.409536 -152.01519) (xy 83.409536 -148.73097) (xy 83.393788 -148.702268) (xy 83.380882 -148.677923)
			(xy 83.361419 -148.626376) (xy 83.349576 -148.572564) (xy 83.3456 -148.517609) (xy 83.349573 -148.462653)
			(xy 83.361414 -148.408841) (xy 83.380874 -148.357292) (xy 83.393788 -148.332952) (xy 83.409536 -148.30425)
			(xy 83.409536 -139.146026) (xy 85.8774 -136.678416) (xy 91.987116 -136.678416) (xy 93.1545 -137.845546)
			(xy 93.1545 -139.009882) (xy 92.221304 -139.942824) (xy 92.140532 -139.942824) (xy 92.123877 -139.943323)
			(xy 92.0917 -139.951938) (xy 92.06285 -139.968591) (xy 92.039295 -139.992144) (xy 92.022641 -140.020992)
			(xy 92.014024 -140.053169) (xy 92.013532 -140.069824) (xy 92.013532 -140.116052) (xy 92.07246 -140.186664)
			(xy 92.117672 -140.194792) (xy 92.154178 -140.201838) (xy 92.225542 -140.222719) (xy 92.29434 -140.250925)
			(xy 92.359823 -140.286149) (xy 92.421277 -140.328007) (xy 92.478033 -140.376043) (xy 92.529473 -140.429734)
			(xy 92.575035 -140.488495) (xy 92.614223 -140.551686) (xy 92.646611 -140.618617) (xy 92.671846 -140.688559)
			(xy 92.689651 -140.760752) (xy 92.699835 -140.834406) (xy 92.702284 -140.908722) (xy 92.696974 -140.982887)
			(xy 92.683961 -141.056095) (xy 92.663388 -141.127548) (xy 92.635478 -141.196467) (xy 92.600536 -141.262101)
			(xy 92.558942 -141.323735) (xy 92.51115 -141.380697) (xy 92.457681 -141.432367) (xy 92.399117 -141.478181)
			(xy 92.367862 -141.49832) (xy 92.35445 -141.507232) (xy 92.332297 -141.53059) (xy 92.316696 -141.558751)
			(xy 92.310949 -141.580991) (xy 93.155011 -141.580991) (xy 93.161033 -141.464808) (xy 93.175056 -141.349317)
			(xy 93.197014 -141.235069) (xy 93.226801 -141.122608) (xy 93.264276 -141.01247) (xy 93.309261 -140.90518)
			(xy 93.36154 -140.801249) (xy 93.420865 -140.701173) (xy 93.486953 -140.605427) (xy 93.559489 -140.51447)
			(xy 93.638128 -140.428734) (xy 93.722494 -140.348627) (xy 93.812186 -140.274531) (xy 93.906776 -140.206801)
			(xy 94.005814 -140.145757) (xy 94.108827 -140.091692) (xy 94.215324 -140.044862) (xy 94.324799 -140.005491)
			(xy 94.436729 -139.973767) (xy 94.550581 -139.949841) (xy 94.665813 -139.933827) (xy 94.781875 -139.9258)
			(xy 94.840044 -139.925298) (xy 94.898213 -139.9258) (xy 95.014275 -139.933827) (xy 95.129507 -139.949841)
			(xy 95.243359 -139.973767) (xy 95.355289 -140.005491) (xy 95.464764 -140.044862) (xy 95.571261 -140.091692)
			(xy 95.674274 -140.145757) (xy 95.773312 -140.206801) (xy 95.867902 -140.274531) (xy 95.957594 -140.348627)
			(xy 96.04196 -140.428734) (xy 96.120599 -140.51447) (xy 96.193135 -140.605427) (xy 96.259223 -140.701173)
			(xy 96.318548 -140.801249) (xy 96.370827 -140.90518) (xy 96.415812 -141.01247) (xy 96.453287 -141.122608)
			(xy 96.483074 -141.235069) (xy 96.505032 -141.349317) (xy 96.519055 -141.464808) (xy 96.525077 -141.580991)
			(xy 96.523069 -141.697313) (xy 96.51304 -141.813219) (xy 96.495039 -141.928156) (xy 96.469151 -142.041579)
			(xy 96.4355 -142.152944) (xy 96.394246 -142.261723) (xy 96.345585 -142.367397) (xy 96.289749 -142.469461)
			(xy 96.227006 -142.56743) (xy 96.157652 -142.660837) (xy 96.08202 -142.749237) (xy 96.000469 -142.832208)
			(xy 95.913388 -142.909355) (xy 95.821192 -142.98031) (xy 95.72432 -143.044736) (xy 95.623235 -143.102325)
			(xy 95.518417 -143.152802) (xy 95.410366 -143.195928) (xy 95.299598 -143.231497) (xy 95.186639 -143.259339)
			(xy 95.072029 -143.279321) (xy 94.956314 -143.291348) (xy 94.840044 -143.295364) (xy 94.723774 -143.291348)
			(xy 94.608059 -143.279321) (xy 94.493449 -143.259339) (xy 94.38049 -143.231497) (xy 94.269722 -143.195928)
			(xy 94.161671 -143.152802) (xy 94.056853 -143.102325) (xy 93.955768 -143.044736) (xy 93.858896 -142.98031)
			(xy 93.7667 -142.909355) (xy 93.679619 -142.832208) (xy 93.598068 -142.749237) (xy 93.522436 -142.660837)
			(xy 93.453082 -142.56743) (xy 93.390339 -142.469461) (xy 93.334503 -142.367397) (xy 93.285842 -142.261723)
			(xy 93.244588 -142.152944) (xy 93.210937 -142.041579) (xy 93.185049 -141.928156) (xy 93.167048 -141.813219)
			(xy 93.157019 -141.697313) (xy 93.155011 -141.580991) (xy 92.310949 -141.580991) (xy 92.308642 -141.589919)
			(xy 92.308172 -141.606016) (xy 92.308172 -142.590012) (xy 87.472266 -147.425918) (xy 87.463376 -147.457414)
			(xy 87.455295 -147.483782) (xy 87.432592 -147.53404) (xy 87.40289 -147.580506) (xy 87.36681 -147.622213)
			(xy 87.325102 -147.658293) (xy 87.278635 -147.687994) (xy 87.228377 -147.710697) (xy 87.20201 -147.71878)
			(xy 87.170514 -147.72767) (xy 86.499446 -148.398738) (xy 86.487988 -148.410819) (xy 86.471296 -148.439618)
			(xy 86.462629 -148.471757) (xy 86.462108 -148.4884) (xy 86.462108 -152.433528) (xy 79.250794 -159.644842)
			(xy 79.234938 -159.661568) (xy 79.208761 -159.699488) (xy 79.189851 -159.741506) (xy 79.178828 -159.786246)
			(xy 79.176054 -159.83224) (xy 79.181619 -159.87798) (xy 79.195342 -159.921967) (xy 79.216772 -159.962758)
			(xy 79.245207 -159.999015) (xy 79.279714 -160.029551) (xy 79.319162 -160.053363) (xy 79.362257 -160.06967)
			(xy 79.407587 -160.077939) (xy 79.430626 -160.07842) (xy 91.060778 -160.07842) (xy 93.058742 -158.080456)
			(xy 93.074411 -158.06411) (xy 93.100258 -158.026938) (xy 93.11911 -157.985775) (xy 93.13037 -157.941922)
			(xy 93.133682 -157.896769) (xy 93.128941 -157.851742) (xy 93.116298 -157.808269) (xy 93.096151 -157.767723)
			(xy 93.06914 -157.731388) (xy 93.036118 -157.700415) (xy 92.99813 -157.675782) (xy 92.956379 -157.65827)
			(xy 92.912186 -157.648432) (xy 92.866948 -157.646581) (xy 92.822099 -157.652774) (xy 92.800424 -157.659324)
			(xy 92.709839 -157.68831) (xy 92.52666 -157.739568) (xy 92.341487 -157.783078) (xy 92.154648 -157.818763)
			(xy 91.966474 -157.846558) (xy 91.777297 -157.866416) (xy 91.587453 -157.878302) (xy 91.397277 -157.882193)
			(xy 91.207105 -157.878084) (xy 91.017275 -157.865981) (xy 90.828121 -157.845906) (xy 90.639979 -157.817894)
			(xy 90.453181 -157.781995) (xy 90.268058 -157.738273) (xy 90.084938 -157.686805) (xy 89.904144 -157.627682)
			(xy 89.725996 -157.561008) (xy 89.550809 -157.486901) (xy 89.378894 -157.405493) (xy 89.210554 -157.316928)
			(xy 89.046087 -157.221362) (xy 88.885785 -157.118964) (xy 88.729931 -157.009916) (xy 88.5788 -156.89441)
			(xy 88.43266 -156.772651) (xy 88.291769 -156.644854) (xy 88.156378 -156.511246) (xy 88.026724 -156.372062)
			(xy 87.903039 -156.227549) (xy 87.78554 -156.077963) (xy 87.674435 -155.923568) (xy 87.569921 -155.764637)
			(xy 87.472183 -155.601452) (xy 87.381394 -155.434301) (xy 87.297714 -155.26348) (xy 87.221292 -155.089291)
			(xy 87.152262 -154.912043) (xy 87.090747 -154.732048) (xy 87.036856 -154.549626) (xy 86.990683 -154.365099)
			(xy 86.952311 -154.178793) (xy 86.921808 -153.991039) (xy 86.899227 -153.802168) (xy 86.884609 -153.612515)
			(xy 86.877979 -153.422414) (xy 86.879349 -153.232203) (xy 86.888716 -153.042218) (xy 86.906065 -152.852795)
			(xy 86.931363 -152.664269) (xy 86.964568 -152.476974) (xy 87.005619 -152.29124) (xy 87.054444 -152.107397)
			(xy 87.110958 -151.92577) (xy 87.175059 -151.74668) (xy 87.246634 -151.570444) (xy 87.325557 -151.397374)
			(xy 87.411689 -151.227776) (xy 87.504876 -151.06195) (xy 87.604954 -150.90019) (xy 87.711746 -150.742781)
			(xy 87.825063 -150.590002) (xy 87.944705 -150.442124) (xy 88.070459 -150.299407) (xy 88.202103 -150.162105)
			(xy 88.339405 -150.03046) (xy 88.482122 -149.904706) (xy 88.63 -149.785065) (xy 88.782779 -149.671748)
			(xy 88.940188 -149.564956) (xy 89.101948 -149.464877) (xy 89.267774 -149.37169) (xy 89.437372 -149.285558)
			(xy 89.610442 -149.206635) (xy 89.786678 -149.135059) (xy 89.965768 -149.070958) (xy 90.147395 -149.014445)
			(xy 90.331238 -148.96562) (xy 90.516971 -148.924568) (xy 90.704266 -148.891364) (xy 90.892793 -148.866065)
			(xy 91.082216 -148.848716) (xy 91.272201 -148.839349) (xy 91.462412 -148.837979) (xy 91.652512 -148.844609)
			(xy 91.842166 -148.859227) (xy 92.031037 -148.881808) (xy 92.218791 -148.912311) (xy 92.405096 -148.950683)
			(xy 92.589624 -148.996855) (xy 92.772046 -149.050746) (xy 92.95204 -149.112261) (xy 93.129289 -149.181291)
			(xy 93.303478 -149.257713) (xy 93.474299 -149.341393) (xy 93.64145 -149.432182) (xy 93.804635 -149.52992)
			(xy 93.963566 -149.634434) (xy 94.117961 -149.745538) (xy 94.267547 -149.863037) (xy 94.41206 -149.986723)
			(xy 94.551244 -150.116376) (xy 94.684853 -150.251768) (xy 94.81265 -150.392658) (xy 94.934409 -150.538798)
			(xy 95.049914 -150.689928) (xy 95.158963 -150.845783) (xy 95.261361 -151.006085) (xy 95.356927 -151.170552)
			(xy 95.445492 -151.338891) (xy 95.5269 -151.510807) (xy 95.601007 -151.685993) (xy 95.667681 -151.864141)
			(xy 95.726804 -152.044935) (xy 95.778273 -152.228056) (xy 95.821995 -152.413179) (xy 95.857894 -152.599977)
			(xy 95.885905 -152.788119) (xy 95.90598 -152.977272) (xy 95.918084 -153.167103) (xy 95.922193 -153.357274)
			(xy 95.918302 -153.547451) (xy 95.906417 -153.737295) (xy 95.886559 -153.926471) (xy 95.858763 -154.114646)
			(xy 95.823079 -154.301484) (xy 95.779569 -154.486657) (xy 95.728311 -154.669837) (xy 95.699326 -154.760422)
			(xy 95.692857 -154.782113) (xy 95.686686 -154.826946) (xy 95.688552 -154.872164) (xy 95.698398 -154.916336)
			(xy 95.715911 -154.958065) (xy 95.740539 -154.996034) (xy 95.771502 -155.02904) (xy 95.807821 -155.05604)
			(xy 95.848349 -155.07618) (xy 95.891802 -155.088824) (xy 95.936809 -155.093572) (xy 95.981944 -155.090273)
			(xy 96.025782 -155.079033) (xy 96.066936 -155.060206) (xy 96.104104 -155.034387) (xy 96.120458 -155.01874)
			(xy 98.997008 -152.14219) (xy 98.997008 -109.08411) (xy 92.337636 -102.424738) (xy 92.30614 -102.415848)
			(xy 92.279758 -102.407812) (xy 92.2295 -102.3851) (xy 92.183034 -102.355391) (xy 92.141328 -102.319303)
			(xy 92.105251 -102.277589) (xy 92.075554 -102.231115) (xy 92.052855 -102.180852) (xy 92.044774 -102.154482)
			(xy 92.035884 -102.122986) (xy 91.808046 -101.895148) (xy 88.370664 -101.895148) (xy 85.322156 -98.846386)
			(xy 85.322156 -98.426016) (xy 85.321693 -98.40992) (xy 85.313635 -98.378753) (xy 85.298028 -98.350598)
			(xy 85.275867 -98.327248) (xy 85.262466 -98.31832) (xy 85.230666 -98.2979) (xy 85.171205 -98.251247)
			(xy 85.117024 -98.198556) (xy 85.068732 -98.140419) (xy 85.026874 -98.077491) (xy 84.99192 -98.010481)
			(xy 84.964264 -97.940145) (xy 84.944219 -97.867274) (xy 84.93201 -97.792688) (xy 84.927774 -97.717229)
			(xy 84.931558 -97.641746) (xy 84.943322 -97.567089) (xy 84.962931 -97.494099) (xy 84.990165 -97.423598)
			(xy 85.024718 -97.356381) (xy 85.066199 -97.293204) (xy 85.114143 -97.234779) (xy 85.168008 -97.181765)
			(xy 85.227189 -97.134757) (xy 85.291018 -97.094286) (xy 85.358776 -97.060808) (xy 85.429702 -97.034699)
			(xy 85.502994 -97.016254) (xy 85.540342 -97.010474) (xy 85.587078 -97.00387) (xy 85.649308 -96.932242)
			(xy 85.649308 -95.957898) (xy 85.587078 -95.88627) (xy 85.540342 -95.879666) (xy 85.503111 -95.87399)
			(xy 85.430063 -95.855637) (xy 85.359362 -95.829673) (xy 85.291798 -95.796389) (xy 85.228127 -95.756155)
			(xy 85.16906 -95.709423) (xy 85.115258 -95.656715) (xy 85.067323 -95.59862) (xy 85.025791 -95.535789)
			(xy 84.991126 -95.468922) (xy 84.963715 -95.398769) (xy 84.943866 -95.326114) (xy 84.9318 -95.251769)
			(xy 84.927653 -95.176565) (xy 84.93147 -95.101344) (xy 84.943209 -95.026947) (xy 84.962738 -94.954205)
			(xy 84.98984 -94.883932) (xy 85.024211 -94.816914) (xy 85.065467 -94.7539) (xy 85.113146 -94.695595)
			(xy 85.166715 -94.642651) (xy 85.225576 -94.59566) (xy 85.28907 -94.555147) (xy 85.356487 -94.521566)
			(xy 85.427074 -94.495292) (xy 85.50004 -94.476618) (xy 85.57457 -94.465753) (xy 85.649831 -94.46282)
			(xy 85.72498 -94.467851) (xy 85.799179 -94.480789) (xy 85.871596 -94.50149) (xy 85.941422 -94.529723)
			(xy 86.007877 -94.565171) (xy 86.070216 -94.607438) (xy 86.127744 -94.656052) (xy 86.179817 -94.710469)
			(xy 86.225852 -94.770081) (xy 86.265334 -94.834221) (xy 86.282022 -94.867984) (xy 86.291901 -94.887725)
			(xy 86.317521 -94.923672) (xy 86.348969 -94.954649) (xy 86.385299 -94.979723) (xy 86.425415 -94.998141)
			(xy 86.468112 -95.009346) (xy 86.512103 -95.013002) (xy 86.556063 -95.008999) (xy 86.59867 -94.997458)
			(xy 86.63864 -94.978725) (xy 86.674771 -94.953365) (xy 86.690708 -94.938088) (xy 86.77656 -94.852236)
			(xy 86.78799 -94.852236) (xy 86.862158 -94.778068) (xy 86.862158 -94.725236) (xy 86.861617 -94.707939)
			(xy 86.852334 -94.674615) (xy 86.83444 -94.645009) (xy 86.809251 -94.621298) (xy 86.778618 -94.605225)
			(xy 86.761828 -94.60103) (xy 86.761574 -94.60103) (xy 86.72457 -94.592643) (xy 86.652464 -94.56902)
			(xy 86.58328 -94.537858) (xy 86.517804 -94.499512) (xy 86.45678 -94.454416) (xy 86.400901 -94.403084)
			(xy 86.350801 -94.346098) (xy 86.307049 -94.284104) (xy 86.270142 -94.217807) (xy 86.240498 -94.147959)
			(xy 86.218454 -94.075354) (xy 86.204261 -94.000815) (xy 86.198079 -93.925189) (xy 86.199979 -93.849335)
			(xy 86.20994 -93.774113) (xy 86.227847 -93.700379) (xy 86.253499 -93.628968) (xy 86.286603 -93.560692)
			(xy 86.326784 -93.496326) (xy 86.373585 -93.436601) (xy 86.426475 -93.382194) (xy 86.484855 -93.333724)
			(xy 86.54806 -93.291741) (xy 86.615373 -93.256721) (xy 86.686031 -93.229063) (xy 86.75923 -93.209079)
			(xy 86.83414 -93.196998) (xy 86.90991 -93.192955) (xy 86.98568 -93.196998) (xy 87.06059 -93.209079)
			(xy 87.133789 -93.229063) (xy 87.204447 -93.256721) (xy 87.27176 -93.291741) (xy 87.334965 -93.333724)
			(xy 87.393345 -93.382194) (xy 87.446235 -93.436601) (xy 87.493036 -93.496326) (xy 87.533217 -93.560692)
			(xy 87.566321 -93.628968) (xy 87.591973 -93.700379) (xy 87.60988 -93.774113) (xy 87.619841 -93.849335)
			(xy 87.621741 -93.925189) (xy 87.615559 -94.000815) (xy 87.601366 -94.075354) (xy 87.579322 -94.147959)
			(xy 87.549678 -94.217807) (xy 87.512771 -94.284104) (xy 87.469019 -94.346098) (xy 87.418919 -94.403084)
			(xy 87.36304 -94.454416) (xy 87.302016 -94.499512) (xy 87.23654 -94.537858) (xy 87.167356 -94.56902)
			(xy 87.09525 -94.592643) (xy 87.058246 -94.60103) (xy 87.01405 -94.610428) (xy 86.957662 -94.680278)
			(xy 86.957662 -94.725236) (xy 86.958211 -94.741883) (xy 86.966834 -94.774041) (xy 86.983484 -94.802872)
			(xy 87.007026 -94.826415) (xy 87.035858 -94.843065) (xy 87.068015 -94.851688) (xy 87.084662 -94.852236)
			(xy 87.472012 -94.852236) (xy 87.487988 -94.851777) (xy 87.518932 -94.843811) (xy 87.546927 -94.828406)
			(xy 87.570217 -94.806529) (xy 87.5792 -94.793308) (xy 87.600283 -94.760931) (xy 87.648542 -94.700586)
			(xy 87.703054 -94.645824) (xy 87.763176 -94.597288) (xy 87.828202 -94.55555) (xy 87.897366 -94.521101)
			(xy 87.969854 -94.494346) (xy 88.044814 -94.475599) (xy 88.121363 -94.465082) (xy 88.198601 -94.462919)
			(xy 88.275619 -94.469134) (xy 88.351511 -94.483654) (xy 88.425383 -94.506309) (xy 88.496367 -94.536832)
			(xy 88.563628 -94.574865) (xy 88.626373 -94.619958) (xy 88.683865 -94.671583) (xy 88.735427 -94.729131)
			(xy 88.780452 -94.791925) (xy 88.818411 -94.859227) (xy 88.848857 -94.930244) (xy 88.86063 -94.967044)
			(xy 88.869774 -94.99727) (xy 88.89238 -95.019876) (xy 88.904551 -95.031229) (xy 88.93339 -95.047818)
			(xy 88.965534 -95.056403) (xy 88.998804 -95.056403) (xy 89.030948 -95.047818) (xy 89.059787 -95.031229)
			(xy 89.071958 -95.019876) (xy 89.094818 -94.996762) (xy 89.10627 -94.984676) (xy 89.122966 -94.95588)
			(xy 89.131635 -94.923742) (xy 89.132156 -94.9071) (xy 89.132156 -94.616016) (xy 89.131693 -94.59992)
			(xy 89.123635 -94.568753) (xy 89.108028 -94.540598) (xy 89.085867 -94.517248) (xy 89.072466 -94.50832)
			(xy 89.040921 -94.488012) (xy 88.981858 -94.441746) (xy 88.92799 -94.389522) (xy 88.879917 -94.33192)
			(xy 88.83817 -94.26958) (xy 88.803214 -94.203194) (xy 88.775437 -94.133498) (xy 88.755147 -94.061267)
			(xy 88.742569 -93.987302) (xy 88.737843 -93.912424) (xy 88.741021 -93.837464) (xy 88.752069 -93.763255)
			(xy 88.770863 -93.69062) (xy 88.797195 -93.620366) (xy 88.830772 -93.553272) (xy 88.871223 -93.490083)
			(xy 88.918097 -93.431501) (xy 88.970874 -93.378175) (xy 89.028969 -93.330699) (xy 89.091737 -93.289598)
			(xy 89.15848 -93.25533) (xy 89.228459 -93.228274) (xy 89.300896 -93.208731) (xy 89.374987 -93.196917)
			(xy 89.44991 -93.192965) (xy 89.524833 -93.196917) (xy 89.598924 -93.208731) (xy 89.671361 -93.228274)
			(xy 89.74134 -93.25533) (xy 89.808083 -93.289598) (xy 89.870851 -93.330699) (xy 89.928946 -93.378175)
			(xy 89.981723 -93.431501) (xy 90.028597 -93.490083) (xy 90.069048 -93.553272) (xy 90.102625 -93.620366)
			(xy 90.128957 -93.69062) (xy 90.147751 -93.763255) (xy 90.158799 -93.837464) (xy 90.160861 -93.886111)
			(xy 91.277949 -93.886111) (xy 91.283998 -93.810541) (xy 91.298045 -93.736043) (xy 91.319931 -93.66346)
			(xy 91.349408 -93.593614) (xy 91.386143 -93.527297) (xy 91.429718 -93.465261) (xy 91.47964 -93.408208)
			(xy 91.535344 -93.356784) (xy 91.596199 -93.311573) (xy 91.661514 -93.273086) (xy 91.73055 -93.24176)
			(xy 91.802525 -93.21795) (xy 91.876623 -93.201925) (xy 91.952004 -93.193866) (xy 91.98991 -93.193362)
			(xy 92.027816 -93.193866) (xy 92.103197 -93.201925) (xy 92.177295 -93.21795) (xy 92.24927 -93.24176)
			(xy 92.318306 -93.273086) (xy 92.383621 -93.311573) (xy 92.444476 -93.356784) (xy 92.50018 -93.408208)
			(xy 92.550102 -93.465261) (xy 92.593677 -93.527297) (xy 92.630412 -93.593614) (xy 92.659889 -93.66346)
			(xy 92.681775 -93.736043) (xy 92.695822 -93.810541) (xy 92.701871 -93.886111) (xy 92.699852 -93.961895)
			(xy 92.68979 -94.037035) (xy 92.671798 -94.11068) (xy 92.64608 -94.181996) (xy 92.612928 -94.250173)
			(xy 92.572716 -94.314441) (xy 92.525901 -94.37407) (xy 92.473013 -94.428386) (xy 92.414651 -94.476772)
			(xy 92.351476 -94.51868) (xy 92.284205 -94.553636) (xy 92.2136 -94.581243) (xy 92.140459 -94.601189)
			(xy 92.065614 -94.613248) (xy 91.98991 -94.617283) (xy 91.914206 -94.613248) (xy 91.839361 -94.601189)
			(xy 91.76622 -94.581243) (xy 91.695615 -94.553636) (xy 91.628344 -94.51868) (xy 91.565169 -94.476772)
			(xy 91.506807 -94.428386) (xy 91.453919 -94.37407) (xy 91.407104 -94.314441) (xy 91.366892 -94.250173)
			(xy 91.33374 -94.181996) (xy 91.308022 -94.11068) (xy 91.29003 -94.037035) (xy 91.279968 -93.961895)
			(xy 91.277949 -93.886111) (xy 90.160861 -93.886111) (xy 90.161977 -93.912424) (xy 90.157251 -93.987302)
			(xy 90.144673 -94.061267) (xy 90.124383 -94.133498) (xy 90.096606 -94.203194) (xy 90.06165 -94.26958)
			(xy 90.019903 -94.33192) (xy 89.97183 -94.389522) (xy 89.917962 -94.441746) (xy 89.858899 -94.488012)
			(xy 89.827354 -94.50832) (xy 89.813941 -94.517229) (xy 89.791788 -94.540589) (xy 89.776188 -94.56875)
			(xy 89.768133 -94.599919) (xy 89.767664 -94.616016) (xy 89.767664 -95.024702) (xy 89.768241 -95.041347)
			(xy 89.776856 -95.073504) (xy 89.793499 -95.102337) (xy 89.817036 -95.12588) (xy 89.845864 -95.142531)
			(xy 89.878019 -95.151154) (xy 89.894664 -95.151702) (xy 89.940892 -95.151702) (xy 90.011504 -95.092774)
			(xy 90.019632 -95.047562) (xy 90.026842 -95.010495) (xy 90.048123 -94.938038) (xy 90.076956 -94.868242)
			(xy 90.113018 -94.801891) (xy 90.155901 -94.739731) (xy 90.205125 -94.682461) (xy 90.260136 -94.630724)
			(xy 90.320315 -94.585103) (xy 90.384987 -94.546109) (xy 90.453423 -94.514183) (xy 90.524856 -94.489681)
			(xy 90.598481 -94.472881) (xy 90.67347 -94.46397) (xy 90.748982 -94.463049) (xy 90.824167 -94.470128)
			(xy 90.89818 -94.485128) (xy 90.970188 -94.50788) (xy 91.039383 -94.538128) (xy 91.104986 -94.575533)
			(xy 91.166261 -94.619673) (xy 91.222517 -94.670052) (xy 91.273123 -94.726105) (xy 91.31751 -94.787201)
			(xy 91.355178 -94.852653) (xy 91.385705 -94.921725) (xy 91.408747 -94.993641) (xy 91.424046 -95.067593)
			(xy 91.431428 -95.142748) (xy 91.430812 -95.218263) (xy 91.422203 -95.293289) (xy 91.4057 -95.366981)
			(xy 91.381487 -95.438511) (xy 91.349836 -95.507076) (xy 91.311104 -95.571904) (xy 91.265726 -95.632267)
			(xy 91.214211 -95.687486) (xy 91.15714 -95.73694) (xy 91.095153 -95.780074) (xy 91.028948 -95.816403)
			(xy 90.959269 -95.845517) (xy 90.886898 -95.86709) (xy 90.812651 -95.88088) (xy 90.73736 -95.886731)
			(xy 90.661873 -95.884577) (xy 90.587039 -95.874444) (xy 90.513698 -95.856443) (xy 90.442676 -95.830779)
			(xy 90.374769 -95.797739) (xy 90.310743 -95.757695) (xy 90.251316 -95.711098) (xy 90.197158 -95.65847)
			(xy 90.148875 -95.600404) (xy 90.107012 -95.537552) (xy 90.072039 -95.470621) (xy 90.057732 -95.435674)
			(xy 90.048884 -95.414552) (xy 90.024744 -95.375642) (xy 89.994026 -95.341684) (xy 89.957724 -95.313776)
			(xy 89.91701 -95.29282) (xy 89.873202 -95.279495) (xy 89.827716 -95.27423) (xy 89.782022 -95.277197)
			(xy 89.737598 -95.288299) (xy 89.695881 -95.307177) (xy 89.658219 -95.333221) (xy 89.64168 -95.34906)
			(xy 89.6239 -95.36684) (xy 89.608028 -95.383358) (xy 89.581952 -95.421016) (xy 89.563047 -95.462738)
			(xy 89.551926 -95.507173) (xy 89.54895 -95.552881) (xy 89.554214 -95.598383) (xy 89.567548 -95.642205)
			(xy 89.58852 -95.682927) (xy 89.616451 -95.71923) (xy 89.650437 -95.74994) (xy 89.689377 -95.774062)
			(xy 89.710514 -95.782892) (xy 89.745126 -95.797098) (xy 89.811489 -95.831652) (xy 89.873861 -95.872979)
			(xy 89.931551 -95.920622) (xy 89.983924 -95.974056) (xy 90.030402 -96.032689) (xy 90.07047 -96.095876)
			(xy 90.103688 -96.162919) (xy 90.129687 -96.233076) (xy 90.148182 -96.305575) (xy 90.158967 -96.379614)
			(xy 90.160806 -96.426111) (xy 91.277949 -96.426111) (xy 91.283998 -96.350541) (xy 91.298045 -96.276043)
			(xy 91.319931 -96.20346) (xy 91.349408 -96.133614) (xy 91.386143 -96.067297) (xy 91.429718 -96.005261)
			(xy 91.47964 -95.948208) (xy 91.535344 -95.896784) (xy 91.596199 -95.851573) (xy 91.661514 -95.813086)
			(xy 91.73055 -95.78176) (xy 91.802525 -95.75795) (xy 91.876623 -95.741925) (xy 91.952004 -95.733866)
			(xy 91.98991 -95.733362) (xy 92.027816 -95.733866) (xy 92.103197 -95.741925) (xy 92.177295 -95.75795)
			(xy 92.24927 -95.78176) (xy 92.318306 -95.813086) (xy 92.383621 -95.851573) (xy 92.444476 -95.896784)
			(xy 92.50018 -95.948208) (xy 92.550102 -96.005261) (xy 92.593677 -96.067297) (xy 92.630412 -96.133614)
			(xy 92.659889 -96.20346) (xy 92.681775 -96.276043) (xy 92.695822 -96.350541) (xy 92.701871 -96.426111)
			(xy 92.699852 -96.501895) (xy 92.68979 -96.577035) (xy 92.671798 -96.65068) (xy 92.64608 -96.721996)
			(xy 92.612928 -96.790173) (xy 92.572716 -96.854441) (xy 92.525901 -96.91407) (xy 92.473013 -96.968386)
			(xy 92.414651 -97.016772) (xy 92.351476 -97.05868) (xy 92.284205 -97.093636) (xy 92.2136 -97.121243)
			(xy 92.177855 -97.130991) (xy 93.154757 -97.130991) (xy 93.160779 -97.014808) (xy 93.174802 -96.899317)
			(xy 93.19676 -96.785069) (xy 93.226547 -96.672608) (xy 93.264022 -96.56247) (xy 93.309007 -96.45518)
			(xy 93.361286 -96.351249) (xy 93.420611 -96.251173) (xy 93.486699 -96.155427) (xy 93.559235 -96.06447)
			(xy 93.637874 -95.978734) (xy 93.72224 -95.898627) (xy 93.811932 -95.824531) (xy 93.906522 -95.756801)
			(xy 94.00556 -95.695757) (xy 94.108573 -95.641692) (xy 94.21507 -95.594862) (xy 94.324545 -95.555491)
			(xy 94.436475 -95.523767) (xy 94.550327 -95.499841) (xy 94.665559 -95.483827) (xy 94.781621 -95.4758)
			(xy 94.83979 -95.475298) (xy 94.897959 -95.4758) (xy 95.014021 -95.483827) (xy 95.129253 -95.499841)
			(xy 95.243105 -95.523767) (xy 95.355035 -95.555491) (xy 95.46451 -95.594862) (xy 95.571007 -95.641692)
			(xy 95.67402 -95.695757) (xy 95.773058 -95.756801) (xy 95.867648 -95.824531) (xy 95.95734 -95.898627)
			(xy 96.041706 -95.978734) (xy 96.120345 -96.06447) (xy 96.192881 -96.155427) (xy 96.258969 -96.251173)
			(xy 96.318294 -96.351249) (xy 96.370573 -96.45518) (xy 96.415558 -96.56247) (xy 96.453033 -96.672608)
			(xy 96.48282 -96.785069) (xy 96.504778 -96.899317) (xy 96.518801 -97.014808) (xy 96.524823 -97.130991)
			(xy 96.522815 -97.247313) (xy 96.512786 -97.363219) (xy 96.494785 -97.478156) (xy 96.468897 -97.591579)
			(xy 96.435246 -97.702944) (xy 96.393992 -97.811723) (xy 96.345331 -97.917397) (xy 96.289495 -98.019461)
			(xy 96.226752 -98.11743) (xy 96.157398 -98.210837) (xy 96.081766 -98.299237) (xy 96.000215 -98.382208)
			(xy 95.913134 -98.459355) (xy 95.820938 -98.53031) (xy 95.724066 -98.594736) (xy 95.622981 -98.652325)
			(xy 95.518163 -98.702802) (xy 95.410112 -98.745928) (xy 95.299344 -98.781497) (xy 95.186385 -98.809339)
			(xy 95.071775 -98.829321) (xy 94.95606 -98.841348) (xy 94.83979 -98.845364) (xy 94.72352 -98.841348)
			(xy 94.607805 -98.829321) (xy 94.493195 -98.809339) (xy 94.380236 -98.781497) (xy 94.269468 -98.745928)
			(xy 94.161417 -98.702802) (xy 94.056599 -98.652325) (xy 93.955514 -98.594736) (xy 93.858642 -98.53031)
			(xy 93.766446 -98.459355) (xy 93.679365 -98.382208) (xy 93.597814 -98.299237) (xy 93.522182 -98.210837)
			(xy 93.452828 -98.11743) (xy 93.390085 -98.019461) (xy 93.334249 -97.917397) (xy 93.285588 -97.811723)
			(xy 93.244334 -97.702944) (xy 93.210683 -97.591579) (xy 93.184795 -97.478156) (xy 93.166794 -97.363219)
			(xy 93.156765 -97.247313) (xy 93.154757 -97.130991) (xy 92.177855 -97.130991) (xy 92.140459 -97.141189)
			(xy 92.065614 -97.153248) (xy 91.98991 -97.157283) (xy 91.914206 -97.153248) (xy 91.839361 -97.141189)
			(xy 91.76622 -97.121243) (xy 91.695615 -97.093636) (xy 91.628344 -97.05868) (xy 91.565169 -97.016772)
			(xy 91.506807 -96.968386) (xy 91.453919 -96.91407) (xy 91.407104 -96.854441) (xy 91.366892 -96.790173)
			(xy 91.33374 -96.721996) (xy 91.308022 -96.65068) (xy 91.29003 -96.577035) (xy 91.279968 -96.501895)
			(xy 91.277949 -96.426111) (xy 90.160806 -96.426111) (xy 90.161924 -96.454375) (xy 90.157021 -96.529035)
			(xy 90.14431 -96.602767) (xy 90.123934 -96.67476) (xy 90.096115 -96.744216) (xy 90.061163 -96.81037)
			(xy 90.019462 -96.872492) (xy 89.971473 -96.929895) (xy 89.917726 -96.981946) (xy 89.858814 -97.02807)
			(xy 89.827354 -97.04832) (xy 89.813941 -97.057229) (xy 89.791788 -97.080589) (xy 89.776188 -97.10875)
			(xy 89.768133 -97.139919) (xy 89.767664 -97.156016) (xy 89.767664 -97.564702) (xy 89.768241 -97.581347)
			(xy 89.776856 -97.613504) (xy 89.793499 -97.642337) (xy 89.817036 -97.66588) (xy 89.845864 -97.682531)
			(xy 89.878019 -97.691154) (xy 89.894664 -97.691702) (xy 89.940892 -97.691702) (xy 90.011504 -97.632774)
			(xy 90.019632 -97.587562) (xy 90.026891 -97.550647) (xy 90.048105 -97.478463) (xy 90.076814 -97.40892)
			(xy 90.112699 -97.342793) (xy 90.155359 -97.28082) (xy 90.204318 -97.223693) (xy 90.25903 -97.172049)
			(xy 90.318885 -97.126464) (xy 90.383214 -97.087447) (xy 90.4513 -97.055434) (xy 90.522382 -97.030781)
			(xy 90.595669 -97.013764) (xy 90.670342 -97.004572) (xy 90.745568 -97.003309) (xy 90.820507 -97.009987)
			(xy 90.894324 -97.024534) (xy 90.966194 -97.046785) (xy 91.035317 -97.076494) (xy 91.10092 -97.113328)
			(xy 91.162271 -97.156877) (xy 91.218687 -97.206654) (xy 91.269537 -97.262105) (xy 91.314255 -97.32261)
			(xy 91.35234 -97.387495) (xy 91.383369 -97.456035) (xy 91.406995 -97.527465) (xy 91.422954 -97.60099)
			(xy 91.431068 -97.675787) (xy 91.431247 -97.751024) (xy 91.423489 -97.825859) (xy 91.407881 -97.899458)
			(xy 91.384596 -97.971001) (xy 91.353894 -98.039688) (xy 91.316118 -98.104753) (xy 91.271689 -98.165471)
			(xy 91.221104 -98.221163) (xy 91.164926 -98.271209) (xy 91.103783 -98.31505) (xy 91.038356 -98.352196)
			(xy 90.969376 -98.382234) (xy 90.897612 -98.404827) (xy 90.823866 -98.419725) (xy 90.786458 -98.42373)
			(xy 90.740738 -98.428048) (xy 90.70848 -98.460306) (xy 90.696994 -98.472417) (xy 90.680281 -98.501301)
			(xy 90.67163 -98.53353) (xy 90.671634 -98.566901) (xy 90.680293 -98.599128) (xy 90.697013 -98.628007)
			(xy 90.70848 -98.640138) (xy 90.772742 -98.7044) (xy 93.280992 -98.7044) (xy 96.816926 -102.24008)
			(xy 96.848422 -102.24897) (xy 96.874801 -102.257017) (xy 96.92506 -102.279725) (xy 96.971527 -102.309432)
			(xy 97.013234 -102.345517) (xy 97.049311 -102.387231) (xy 97.079009 -102.433703) (xy 97.101708 -102.483966)
			(xy 97.109788 -102.510336) (xy 97.118678 -102.541832) (xy 101.548184 -106.971338) (xy 101.548184 -153.199338)
			(xy 92.117926 -162.629596) (xy 79.283052 -162.629596) (xy 77.241654 -164.670994) (xy 77.225767 -164.687553)
			(xy 77.199668 -164.725292) (xy 77.180769 -164.767104) (xy 77.169685 -164.81163) (xy 77.166775 -164.857422)
			(xy 77.172135 -164.902993) (xy 77.185589 -164.94686) (xy 77.206701 -164.987599) (xy 77.234785 -165.023886)
			(xy 77.268928 -165.05454) (xy 77.308019 -165.078566) (xy 77.35079 -165.095183) (xy 77.373226 -165.1)
			(xy 77.407805 -165.107152) (xy 77.475241 -165.128103) (xy 77.539939 -165.156401) (xy 77.601101 -165.191696)
			(xy 77.657974 -165.233554) (xy 77.709856 -165.281457) (xy 77.756108 -165.334817) (xy 77.796161 -165.392975)
			(xy 77.829519 -165.455215) (xy 77.855773 -165.520769) (xy 77.874598 -165.588829) (xy 77.885763 -165.658556)
			(xy 77.88913 -165.729091) (xy 77.887185 -165.759739) (xy 79.42249 -165.759739) (xy 79.42249 -165.688417)
			(xy 79.430476 -165.617543) (xy 79.446346 -165.548008) (xy 79.469903 -165.480688) (xy 79.500848 -165.416429)
			(xy 79.538794 -165.356038) (xy 79.583263 -165.300276) (xy 79.633696 -165.249843) (xy 79.689458 -165.205374)
			(xy 79.749849 -165.167428) (xy 79.814108 -165.136483) (xy 79.881428 -165.112926) (xy 79.950963 -165.097056)
			(xy 80.021837 -165.08907) (xy 80.057498 -165.08857) (xy 80.093159 -165.08907) (xy 80.164033 -165.097056)
			(xy 80.233568 -165.112926) (xy 80.300888 -165.136483) (xy 80.365147 -165.167428) (xy 80.425538 -165.205374)
			(xy 80.4813 -165.249843) (xy 80.531733 -165.300276) (xy 80.576202 -165.356038) (xy 80.614148 -165.416429)
			(xy 80.645093 -165.480688) (xy 80.66865 -165.548008) (xy 80.68452 -165.617543) (xy 80.692506 -165.688417)
			(xy 80.692506 -165.759739) (xy 80.68452 -165.830613) (xy 80.66865 -165.900148) (xy 80.645093 -165.967468)
			(xy 80.614148 -166.031727) (xy 80.576202 -166.092118) (xy 80.531733 -166.14788) (xy 80.4813 -166.198313)
			(xy 80.425538 -166.242782) (xy 80.365147 -166.280728) (xy 80.300888 -166.311673) (xy 80.233568 -166.33523)
			(xy 80.164033 -166.3511) (xy 80.093159 -166.359086) (xy 80.021837 -166.359086) (xy 79.950963 -166.3511)
			(xy 79.881428 -166.33523) (xy 79.814108 -166.311673) (xy 79.749849 -166.280728) (xy 79.689458 -166.242782)
			(xy 79.633696 -166.198313) (xy 79.583263 -166.14788) (xy 79.538794 -166.092118) (xy 79.500848 -166.031727)
			(xy 79.469903 -165.967468) (xy 79.446346 -165.900148) (xy 79.430476 -165.830613) (xy 79.42249 -165.759739)
			(xy 77.887185 -165.759739) (xy 77.884657 -165.799565) (xy 77.872399 -165.869108) (xy 77.852508 -165.936865)
			(xy 77.825229 -166.001998) (xy 77.790897 -166.063707) (xy 77.749937 -166.121229) (xy 77.702853 -166.173856)
			(xy 77.650225 -166.22094) (xy 77.592703 -166.2619) (xy 77.530994 -166.296231) (xy 77.46586 -166.323509)
			(xy 77.398104 -166.3434) (xy 77.32856 -166.355657) (xy 77.258086 -166.36013) (xy 77.187551 -166.356763)
			(xy 77.117824 -166.345597) (xy 77.049764 -166.326772) (xy 76.984211 -166.300517) (xy 76.921971 -166.267158)
			(xy 76.863813 -166.227106) (xy 76.810454 -166.180853) (xy 76.762551 -166.12897) (xy 76.720694 -166.072097)
			(xy 76.685399 -166.010935) (xy 76.657102 -165.946237) (xy 76.636151 -165.878801) (xy 76.629006 -165.84422)
			(xy 76.624212 -165.821782) (xy 76.607582 -165.779022) (xy 76.583547 -165.739941) (xy 76.552888 -165.705809)
			(xy 76.516601 -165.677734) (xy 76.475864 -165.656629) (xy 76.432 -165.643178) (xy 76.386434 -165.637818)
			(xy 76.340647 -165.640724) (xy 76.296124 -165.651802) (xy 76.254313 -165.67069) (xy 76.216571 -165.696777)
			(xy 76.2 -165.712648) (xy 73.917413 -167.995193) (xy 76.618076 -167.995193) (xy 76.618076 -167.923871)
			(xy 76.626062 -167.852997) (xy 76.641932 -167.783462) (xy 76.665489 -167.716142) (xy 76.696434 -167.651883)
			(xy 76.73438 -167.591492) (xy 76.778849 -167.53573) (xy 76.829282 -167.485297) (xy 76.885044 -167.440828)
			(xy 76.945435 -167.402882) (xy 77.009694 -167.371937) (xy 77.077014 -167.34838) (xy 77.146549 -167.33251)
			(xy 77.217423 -167.324524) (xy 77.253084 -167.324024) (xy 77.288745 -167.324524) (xy 77.359619 -167.33251)
			(xy 77.429154 -167.34838) (xy 77.496474 -167.371937) (xy 77.560733 -167.402882) (xy 77.621124 -167.440828)
			(xy 77.676886 -167.485297) (xy 77.727319 -167.53573) (xy 77.771788 -167.591492) (xy 77.809734 -167.651883)
			(xy 77.840679 -167.716142) (xy 77.864236 -167.783462) (xy 77.880106 -167.852997) (xy 77.888092 -167.923871)
			(xy 77.888092 -167.995193) (xy 79.42249 -167.995193) (xy 79.42249 -167.923871) (xy 79.430476 -167.852997)
			(xy 79.446346 -167.783462) (xy 79.469903 -167.716142) (xy 79.500848 -167.651883) (xy 79.538794 -167.591492)
			(xy 79.583263 -167.53573) (xy 79.633696 -167.485297) (xy 79.689458 -167.440828) (xy 79.749849 -167.402882)
			(xy 79.814108 -167.371937) (xy 79.881428 -167.34838) (xy 79.950963 -167.33251) (xy 80.021837 -167.324524)
			(xy 80.057498 -167.324024) (xy 80.093159 -167.324524) (xy 80.164033 -167.33251) (xy 80.233568 -167.34838)
			(xy 80.300888 -167.371937) (xy 80.365147 -167.402882) (xy 80.425538 -167.440828) (xy 80.4813 -167.485297)
			(xy 80.531733 -167.53573) (xy 80.576202 -167.591492) (xy 80.614148 -167.651883) (xy 80.645093 -167.716142)
			(xy 80.66865 -167.783462) (xy 80.68452 -167.852997) (xy 80.692506 -167.923871) (xy 80.692506 -167.995193)
			(xy 80.68452 -168.066067) (xy 80.66865 -168.135602) (xy 80.645093 -168.202922) (xy 80.614148 -168.267181)
			(xy 80.576202 -168.327572) (xy 80.531733 -168.383334) (xy 80.4813 -168.433767) (xy 80.425538 -168.478236)
			(xy 80.365147 -168.516182) (xy 80.300888 -168.547127) (xy 80.233568 -168.570684) (xy 80.164033 -168.586554)
			(xy 80.093159 -168.59454) (xy 80.021837 -168.59454) (xy 79.950963 -168.586554) (xy 79.881428 -168.570684)
			(xy 79.814108 -168.547127) (xy 79.749849 -168.516182) (xy 79.689458 -168.478236) (xy 79.633696 -168.433767)
			(xy 79.583263 -168.383334) (xy 79.538794 -168.327572) (xy 79.500848 -168.267181) (xy 79.469903 -168.202922)
			(xy 79.446346 -168.135602) (xy 79.430476 -168.066067) (xy 79.42249 -167.995193) (xy 77.888092 -167.995193)
			(xy 77.880106 -168.066067) (xy 77.864236 -168.135602) (xy 77.840679 -168.202922) (xy 77.809734 -168.267181)
			(xy 77.771788 -168.327572) (xy 77.727319 -168.383334) (xy 77.676886 -168.433767) (xy 77.621124 -168.478236)
			(xy 77.560733 -168.516182) (xy 77.496474 -168.547127) (xy 77.429154 -168.570684) (xy 77.359619 -168.586554)
			(xy 77.288745 -168.59454) (xy 77.217423 -168.59454) (xy 77.146549 -168.586554) (xy 77.077014 -168.570684)
			(xy 77.009694 -168.547127) (xy 76.945435 -168.516182) (xy 76.885044 -168.478236) (xy 76.829282 -168.433767)
			(xy 76.778849 -168.383334) (xy 76.73438 -168.327572) (xy 76.696434 -168.267181) (xy 76.665489 -168.202922)
			(xy 76.641932 -168.135602) (xy 76.626062 -168.066067) (xy 76.618076 -167.995193) (xy 73.917413 -167.995193)
			(xy 71.249094 -170.663463) (xy 76.618076 -170.663463) (xy 76.618076 -170.592141) (xy 76.626062 -170.521267)
			(xy 76.641932 -170.451732) (xy 76.665489 -170.384412) (xy 76.696434 -170.320153) (xy 76.73438 -170.259762)
			(xy 76.778849 -170.204) (xy 76.829282 -170.153567) (xy 76.885044 -170.109098) (xy 76.945435 -170.071152)
			(xy 77.009694 -170.040207) (xy 77.077014 -170.01665) (xy 77.146549 -170.00078) (xy 77.217423 -169.992794)
			(xy 77.253084 -169.992294) (xy 77.288745 -169.992794) (xy 77.359619 -170.00078) (xy 77.429154 -170.01665)
			(xy 77.496474 -170.040207) (xy 77.560733 -170.071152) (xy 77.621124 -170.109098) (xy 77.676886 -170.153567)
			(xy 77.727319 -170.204) (xy 77.771788 -170.259762) (xy 77.809734 -170.320153) (xy 77.840679 -170.384412)
			(xy 77.864236 -170.451732) (xy 77.880106 -170.521267) (xy 77.888092 -170.592141) (xy 77.888092 -170.663463)
			(xy 79.42249 -170.663463) (xy 79.42249 -170.592141) (xy 79.430476 -170.521267) (xy 79.446346 -170.451732)
			(xy 79.469903 -170.384412) (xy 79.500848 -170.320153) (xy 79.538794 -170.259762) (xy 79.583263 -170.204)
			(xy 79.633696 -170.153567) (xy 79.689458 -170.109098) (xy 79.749849 -170.071152) (xy 79.814108 -170.040207)
			(xy 79.881428 -170.01665) (xy 79.950963 -170.00078) (xy 80.021837 -169.992794) (xy 80.057498 -169.992294)
			(xy 80.093159 -169.992794) (xy 80.164033 -170.00078) (xy 80.233568 -170.01665) (xy 80.300888 -170.040207)
			(xy 80.365147 -170.071152) (xy 80.425538 -170.109098) (xy 80.4813 -170.153567) (xy 80.531733 -170.204)
			(xy 80.576202 -170.259762) (xy 80.614148 -170.320153) (xy 80.645093 -170.384412) (xy 80.66865 -170.451732)
			(xy 80.68452 -170.521267) (xy 80.692506 -170.592141) (xy 80.692506 -170.663463) (xy 80.68452 -170.734337)
			(xy 80.66865 -170.803872) (xy 80.645093 -170.871192) (xy 80.614148 -170.935451) (xy 80.576202 -170.995842)
			(xy 80.531733 -171.051604) (xy 80.4813 -171.102037) (xy 80.425538 -171.146506) (xy 80.365147 -171.184452)
			(xy 80.300888 -171.215397) (xy 80.233568 -171.238954) (xy 80.164033 -171.254824) (xy 80.093159 -171.26281)
			(xy 80.021837 -171.26281) (xy 79.950963 -171.254824) (xy 79.881428 -171.238954) (xy 79.814108 -171.215397)
			(xy 79.749849 -171.184452) (xy 79.689458 -171.146506) (xy 79.633696 -171.102037) (xy 79.583263 -171.051604)
			(xy 79.538794 -170.995842) (xy 79.500848 -170.935451) (xy 79.469903 -170.871192) (xy 79.446346 -170.803872)
			(xy 79.430476 -170.734337) (xy 79.42249 -170.663463) (xy 77.888092 -170.663463) (xy 77.880106 -170.734337)
			(xy 77.864236 -170.803872) (xy 77.840679 -170.871192) (xy 77.809734 -170.935451) (xy 77.771788 -170.995842)
			(xy 77.727319 -171.051604) (xy 77.676886 -171.102037) (xy 77.621124 -171.146506) (xy 77.560733 -171.184452)
			(xy 77.496474 -171.215397) (xy 77.429154 -171.238954) (xy 77.359619 -171.254824) (xy 77.288745 -171.26281)
			(xy 77.217423 -171.26281) (xy 77.146549 -171.254824) (xy 77.077014 -171.238954) (xy 77.009694 -171.215397)
			(xy 76.945435 -171.184452) (xy 76.885044 -171.146506) (xy 76.829282 -171.102037) (xy 76.778849 -171.051604)
			(xy 76.73438 -170.995842) (xy 76.696434 -170.935451) (xy 76.665489 -170.871192) (xy 76.641932 -170.803872)
			(xy 76.626062 -170.734337) (xy 76.618076 -170.663463) (xy 71.249094 -170.663463) (xy 68.877453 -173.035061)
			(xy 76.618076 -173.035061) (xy 76.618076 -172.963739) (xy 76.626062 -172.892865) (xy 76.641932 -172.82333)
			(xy 76.665489 -172.75601) (xy 76.696434 -172.691751) (xy 76.73438 -172.63136) (xy 76.778849 -172.575598)
			(xy 76.829282 -172.525165) (xy 76.885044 -172.480696) (xy 76.945435 -172.44275) (xy 77.009694 -172.411805)
			(xy 77.077014 -172.388248) (xy 77.146549 -172.372378) (xy 77.217423 -172.364392) (xy 77.253084 -172.363892)
			(xy 77.288745 -172.364392) (xy 77.359619 -172.372378) (xy 77.429154 -172.388248) (xy 77.496474 -172.411805)
			(xy 77.560733 -172.44275) (xy 77.621124 -172.480696) (xy 77.676886 -172.525165) (xy 77.727319 -172.575598)
			(xy 77.771788 -172.63136) (xy 77.809734 -172.691751) (xy 77.840679 -172.75601) (xy 77.864236 -172.82333)
			(xy 77.880106 -172.892865) (xy 77.888092 -172.963739) (xy 77.888092 -173.035061) (xy 79.42249 -173.035061)
			(xy 79.42249 -172.963739) (xy 79.430476 -172.892865) (xy 79.446346 -172.82333) (xy 79.469903 -172.75601)
			(xy 79.500848 -172.691751) (xy 79.538794 -172.63136) (xy 79.583263 -172.575598) (xy 79.633696 -172.525165)
			(xy 79.689458 -172.480696) (xy 79.749849 -172.44275) (xy 79.814108 -172.411805) (xy 79.881428 -172.388248)
			(xy 79.950963 -172.372378) (xy 80.021837 -172.364392) (xy 80.057498 -172.363892) (xy 80.093159 -172.364392)
			(xy 80.164033 -172.372378) (xy 80.233568 -172.388248) (xy 80.300888 -172.411805) (xy 80.365147 -172.44275)
			(xy 80.425538 -172.480696) (xy 80.4813 -172.525165) (xy 80.531733 -172.575598) (xy 80.576202 -172.63136)
			(xy 80.614148 -172.691751) (xy 80.645093 -172.75601) (xy 80.66865 -172.82333) (xy 80.68452 -172.892865)
			(xy 80.692506 -172.963739) (xy 80.692506 -173.035061) (xy 80.68452 -173.105935) (xy 80.66865 -173.17547)
			(xy 80.645093 -173.24279) (xy 80.614148 -173.307049) (xy 80.576202 -173.36744) (xy 80.531733 -173.423202)
			(xy 80.4813 -173.473635) (xy 80.425538 -173.518104) (xy 80.365147 -173.55605) (xy 80.300888 -173.586995)
			(xy 80.233568 -173.610552) (xy 80.164033 -173.626422) (xy 80.093159 -173.634408) (xy 80.021837 -173.634408)
			(xy 79.950963 -173.626422) (xy 79.881428 -173.610552) (xy 79.814108 -173.586995) (xy 79.749849 -173.55605)
			(xy 79.689458 -173.518104) (xy 79.633696 -173.473635) (xy 79.583263 -173.423202) (xy 79.538794 -173.36744)
			(xy 79.500848 -173.307049) (xy 79.469903 -173.24279) (xy 79.446346 -173.17547) (xy 79.430476 -173.105935)
			(xy 79.42249 -173.035061) (xy 77.888092 -173.035061) (xy 77.880106 -173.105935) (xy 77.864236 -173.17547)
			(xy 77.840679 -173.24279) (xy 77.809734 -173.307049) (xy 77.771788 -173.36744) (xy 77.727319 -173.423202)
			(xy 77.676886 -173.473635) (xy 77.621124 -173.518104) (xy 77.560733 -173.55605) (xy 77.496474 -173.586995)
			(xy 77.429154 -173.610552) (xy 77.359619 -173.626422) (xy 77.288745 -173.634408) (xy 77.217423 -173.634408)
			(xy 77.146549 -173.626422) (xy 77.077014 -173.610552) (xy 77.009694 -173.586995) (xy 76.945435 -173.55605)
			(xy 76.885044 -173.518104) (xy 76.829282 -173.473635) (xy 76.778849 -173.423202) (xy 76.73438 -173.36744)
			(xy 76.696434 -173.307049) (xy 76.665489 -173.24279) (xy 76.641932 -173.17547) (xy 76.626062 -173.105935)
			(xy 76.618076 -173.035061) (xy 68.877453 -173.035061) (xy 66.914505 -174.997973) (xy 76.618076 -174.997973)
			(xy 76.618076 -174.926651) (xy 76.626062 -174.855777) (xy 76.641932 -174.786242) (xy 76.665489 -174.718922)
			(xy 76.696434 -174.654663) (xy 76.73438 -174.594272) (xy 76.778849 -174.53851) (xy 76.829282 -174.488077)
			(xy 76.885044 -174.443608) (xy 76.945435 -174.405662) (xy 77.009694 -174.374717) (xy 77.077014 -174.35116)
			(xy 77.146549 -174.33529) (xy 77.217423 -174.327304) (xy 77.253084 -174.326804) (xy 77.288745 -174.327304)
			(xy 77.359619 -174.33529) (xy 77.429154 -174.35116) (xy 77.496474 -174.374717) (xy 77.560733 -174.405662)
			(xy 77.621124 -174.443608) (xy 77.676886 -174.488077) (xy 77.727319 -174.53851) (xy 77.771788 -174.594272)
			(xy 77.809734 -174.654663) (xy 77.840679 -174.718922) (xy 77.864236 -174.786242) (xy 77.880106 -174.855777)
			(xy 77.888092 -174.926651) (xy 77.888092 -174.997973) (xy 79.42249 -174.997973) (xy 79.42249 -174.926651)
			(xy 79.430476 -174.855777) (xy 79.446346 -174.786242) (xy 79.469903 -174.718922) (xy 79.500848 -174.654663)
			(xy 79.538794 -174.594272) (xy 79.583263 -174.53851) (xy 79.633696 -174.488077) (xy 79.689458 -174.443608)
			(xy 79.749849 -174.405662) (xy 79.814108 -174.374717) (xy 79.881428 -174.35116) (xy 79.950963 -174.33529)
			(xy 80.021837 -174.327304) (xy 80.057498 -174.326804) (xy 80.093159 -174.327304) (xy 80.164033 -174.33529)
			(xy 80.233568 -174.35116) (xy 80.300888 -174.374717) (xy 80.365147 -174.405662) (xy 80.425538 -174.443608)
			(xy 80.4813 -174.488077) (xy 80.531733 -174.53851) (xy 80.576202 -174.594272) (xy 80.614148 -174.654663)
			(xy 80.645093 -174.718922) (xy 80.66865 -174.786242) (xy 80.68452 -174.855777) (xy 80.692506 -174.926651)
			(xy 80.692506 -174.997973) (xy 80.68452 -175.068847) (xy 80.66865 -175.138382) (xy 80.645093 -175.205702)
			(xy 80.614148 -175.269961) (xy 80.576202 -175.330352) (xy 80.531733 -175.386114) (xy 80.4813 -175.436547)
			(xy 80.425538 -175.481016) (xy 80.365147 -175.518962) (xy 80.300888 -175.549907) (xy 80.233568 -175.573464)
			(xy 80.164033 -175.589334) (xy 80.093159 -175.59732) (xy 80.021837 -175.59732) (xy 79.950963 -175.589334)
			(xy 79.881428 -175.573464) (xy 79.814108 -175.549907) (xy 79.749849 -175.518962) (xy 79.689458 -175.481016)
			(xy 79.633696 -175.436547) (xy 79.583263 -175.386114) (xy 79.538794 -175.330352) (xy 79.500848 -175.269961)
			(xy 79.469903 -175.205702) (xy 79.446346 -175.138382) (xy 79.430476 -175.068847) (xy 79.42249 -174.997973)
			(xy 77.888092 -174.997973) (xy 77.880106 -175.068847) (xy 77.864236 -175.138382) (xy 77.840679 -175.205702)
			(xy 77.809734 -175.269961) (xy 77.771788 -175.330352) (xy 77.727319 -175.386114) (xy 77.676886 -175.436547)
			(xy 77.621124 -175.481016) (xy 77.560733 -175.518962) (xy 77.496474 -175.549907) (xy 77.429154 -175.573464)
			(xy 77.359619 -175.589334) (xy 77.288745 -175.59732) (xy 77.217423 -175.59732) (xy 77.146549 -175.589334)
			(xy 77.077014 -175.573464) (xy 77.009694 -175.549907) (xy 76.945435 -175.518962) (xy 76.885044 -175.481016)
			(xy 76.829282 -175.436547) (xy 76.778849 -175.386114) (xy 76.73438 -175.330352) (xy 76.696434 -175.269961)
			(xy 76.665489 -175.205702) (xy 76.641932 -175.138382) (xy 76.626062 -175.068847) (xy 76.618076 -174.997973)
			(xy 66.914505 -174.997973) (xy 64.77096 -177.141479) (xy 76.618076 -177.141479) (xy 76.618076 -177.070157)
			(xy 76.626062 -176.999283) (xy 76.641932 -176.929748) (xy 76.665489 -176.862428) (xy 76.696434 -176.798169)
			(xy 76.73438 -176.737778) (xy 76.778849 -176.682016) (xy 76.829282 -176.631583) (xy 76.885044 -176.587114)
			(xy 76.945435 -176.549168) (xy 77.009694 -176.518223) (xy 77.077014 -176.494666) (xy 77.146549 -176.478796)
			(xy 77.217423 -176.47081) (xy 77.253084 -176.47031) (xy 77.288745 -176.47081) (xy 77.359619 -176.478796)
			(xy 77.429154 -176.494666) (xy 77.496474 -176.518223) (xy 77.560733 -176.549168) (xy 77.621124 -176.587114)
			(xy 77.676886 -176.631583) (xy 77.727319 -176.682016) (xy 77.771788 -176.737778) (xy 77.809734 -176.798169)
			(xy 77.840679 -176.862428) (xy 77.864236 -176.929748) (xy 77.880106 -176.999283) (xy 77.888092 -177.070157)
			(xy 77.888092 -177.141479) (xy 79.42249 -177.141479) (xy 79.42249 -177.070157) (xy 79.430476 -176.999283)
			(xy 79.446346 -176.929748) (xy 79.469903 -176.862428) (xy 79.500848 -176.798169) (xy 79.538794 -176.737778)
			(xy 79.583263 -176.682016) (xy 79.633696 -176.631583) (xy 79.689458 -176.587114) (xy 79.749849 -176.549168)
			(xy 79.814108 -176.518223) (xy 79.881428 -176.494666) (xy 79.950963 -176.478796) (xy 80.021837 -176.47081)
			(xy 80.057498 -176.47031) (xy 80.093159 -176.47081) (xy 80.164033 -176.478796) (xy 80.233568 -176.494666)
			(xy 80.300888 -176.518223) (xy 80.365147 -176.549168) (xy 80.425538 -176.587114) (xy 80.4813 -176.631583)
			(xy 80.531733 -176.682016) (xy 80.576202 -176.737778) (xy 80.614148 -176.798169) (xy 80.645093 -176.862428)
			(xy 80.66865 -176.929748) (xy 80.68452 -176.999283) (xy 80.692506 -177.070157) (xy 80.692506 -177.141479)
			(xy 80.68452 -177.212353) (xy 80.66865 -177.281888) (xy 80.645093 -177.349208) (xy 80.614148 -177.413467)
			(xy 80.576202 -177.473858) (xy 80.531733 -177.52962) (xy 80.4813 -177.580053) (xy 80.425538 -177.624522)
			(xy 80.365147 -177.662468) (xy 80.300888 -177.693413) (xy 80.233568 -177.71697) (xy 80.164033 -177.73284)
			(xy 80.093159 -177.740826) (xy 80.021837 -177.740826) (xy 79.950963 -177.73284) (xy 79.881428 -177.71697)
			(xy 79.814108 -177.693413) (xy 79.749849 -177.662468) (xy 79.689458 -177.624522) (xy 79.633696 -177.580053)
			(xy 79.583263 -177.52962) (xy 79.538794 -177.473858) (xy 79.500848 -177.413467) (xy 79.469903 -177.349208)
			(xy 79.446346 -177.281888) (xy 79.430476 -177.212353) (xy 79.42249 -177.141479) (xy 77.888092 -177.141479)
			(xy 77.880106 -177.212353) (xy 77.864236 -177.281888) (xy 77.840679 -177.349208) (xy 77.809734 -177.413467)
			(xy 77.771788 -177.473858) (xy 77.727319 -177.52962) (xy 77.676886 -177.580053) (xy 77.621124 -177.624522)
			(xy 77.560733 -177.662468) (xy 77.496474 -177.693413) (xy 77.429154 -177.71697) (xy 77.359619 -177.73284)
			(xy 77.288745 -177.740826) (xy 77.217423 -177.740826) (xy 77.146549 -177.73284) (xy 77.077014 -177.71697)
			(xy 77.009694 -177.693413) (xy 76.945435 -177.662468) (xy 76.885044 -177.624522) (xy 76.829282 -177.580053)
			(xy 76.778849 -177.52962) (xy 76.73438 -177.473858) (xy 76.696434 -177.413467) (xy 76.665489 -177.349208)
			(xy 76.641932 -177.281888) (xy 76.626062 -177.212353) (xy 76.618076 -177.141479) (xy 64.77096 -177.141479)
			(xy 62.313058 -179.599336) (xy 30.953456 -179.599336) (xy 30.936822 -179.599896) (xy 30.904704 -179.608582)
			(xy 30.875922 -179.625274) (xy 30.863794 -179.636674) (xy 30.469332 -180.031136) (xy 30.453276 -180.047981)
			(xy 30.42692 -180.086328) (xy 30.407982 -180.128829) (xy 30.397092 -180.174068) (xy 30.394615 -180.220532)
			(xy 30.400633 -180.266671) (xy 30.414946 -180.310945) (xy 30.437075 -180.351877) (xy 30.466282 -180.388099)
			(xy 30.501592 -180.418402) (xy 30.541826 -180.441775) (xy 30.58564 -180.457438) (xy 30.608524 -180.461666)
			(xy 30.650963 -180.468894) (xy 30.734372 -180.490237) (xy 30.81548 -180.519117) (xy 30.893609 -180.55529)
			(xy 30.968103 -180.598455) (xy 31.038339 -180.648249) (xy 31.103728 -180.704256) (xy 31.163724 -180.766006)
			(xy 31.217823 -180.832983) (xy 31.265572 -180.904625) (xy 31.306571 -180.980333) (xy 31.340477 -181.059472)
			(xy 31.367006 -181.141379) (xy 31.385936 -181.225368) (xy 31.397109 -181.310737) (xy 31.400429 -181.396769)
			(xy 31.398482 -181.433486) (xy 34.599874 -181.433486) (xy 34.599874 -181.346586) (xy 34.607892 -181.260057)
			(xy 34.62386 -181.174637) (xy 34.647641 -181.091055) (xy 34.679033 -181.010023) (xy 34.717767 -180.932234)
			(xy 34.763514 -180.85835) (xy 34.815883 -180.789003) (xy 34.874427 -180.724783) (xy 34.938647 -180.666239)
			(xy 35.007994 -180.61387) (xy 35.081878 -180.568123) (xy 35.159667 -180.529389) (xy 35.240699 -180.497997)
			(xy 35.324281 -180.474216) (xy 35.409701 -180.458248) (xy 35.49623 -180.45023) (xy 35.53968 -180.449728)
			(xy 35.58313 -180.45023) (xy 35.669659 -180.458248) (xy 35.755079 -180.474216) (xy 35.838661 -180.497997)
			(xy 35.919693 -180.529389) (xy 35.997482 -180.568123) (xy 36.071366 -180.61387) (xy 36.140713 -180.666239)
			(xy 36.204933 -180.724783) (xy 36.263477 -180.789003) (xy 36.315846 -180.85835) (xy 36.361593 -180.932234)
			(xy 36.400327 -181.010023) (xy 36.431719 -181.091055) (xy 36.4555 -181.174637) (xy 36.471468 -181.260057)
			(xy 36.479486 -181.346586) (xy 36.479486 -181.433486) (xy 36.471468 -181.520015) (xy 36.4555 -181.605435)
			(xy 36.431719 -181.689017) (xy 36.400327 -181.770049) (xy 36.361593 -181.847838) (xy 36.315846 -181.921722)
			(xy 36.263477 -181.991069) (xy 36.204933 -182.055289) (xy 36.140713 -182.113833) (xy 36.071366 -182.166202)
			(xy 35.997482 -182.211949) (xy 35.919693 -182.250683) (xy 35.838661 -182.282075) (xy 35.755079 -182.305856)
			(xy 35.669659 -182.321824) (xy 35.58313 -182.329842) (xy 35.49623 -182.329842) (xy 35.409701 -182.321824)
			(xy 35.324281 -182.305856) (xy 35.240699 -182.282075) (xy 35.159667 -182.250683) (xy 35.081878 -182.211949)
			(xy 35.007994 -182.166202) (xy 34.938647 -182.113833) (xy 34.874427 -182.055289) (xy 34.815883 -181.991069)
			(xy 34.763514 -181.921722) (xy 34.717767 -181.847838) (xy 34.679033 -181.770049) (xy 34.647641 -181.689017)
			(xy 34.62386 -181.605435) (xy 34.607892 -181.520015) (xy 34.599874 -181.433486) (xy 31.398482 -181.433486)
			(xy 31.395871 -181.482744) (xy 31.383471 -181.567943) (xy 31.363335 -181.651651) (xy 31.33563 -181.733168)
			(xy 31.300588 -181.811811) (xy 31.258504 -181.886921) (xy 31.209729 -181.957868) (xy 31.154672 -182.02406)
			(xy 31.093794 -182.08494) (xy 31.027605 -182.140001) (xy 30.95666 -182.188779) (xy 30.881552 -182.230867)
			(xy 30.802912 -182.265913) (xy 30.721396 -182.293622) (xy 30.637689 -182.313763) (xy 30.552491 -182.326166)
			(xy 30.466515 -182.330729) (xy 30.380483 -182.327412) (xy 30.295114 -182.316245) (xy 30.211124 -182.297319)
			(xy 30.129215 -182.270794) (xy 30.050075 -182.236891) (xy 29.974365 -182.195896) (xy 29.902721 -182.14815)
			(xy 29.835741 -182.094055) (xy 29.773988 -182.034062) (xy 29.717978 -181.968676) (xy 29.66818 -181.898442)
			(xy 29.625011 -181.82395) (xy 29.588834 -181.745823) (xy 29.559951 -181.664716) (xy 29.538604 -181.581309)
			(xy 29.53131 -181.53888) (xy 29.527158 -181.515964) (xy 29.511544 -181.472091) (xy 29.488197 -181.431799)
			(xy 29.457898 -181.396435) (xy 29.421662 -181.367184) (xy 29.380704 -181.345026) (xy 29.336393 -181.330702)
			(xy 29.290214 -181.324693) (xy 29.243713 -181.327199) (xy 29.198447 -181.338136) (xy 29.155932 -181.357138)
			(xy 29.117592 -181.38357) (xy 29.10078 -181.399688) (xy 28.503626 -181.996842) (xy 28.492163 -182.008918)
			(xy 28.475474 -182.03772) (xy 28.466808 -182.069861) (xy 28.466288 -182.086504) (xy 28.466288 -183.973486)
			(xy 29.519874 -183.973486) (xy 29.519874 -183.886586) (xy 29.527892 -183.800057) (xy 29.54386 -183.714637)
			(xy 29.567641 -183.631055) (xy 29.599033 -183.550023) (xy 29.637767 -183.472234) (xy 29.683514 -183.39835)
			(xy 29.735883 -183.329003) (xy 29.794427 -183.264783) (xy 29.858647 -183.206239) (xy 29.927994 -183.15387)
			(xy 30.001878 -183.108123) (xy 30.079667 -183.069389) (xy 30.160699 -183.037997) (xy 30.244281 -183.014216)
			(xy 30.329701 -182.998248) (xy 30.41623 -182.99023) (xy 30.45968 -182.989728) (xy 30.50313 -182.99023)
			(xy 30.589659 -182.998248) (xy 30.675079 -183.014216) (xy 30.758661 -183.037997) (xy 30.839693 -183.069389)
			(xy 30.917482 -183.108123) (xy 30.991366 -183.15387) (xy 31.060713 -183.206239) (xy 31.124933 -183.264783)
			(xy 31.183477 -183.329003) (xy 31.235846 -183.39835) (xy 31.281593 -183.472234) (xy 31.320327 -183.550023)
			(xy 31.351719 -183.631055) (xy 31.3755 -183.714637) (xy 31.391468 -183.800057) (xy 31.399486 -183.886586)
			(xy 31.399486 -183.973486) (xy 34.599874 -183.973486) (xy 34.599874 -183.886586) (xy 34.607892 -183.800057)
			(xy 34.62386 -183.714637) (xy 34.647641 -183.631055) (xy 34.679033 -183.550023) (xy 34.717767 -183.472234)
			(xy 34.763514 -183.39835) (xy 34.815883 -183.329003) (xy 34.874427 -183.264783) (xy 34.938647 -183.206239)
			(xy 35.007994 -183.15387) (xy 35.081878 -183.108123) (xy 35.159667 -183.069389) (xy 35.240699 -183.037997)
			(xy 35.324281 -183.014216) (xy 35.409701 -182.998248) (xy 35.49623 -182.99023) (xy 35.53968 -182.989728)
			(xy 35.58313 -182.99023) (xy 35.669659 -182.998248) (xy 35.755079 -183.014216) (xy 35.838661 -183.037997)
			(xy 35.919693 -183.069389) (xy 35.997482 -183.108123) (xy 36.071366 -183.15387) (xy 36.140713 -183.206239)
			(xy 36.204933 -183.264783) (xy 36.263477 -183.329003) (xy 36.315846 -183.39835) (xy 36.361593 -183.472234)
			(xy 36.400327 -183.550023) (xy 36.431719 -183.631055) (xy 36.4555 -183.714637) (xy 36.471468 -183.800057)
			(xy 36.479486 -183.886586) (xy 36.479486 -183.973486) (xy 36.471468 -184.060015) (xy 36.4555 -184.145435)
			(xy 36.431719 -184.229017) (xy 36.400327 -184.310049) (xy 36.361593 -184.387838) (xy 36.315846 -184.461722)
			(xy 36.263477 -184.531069) (xy 36.204933 -184.595289) (xy 36.140713 -184.653833) (xy 36.104683 -184.681042)
			(xy 39.818568 -184.681042) (xy 39.824577 -184.565104) (xy 39.83857 -184.449857) (xy 39.860481 -184.335851)
			(xy 39.890206 -184.223627) (xy 39.927602 -184.113721) (xy 39.972491 -184.006658) (xy 40.02466 -183.902946)
			(xy 40.08386 -183.803081) (xy 40.149809 -183.707538) (xy 40.222192 -183.616772) (xy 40.300665 -183.531217)
			(xy 40.384853 -183.451279) (xy 40.474355 -183.37734) (xy 40.568746 -183.309752) (xy 40.667574 -183.248838)
			(xy 40.77037 -183.194886) (xy 40.876643 -183.148156) (xy 40.985887 -183.108868) (xy 41.09758 -183.077211)
			(xy 41.211192 -183.053335) (xy 41.32618 -183.037354) (xy 41.441997 -183.029345) (xy 41.500044 -183.028844)
			(xy 41.558091 -183.029345) (xy 41.673908 -183.037354) (xy 41.788896 -183.053335) (xy 41.902508 -183.077211)
			(xy 42.014201 -183.108868) (xy 42.123445 -183.148156) (xy 42.229718 -183.194886) (xy 42.332514 -183.248838)
			(xy 42.431342 -183.309752) (xy 42.475123 -183.341101) (xy 63.648083 -183.341101) (xy 63.654132 -183.265531)
			(xy 63.668179 -183.191033) (xy 63.690065 -183.11845) (xy 63.719542 -183.048604) (xy 63.756277 -182.982287)
			(xy 63.799852 -182.920251) (xy 63.849774 -182.863198) (xy 63.905478 -182.811774) (xy 63.966333 -182.766563)
			(xy 64.031648 -182.728076) (xy 64.100684 -182.69675) (xy 64.172659 -182.67294) (xy 64.246757 -182.656915)
			(xy 64.322138 -182.648856) (xy 64.360044 -182.648352) (xy 64.39795 -182.648856) (xy 64.473331 -182.656915)
			(xy 64.547429 -182.67294) (xy 64.619404 -182.69675) (xy 64.68844 -182.728076) (xy 64.753755 -182.766563)
			(xy 64.81461 -182.811774) (xy 64.870314 -182.863198) (xy 64.920236 -182.920251) (xy 64.963811 -182.982287)
			(xy 65.000546 -183.048604) (xy 65.030023 -183.11845) (xy 65.051909 -183.191033) (xy 65.065956 -183.265531)
			(xy 65.072005 -183.341101) (xy 66.188083 -183.341101) (xy 66.194132 -183.265531) (xy 66.208179 -183.191033)
			(xy 66.230065 -183.11845) (xy 66.259542 -183.048604) (xy 66.296277 -182.982287) (xy 66.339852 -182.920251)
			(xy 66.389774 -182.863198) (xy 66.445478 -182.811774) (xy 66.506333 -182.766563) (xy 66.571648 -182.728076)
			(xy 66.640684 -182.69675) (xy 66.712659 -182.67294) (xy 66.786757 -182.656915) (xy 66.862138 -182.648856)
			(xy 66.900044 -182.648352) (xy 66.93795 -182.648856) (xy 67.013331 -182.656915) (xy 67.087429 -182.67294)
			(xy 67.159404 -182.69675) (xy 67.22844 -182.728076) (xy 67.293755 -182.766563) (xy 67.35461 -182.811774)
			(xy 67.410314 -182.863198) (xy 67.460236 -182.920251) (xy 67.503811 -182.982287) (xy 67.540546 -183.048604)
			(xy 67.570023 -183.11845) (xy 67.591909 -183.191033) (xy 67.605956 -183.265531) (xy 67.612005 -183.341101)
			(xy 68.728083 -183.341101) (xy 68.734132 -183.265531) (xy 68.748179 -183.191033) (xy 68.770065 -183.11845)
			(xy 68.799542 -183.048604) (xy 68.836277 -182.982287) (xy 68.879852 -182.920251) (xy 68.929774 -182.863198)
			(xy 68.985478 -182.811774) (xy 69.046333 -182.766563) (xy 69.111648 -182.728076) (xy 69.180684 -182.69675)
			(xy 69.252659 -182.67294) (xy 69.326757 -182.656915) (xy 69.402138 -182.648856) (xy 69.440044 -182.648352)
			(xy 69.47795 -182.648856) (xy 69.553331 -182.656915) (xy 69.627429 -182.67294) (xy 69.699404 -182.69675)
			(xy 69.76844 -182.728076) (xy 69.833755 -182.766563) (xy 69.89461 -182.811774) (xy 69.950314 -182.863198)
			(xy 70.000236 -182.920251) (xy 70.043811 -182.982287) (xy 70.080546 -183.048604) (xy 70.110023 -183.11845)
			(xy 70.131909 -183.191033) (xy 70.145956 -183.265531) (xy 70.152005 -183.341101) (xy 71.268083 -183.341101)
			(xy 71.274132 -183.265531) (xy 71.288179 -183.191033) (xy 71.310065 -183.11845) (xy 71.339542 -183.048604)
			(xy 71.376277 -182.982287) (xy 71.419852 -182.920251) (xy 71.469774 -182.863198) (xy 71.525478 -182.811774)
			(xy 71.586333 -182.766563) (xy 71.651648 -182.728076) (xy 71.720684 -182.69675) (xy 71.792659 -182.67294)
			(xy 71.866757 -182.656915) (xy 71.942138 -182.648856) (xy 71.980044 -182.648352) (xy 72.01795 -182.648856)
			(xy 72.093331 -182.656915) (xy 72.167429 -182.67294) (xy 72.239404 -182.69675) (xy 72.30844 -182.728076)
			(xy 72.373755 -182.766563) (xy 72.43461 -182.811774) (xy 72.490314 -182.863198) (xy 72.540236 -182.920251)
			(xy 72.583811 -182.982287) (xy 72.620546 -183.048604) (xy 72.650023 -183.11845) (xy 72.671909 -183.191033)
			(xy 72.685956 -183.265531) (xy 72.692005 -183.341101) (xy 73.808083 -183.341101) (xy 73.814132 -183.265531)
			(xy 73.828179 -183.191033) (xy 73.850065 -183.11845) (xy 73.879542 -183.048604) (xy 73.916277 -182.982287)
			(xy 73.959852 -182.920251) (xy 74.009774 -182.863198) (xy 74.065478 -182.811774) (xy 74.126333 -182.766563)
			(xy 74.191648 -182.728076) (xy 74.260684 -182.69675) (xy 74.332659 -182.67294) (xy 74.406757 -182.656915)
			(xy 74.482138 -182.648856) (xy 74.520044 -182.648352) (xy 74.55795 -182.648856) (xy 74.633331 -182.656915)
			(xy 74.707429 -182.67294) (xy 74.779404 -182.69675) (xy 74.84844 -182.728076) (xy 74.913755 -182.766563)
			(xy 74.97461 -182.811774) (xy 75.030314 -182.863198) (xy 75.080236 -182.920251) (xy 75.123811 -182.982287)
			(xy 75.160546 -183.048604) (xy 75.190023 -183.11845) (xy 75.211909 -183.191033) (xy 75.225956 -183.265531)
			(xy 75.232005 -183.341101) (xy 76.348083 -183.341101) (xy 76.354132 -183.265531) (xy 76.368179 -183.191033)
			(xy 76.390065 -183.11845) (xy 76.419542 -183.048604) (xy 76.456277 -182.982287) (xy 76.499852 -182.920251)
			(xy 76.549774 -182.863198) (xy 76.605478 -182.811774) (xy 76.666333 -182.766563) (xy 76.731648 -182.728076)
			(xy 76.800684 -182.69675) (xy 76.872659 -182.67294) (xy 76.946757 -182.656915) (xy 77.022138 -182.648856)
			(xy 77.060044 -182.648352) (xy 77.09795 -182.648856) (xy 77.173331 -182.656915) (xy 77.247429 -182.67294)
			(xy 77.319404 -182.69675) (xy 77.38844 -182.728076) (xy 77.453755 -182.766563) (xy 77.51461 -182.811774)
			(xy 77.570314 -182.863198) (xy 77.620236 -182.920251) (xy 77.663811 -182.982287) (xy 77.700546 -183.048604)
			(xy 77.730023 -183.11845) (xy 77.751909 -183.191033) (xy 77.765956 -183.265531) (xy 77.772005 -183.341101)
			(xy 78.888083 -183.341101) (xy 78.894132 -183.265531) (xy 78.908179 -183.191033) (xy 78.930065 -183.11845)
			(xy 78.959542 -183.048604) (xy 78.996277 -182.982287) (xy 79.039852 -182.920251) (xy 79.089774 -182.863198)
			(xy 79.145478 -182.811774) (xy 79.206333 -182.766563) (xy 79.271648 -182.728076) (xy 79.340684 -182.69675)
			(xy 79.412659 -182.67294) (xy 79.486757 -182.656915) (xy 79.562138 -182.648856) (xy 79.600044 -182.648352)
			(xy 79.63795 -182.648856) (xy 79.713331 -182.656915) (xy 79.787429 -182.67294) (xy 79.859404 -182.69675)
			(xy 79.92844 -182.728076) (xy 79.993755 -182.766563) (xy 80.05461 -182.811774) (xy 80.110314 -182.863198)
			(xy 80.160236 -182.920251) (xy 80.203811 -182.982287) (xy 80.240546 -183.048604) (xy 80.270023 -183.11845)
			(xy 80.291909 -183.191033) (xy 80.305956 -183.265531) (xy 80.312005 -183.341101) (xy 81.428083 -183.341101)
			(xy 81.434132 -183.265531) (xy 81.448179 -183.191033) (xy 81.470065 -183.11845) (xy 81.499542 -183.048604)
			(xy 81.536277 -182.982287) (xy 81.579852 -182.920251) (xy 81.629774 -182.863198) (xy 81.685478 -182.811774)
			(xy 81.746333 -182.766563) (xy 81.811648 -182.728076) (xy 81.880684 -182.69675) (xy 81.952659 -182.67294)
			(xy 82.026757 -182.656915) (xy 82.102138 -182.648856) (xy 82.140044 -182.648352) (xy 82.17795 -182.648856)
			(xy 82.253331 -182.656915) (xy 82.327429 -182.67294) (xy 82.399404 -182.69675) (xy 82.46844 -182.728076)
			(xy 82.533755 -182.766563) (xy 82.560067 -182.786111) (xy 86.198203 -182.786111) (xy 86.204252 -182.710541)
			(xy 86.218299 -182.636043) (xy 86.240185 -182.56346) (xy 86.269662 -182.493614) (xy 86.306397 -182.427297)
			(xy 86.349972 -182.365261) (xy 86.399894 -182.308208) (xy 86.455598 -182.256784) (xy 86.516453 -182.211573)
			(xy 86.581768 -182.173086) (xy 86.650804 -182.14176) (xy 86.722779 -182.11795) (xy 86.796877 -182.101925)
			(xy 86.872258 -182.093866) (xy 86.910164 -182.093362) (xy 86.94807 -182.093866) (xy 87.023451 -182.101925)
			(xy 87.097549 -182.11795) (xy 87.169524 -182.14176) (xy 87.23856 -182.173086) (xy 87.303875 -182.211573)
			(xy 87.36473 -182.256784) (xy 87.420434 -182.308208) (xy 87.470356 -182.365261) (xy 87.513931 -182.427297)
			(xy 87.550666 -182.493614) (xy 87.580143 -182.56346) (xy 87.602029 -182.636043) (xy 87.616076 -182.710541)
			(xy 87.622125 -182.786111) (xy 87.620106 -182.861895) (xy 87.610044 -182.937035) (xy 87.592052 -183.01068)
			(xy 87.566334 -183.081996) (xy 87.533182 -183.150173) (xy 87.49297 -183.214441) (xy 87.446155 -183.27407)
			(xy 87.393267 -183.328386) (xy 87.334905 -183.376772) (xy 87.27173 -183.41868) (xy 87.204459 -183.453636)
			(xy 87.133854 -183.481243) (xy 87.060713 -183.501189) (xy 86.985868 -183.513248) (xy 86.910164 -183.517283)
			(xy 86.83446 -183.513248) (xy 86.759615 -183.501189) (xy 86.686474 -183.481243) (xy 86.615869 -183.453636)
			(xy 86.548598 -183.41868) (xy 86.485423 -183.376772) (xy 86.427061 -183.328386) (xy 86.374173 -183.27407)
			(xy 86.327358 -183.214441) (xy 86.287146 -183.150173) (xy 86.253994 -183.081996) (xy 86.228276 -183.01068)
			(xy 86.210284 -182.937035) (xy 86.200222 -182.861895) (xy 86.198203 -182.786111) (xy 82.560067 -182.786111)
			(xy 82.59461 -182.811774) (xy 82.650314 -182.863198) (xy 82.700236 -182.920251) (xy 82.743811 -182.982287)
			(xy 82.780546 -183.048604) (xy 82.810023 -183.11845) (xy 82.831909 -183.191033) (xy 82.845956 -183.265531)
			(xy 82.852005 -183.341101) (xy 82.849986 -183.416885) (xy 82.839924 -183.492025) (xy 82.821932 -183.56567)
			(xy 82.796214 -183.636986) (xy 82.763062 -183.705163) (xy 82.72285 -183.769431) (xy 82.676035 -183.82906)
			(xy 82.623147 -183.883376) (xy 82.564785 -183.931762) (xy 82.50161 -183.97367) (xy 82.434339 -184.008626)
			(xy 82.363734 -184.036233) (xy 82.290593 -184.056179) (xy 82.215748 -184.068238) (xy 82.140044 -184.072273)
			(xy 82.06434 -184.068238) (xy 81.989495 -184.056179) (xy 81.916354 -184.036233) (xy 81.845749 -184.008626)
			(xy 81.778478 -183.97367) (xy 81.715303 -183.931762) (xy 81.656941 -183.883376) (xy 81.604053 -183.82906)
			(xy 81.557238 -183.769431) (xy 81.517026 -183.705163) (xy 81.483874 -183.636986) (xy 81.458156 -183.56567)
			(xy 81.440164 -183.492025) (xy 81.430102 -183.416885) (xy 81.428083 -183.341101) (xy 80.312005 -183.341101)
			(xy 80.309986 -183.416885) (xy 80.299924 -183.492025) (xy 80.281932 -183.56567) (xy 80.256214 -183.636986)
			(xy 80.223062 -183.705163) (xy 80.18285 -183.769431) (xy 80.136035 -183.82906) (xy 80.083147 -183.883376)
			(xy 80.024785 -183.931762) (xy 79.96161 -183.97367) (xy 79.894339 -184.008626) (xy 79.823734 -184.036233)
			(xy 79.750593 -184.056179) (xy 79.675748 -184.068238) (xy 79.600044 -184.072273) (xy 79.52434 -184.068238)
			(xy 79.449495 -184.056179) (xy 79.376354 -184.036233) (xy 79.305749 -184.008626) (xy 79.238478 -183.97367)
			(xy 79.175303 -183.931762) (xy 79.116941 -183.883376) (xy 79.064053 -183.82906) (xy 79.017238 -183.769431)
			(xy 78.977026 -183.705163) (xy 78.943874 -183.636986) (xy 78.918156 -183.56567) (xy 78.900164 -183.492025)
			(xy 78.890102 -183.416885) (xy 78.888083 -183.341101) (xy 77.772005 -183.341101) (xy 77.769986 -183.416885)
			(xy 77.759924 -183.492025) (xy 77.741932 -183.56567) (xy 77.716214 -183.636986) (xy 77.683062 -183.705163)
			(xy 77.64285 -183.769431) (xy 77.596035 -183.82906) (xy 77.543147 -183.883376) (xy 77.484785 -183.931762)
			(xy 77.42161 -183.97367) (xy 77.354339 -184.008626) (xy 77.283734 -184.036233) (xy 77.210593 -184.056179)
			(xy 77.135748 -184.068238) (xy 77.060044 -184.072273) (xy 76.98434 -184.068238) (xy 76.909495 -184.056179)
			(xy 76.836354 -184.036233) (xy 76.765749 -184.008626) (xy 76.698478 -183.97367) (xy 76.635303 -183.931762)
			(xy 76.576941 -183.883376) (xy 76.524053 -183.82906) (xy 76.477238 -183.769431) (xy 76.437026 -183.705163)
			(xy 76.403874 -183.636986) (xy 76.378156 -183.56567) (xy 76.360164 -183.492025) (xy 76.350102 -183.416885)
			(xy 76.348083 -183.341101) (xy 75.232005 -183.341101) (xy 75.229986 -183.416885) (xy 75.219924 -183.492025)
			(xy 75.201932 -183.56567) (xy 75.176214 -183.636986) (xy 75.143062 -183.705163) (xy 75.10285 -183.769431)
			(xy 75.056035 -183.82906) (xy 75.003147 -183.883376) (xy 74.944785 -183.931762) (xy 74.88161 -183.97367)
			(xy 74.814339 -184.008626) (xy 74.743734 -184.036233) (xy 74.670593 -184.056179) (xy 74.595748 -184.068238)
			(xy 74.520044 -184.072273) (xy 74.44434 -184.068238) (xy 74.369495 -184.056179) (xy 74.296354 -184.036233)
			(xy 74.225749 -184.008626) (xy 74.158478 -183.97367) (xy 74.095303 -183.931762) (xy 74.036941 -183.883376)
			(xy 73.984053 -183.82906) (xy 73.937238 -183.769431) (xy 73.897026 -183.705163) (xy 73.863874 -183.636986)
			(xy 73.838156 -183.56567) (xy 73.820164 -183.492025) (xy 73.810102 -183.416885) (xy 73.808083 -183.341101)
			(xy 72.692005 -183.341101) (xy 72.689986 -183.416885) (xy 72.679924 -183.492025) (xy 72.661932 -183.56567)
			(xy 72.636214 -183.636986) (xy 72.603062 -183.705163) (xy 72.56285 -183.769431) (xy 72.516035 -183.82906)
			(xy 72.463147 -183.883376) (xy 72.404785 -183.931762) (xy 72.34161 -183.97367) (xy 72.274339 -184.008626)
			(xy 72.203734 -184.036233) (xy 72.130593 -184.056179) (xy 72.055748 -184.068238) (xy 71.980044 -184.072273)
			(xy 71.90434 -184.068238) (xy 71.829495 -184.056179) (xy 71.756354 -184.036233) (xy 71.685749 -184.008626)
			(xy 71.618478 -183.97367) (xy 71.555303 -183.931762) (xy 71.496941 -183.883376) (xy 71.444053 -183.82906)
			(xy 71.397238 -183.769431) (xy 71.357026 -183.705163) (xy 71.323874 -183.636986) (xy 71.298156 -183.56567)
			(xy 71.280164 -183.492025) (xy 71.270102 -183.416885) (xy 71.268083 -183.341101) (xy 70.152005 -183.341101)
			(xy 70.149986 -183.416885) (xy 70.139924 -183.492025) (xy 70.121932 -183.56567) (xy 70.096214 -183.636986)
			(xy 70.063062 -183.705163) (xy 70.02285 -183.769431) (xy 69.976035 -183.82906) (xy 69.923147 -183.883376)
			(xy 69.864785 -183.931762) (xy 69.80161 -183.97367) (xy 69.734339 -184.008626) (xy 69.663734 -184.036233)
			(xy 69.590593 -184.056179) (xy 69.515748 -184.068238) (xy 69.440044 -184.072273) (xy 69.36434 -184.068238)
			(xy 69.289495 -184.056179) (xy 69.216354 -184.036233) (xy 69.145749 -184.008626) (xy 69.078478 -183.97367)
			(xy 69.015303 -183.931762) (xy 68.956941 -183.883376) (xy 68.904053 -183.82906) (xy 68.857238 -183.769431)
			(xy 68.817026 -183.705163) (xy 68.783874 -183.636986) (xy 68.758156 -183.56567) (xy 68.740164 -183.492025)
			(xy 68.730102 -183.416885) (xy 68.728083 -183.341101) (xy 67.612005 -183.341101) (xy 67.609986 -183.416885)
			(xy 67.599924 -183.492025) (xy 67.581932 -183.56567) (xy 67.556214 -183.636986) (xy 67.523062 -183.705163)
			(xy 67.48285 -183.769431) (xy 67.436035 -183.82906) (xy 67.383147 -183.883376) (xy 67.324785 -183.931762)
			(xy 67.26161 -183.97367) (xy 67.194339 -184.008626) (xy 67.123734 -184.036233) (xy 67.050593 -184.056179)
			(xy 66.975748 -184.068238) (xy 66.900044 -184.072273) (xy 66.82434 -184.068238) (xy 66.749495 -184.056179)
			(xy 66.676354 -184.036233) (xy 66.605749 -184.008626) (xy 66.538478 -183.97367) (xy 66.475303 -183.931762)
			(xy 66.416941 -183.883376) (xy 66.364053 -183.82906) (xy 66.317238 -183.769431) (xy 66.277026 -183.705163)
			(xy 66.243874 -183.636986) (xy 66.218156 -183.56567) (xy 66.200164 -183.492025) (xy 66.190102 -183.416885)
			(xy 66.188083 -183.341101) (xy 65.072005 -183.341101) (xy 65.069986 -183.416885) (xy 65.059924 -183.492025)
			(xy 65.041932 -183.56567) (xy 65.016214 -183.636986) (xy 64.983062 -183.705163) (xy 64.94285 -183.769431)
			(xy 64.896035 -183.82906) (xy 64.843147 -183.883376) (xy 64.784785 -183.931762) (xy 64.72161 -183.97367)
			(xy 64.654339 -184.008626) (xy 64.583734 -184.036233) (xy 64.510593 -184.056179) (xy 64.435748 -184.068238)
			(xy 64.360044 -184.072273) (xy 64.28434 -184.068238) (xy 64.209495 -184.056179) (xy 64.136354 -184.036233)
			(xy 64.065749 -184.008626) (xy 63.998478 -183.97367) (xy 63.935303 -183.931762) (xy 63.876941 -183.883376)
			(xy 63.824053 -183.82906) (xy 63.777238 -183.769431) (xy 63.737026 -183.705163) (xy 63.703874 -183.636986)
			(xy 63.678156 -183.56567) (xy 63.660164 -183.492025) (xy 63.650102 -183.416885) (xy 63.648083 -183.341101)
			(xy 42.475123 -183.341101) (xy 42.525733 -183.37734) (xy 42.615235 -183.451279) (xy 42.699423 -183.531217)
			(xy 42.777896 -183.616772) (xy 42.850279 -183.707538) (xy 42.916228 -183.803081) (xy 42.975428 -183.902946)
			(xy 43.027597 -184.006658) (xy 43.072486 -184.113721) (xy 43.109882 -184.223627) (xy 43.139607 -184.335851)
			(xy 43.161518 -184.449857) (xy 43.175511 -184.565104) (xy 43.18152 -184.681042) (xy 43.179517 -184.797118)
			(xy 43.169509 -184.91278) (xy 43.151546 -185.027475) (xy 43.125713 -185.140658) (xy 43.092133 -185.251789)
			(xy 43.050965 -185.360338) (xy 43.002407 -185.465788) (xy 42.94669 -185.567637) (xy 42.884078 -185.6654)
			(xy 42.814871 -185.75861) (xy 42.739398 -185.846823) (xy 42.658019 -185.929619) (xy 42.571122 -186.006603)
			(xy 42.526271 -186.041121) (xy 63.648083 -186.041121) (xy 63.654132 -185.965551) (xy 63.668179 -185.891053)
			(xy 63.690065 -185.81847) (xy 63.719542 -185.748624) (xy 63.756277 -185.682307) (xy 63.799852 -185.620271)
			(xy 63.849774 -185.563218) (xy 63.905478 -185.511794) (xy 63.966333 -185.466583) (xy 64.031648 -185.428096)
			(xy 64.100684 -185.39677) (xy 64.172659 -185.37296) (xy 64.246757 -185.356935) (xy 64.322138 -185.348876)
			(xy 64.360044 -185.348372) (xy 64.39795 -185.348876) (xy 64.473331 -185.356935) (xy 64.547429 -185.37296)
			(xy 64.619404 -185.39677) (xy 64.68844 -185.428096) (xy 64.753755 -185.466583) (xy 64.81461 -185.511794)
			(xy 64.870314 -185.563218) (xy 64.920236 -185.620271) (xy 64.963811 -185.682307) (xy 65.000546 -185.748624)
			(xy 65.030023 -185.81847) (xy 65.051909 -185.891053) (xy 65.065956 -185.965551) (xy 65.072005 -186.041121)
			(xy 66.188083 -186.041121) (xy 66.194132 -185.965551) (xy 66.208179 -185.891053) (xy 66.230065 -185.81847)
			(xy 66.259542 -185.748624) (xy 66.296277 -185.682307) (xy 66.339852 -185.620271) (xy 66.389774 -185.563218)
			(xy 66.445478 -185.511794) (xy 66.506333 -185.466583) (xy 66.571648 -185.428096) (xy 66.640684 -185.39677)
			(xy 66.712659 -185.37296) (xy 66.786757 -185.356935) (xy 66.862138 -185.348876) (xy 66.900044 -185.348372)
			(xy 66.93795 -185.348876) (xy 67.013331 -185.356935) (xy 67.087429 -185.37296) (xy 67.159404 -185.39677)
			(xy 67.22844 -185.428096) (xy 67.293755 -185.466583) (xy 67.35461 -185.511794) (xy 67.410314 -185.563218)
			(xy 67.460236 -185.620271) (xy 67.503811 -185.682307) (xy 67.540546 -185.748624) (xy 67.570023 -185.81847)
			(xy 67.591909 -185.891053) (xy 67.605956 -185.965551) (xy 67.612005 -186.041121) (xy 68.728083 -186.041121)
			(xy 68.734132 -185.965551) (xy 68.748179 -185.891053) (xy 68.770065 -185.81847) (xy 68.799542 -185.748624)
			(xy 68.836277 -185.682307) (xy 68.879852 -185.620271) (xy 68.929774 -185.563218) (xy 68.985478 -185.511794)
			(xy 69.046333 -185.466583) (xy 69.111648 -185.428096) (xy 69.180684 -185.39677) (xy 69.252659 -185.37296)
			(xy 69.326757 -185.356935) (xy 69.402138 -185.348876) (xy 69.440044 -185.348372) (xy 69.47795 -185.348876)
			(xy 69.553331 -185.356935) (xy 69.627429 -185.37296) (xy 69.699404 -185.39677) (xy 69.76844 -185.428096)
			(xy 69.833755 -185.466583) (xy 69.89461 -185.511794) (xy 69.950314 -185.563218) (xy 70.000236 -185.620271)
			(xy 70.043811 -185.682307) (xy 70.080546 -185.748624) (xy 70.110023 -185.81847) (xy 70.131909 -185.891053)
			(xy 70.145956 -185.965551) (xy 70.152005 -186.041121) (xy 71.268083 -186.041121) (xy 71.274132 -185.965551)
			(xy 71.288179 -185.891053) (xy 71.310065 -185.81847) (xy 71.339542 -185.748624) (xy 71.376277 -185.682307)
			(xy 71.419852 -185.620271) (xy 71.469774 -185.563218) (xy 71.525478 -185.511794) (xy 71.586333 -185.466583)
			(xy 71.651648 -185.428096) (xy 71.720684 -185.39677) (xy 71.792659 -185.37296) (xy 71.866757 -185.356935)
			(xy 71.942138 -185.348876) (xy 71.980044 -185.348372) (xy 72.01795 -185.348876) (xy 72.093331 -185.356935)
			(xy 72.167429 -185.37296) (xy 72.239404 -185.39677) (xy 72.30844 -185.428096) (xy 72.373755 -185.466583)
			(xy 72.43461 -185.511794) (xy 72.490314 -185.563218) (xy 72.540236 -185.620271) (xy 72.583811 -185.682307)
			(xy 72.620546 -185.748624) (xy 72.650023 -185.81847) (xy 72.671909 -185.891053) (xy 72.685956 -185.965551)
			(xy 72.692005 -186.041121) (xy 73.808083 -186.041121) (xy 73.814132 -185.965551) (xy 73.828179 -185.891053)
			(xy 73.850065 -185.81847) (xy 73.879542 -185.748624) (xy 73.916277 -185.682307) (xy 73.959852 -185.620271)
			(xy 74.009774 -185.563218) (xy 74.065478 -185.511794) (xy 74.126333 -185.466583) (xy 74.191648 -185.428096)
			(xy 74.260684 -185.39677) (xy 74.332659 -185.37296) (xy 74.406757 -185.356935) (xy 74.482138 -185.348876)
			(xy 74.520044 -185.348372) (xy 74.55795 -185.348876) (xy 74.633331 -185.356935) (xy 74.707429 -185.37296)
			(xy 74.779404 -185.39677) (xy 74.84844 -185.428096) (xy 74.913755 -185.466583) (xy 74.97461 -185.511794)
			(xy 75.030314 -185.563218) (xy 75.080236 -185.620271) (xy 75.123811 -185.682307) (xy 75.160546 -185.748624)
			(xy 75.190023 -185.81847) (xy 75.211909 -185.891053) (xy 75.225956 -185.965551) (xy 75.232005 -186.041121)
			(xy 76.348083 -186.041121) (xy 76.354132 -185.965551) (xy 76.368179 -185.891053) (xy 76.390065 -185.81847)
			(xy 76.419542 -185.748624) (xy 76.456277 -185.682307) (xy 76.499852 -185.620271) (xy 76.549774 -185.563218)
			(xy 76.605478 -185.511794) (xy 76.666333 -185.466583) (xy 76.731648 -185.428096) (xy 76.800684 -185.39677)
			(xy 76.872659 -185.37296) (xy 76.946757 -185.356935) (xy 77.022138 -185.348876) (xy 77.060044 -185.348372)
			(xy 77.09795 -185.348876) (xy 77.173331 -185.356935) (xy 77.247429 -185.37296) (xy 77.319404 -185.39677)
			(xy 77.38844 -185.428096) (xy 77.453755 -185.466583) (xy 77.51461 -185.511794) (xy 77.570314 -185.563218)
			(xy 77.620236 -185.620271) (xy 77.663811 -185.682307) (xy 77.700546 -185.748624) (xy 77.730023 -185.81847)
			(xy 77.751909 -185.891053) (xy 77.765956 -185.965551) (xy 77.772005 -186.041121) (xy 78.888083 -186.041121)
			(xy 78.894132 -185.965551) (xy 78.908179 -185.891053) (xy 78.930065 -185.81847) (xy 78.959542 -185.748624)
			(xy 78.996277 -185.682307) (xy 79.039852 -185.620271) (xy 79.089774 -185.563218) (xy 79.145478 -185.511794)
			(xy 79.206333 -185.466583) (xy 79.271648 -185.428096) (xy 79.340684 -185.39677) (xy 79.412659 -185.37296)
			(xy 79.486757 -185.356935) (xy 79.562138 -185.348876) (xy 79.600044 -185.348372) (xy 79.63795 -185.348876)
			(xy 79.713331 -185.356935) (xy 79.787429 -185.37296) (xy 79.859404 -185.39677) (xy 79.92844 -185.428096)
			(xy 79.993755 -185.466583) (xy 80.05461 -185.511794) (xy 80.110314 -185.563218) (xy 80.160236 -185.620271)
			(xy 80.203811 -185.682307) (xy 80.240546 -185.748624) (xy 80.270023 -185.81847) (xy 80.291909 -185.891053)
			(xy 80.305956 -185.965551) (xy 80.312005 -186.041121) (xy 81.428083 -186.041121) (xy 81.434132 -185.965551)
			(xy 81.448179 -185.891053) (xy 81.470065 -185.81847) (xy 81.499542 -185.748624) (xy 81.536277 -185.682307)
			(xy 81.579852 -185.620271) (xy 81.629774 -185.563218) (xy 81.685478 -185.511794) (xy 81.746333 -185.466583)
			(xy 81.811648 -185.428096) (xy 81.880684 -185.39677) (xy 81.952659 -185.37296) (xy 82.026757 -185.356935)
			(xy 82.102138 -185.348876) (xy 82.140044 -185.348372) (xy 82.17795 -185.348876) (xy 82.253331 -185.356935)
			(xy 82.327429 -185.37296) (xy 82.399404 -185.39677) (xy 82.46844 -185.428096) (xy 82.533755 -185.466583)
			(xy 82.59461 -185.511794) (xy 82.650314 -185.563218) (xy 82.700236 -185.620271) (xy 82.743811 -185.682307)
			(xy 82.780546 -185.748624) (xy 82.810023 -185.81847) (xy 82.831909 -185.891053) (xy 82.845956 -185.965551)
			(xy 82.852005 -186.041121) (xy 82.849986 -186.116905) (xy 82.839924 -186.192045) (xy 82.821932 -186.26569)
			(xy 82.796214 -186.337006) (xy 82.763062 -186.405183) (xy 82.72285 -186.469451) (xy 82.676035 -186.52908)
			(xy 82.623147 -186.583396) (xy 82.564785 -186.631782) (xy 82.50161 -186.67369) (xy 82.434339 -186.708646)
			(xy 82.363734 -186.736253) (xy 82.290593 -186.756199) (xy 82.215748 -186.768258) (xy 82.140044 -186.772293)
			(xy 82.06434 -186.768258) (xy 81.989495 -186.756199) (xy 81.916354 -186.736253) (xy 81.845749 -186.708646)
			(xy 81.778478 -186.67369) (xy 81.715303 -186.631782) (xy 81.656941 -186.583396) (xy 81.604053 -186.52908)
			(xy 81.557238 -186.469451) (xy 81.517026 -186.405183) (xy 81.483874 -186.337006) (xy 81.458156 -186.26569)
			(xy 81.440164 -186.192045) (xy 81.430102 -186.116905) (xy 81.428083 -186.041121) (xy 80.312005 -186.041121)
			(xy 80.309986 -186.116905) (xy 80.299924 -186.192045) (xy 80.281932 -186.26569) (xy 80.256214 -186.337006)
			(xy 80.223062 -186.405183) (xy 80.18285 -186.469451) (xy 80.136035 -186.52908) (xy 80.083147 -186.583396)
			(xy 80.024785 -186.631782) (xy 79.96161 -186.67369) (xy 79.894339 -186.708646) (xy 79.823734 -186.736253)
			(xy 79.750593 -186.756199) (xy 79.675748 -186.768258) (xy 79.600044 -186.772293) (xy 79.52434 -186.768258)
			(xy 79.449495 -186.756199) (xy 79.376354 -186.736253) (xy 79.305749 -186.708646) (xy 79.238478 -186.67369)
			(xy 79.175303 -186.631782) (xy 79.116941 -186.583396) (xy 79.064053 -186.52908) (xy 79.017238 -186.469451)
			(xy 78.977026 -186.405183) (xy 78.943874 -186.337006) (xy 78.918156 -186.26569) (xy 78.900164 -186.192045)
			(xy 78.890102 -186.116905) (xy 78.888083 -186.041121) (xy 77.772005 -186.041121) (xy 77.769986 -186.116905)
			(xy 77.759924 -186.192045) (xy 77.741932 -186.26569) (xy 77.716214 -186.337006) (xy 77.683062 -186.405183)
			(xy 77.64285 -186.469451) (xy 77.596035 -186.52908) (xy 77.543147 -186.583396) (xy 77.484785 -186.631782)
			(xy 77.42161 -186.67369) (xy 77.354339 -186.708646) (xy 77.283734 -186.736253) (xy 77.210593 -186.756199)
			(xy 77.135748 -186.768258) (xy 77.060044 -186.772293) (xy 76.98434 -186.768258) (xy 76.909495 -186.756199)
			(xy 76.836354 -186.736253) (xy 76.765749 -186.708646) (xy 76.698478 -186.67369) (xy 76.635303 -186.631782)
			(xy 76.576941 -186.583396) (xy 76.524053 -186.52908) (xy 76.477238 -186.469451) (xy 76.437026 -186.405183)
			(xy 76.403874 -186.337006) (xy 76.378156 -186.26569) (xy 76.360164 -186.192045) (xy 76.350102 -186.116905)
			(xy 76.348083 -186.041121) (xy 75.232005 -186.041121) (xy 75.229986 -186.116905) (xy 75.219924 -186.192045)
			(xy 75.201932 -186.26569) (xy 75.176214 -186.337006) (xy 75.143062 -186.405183) (xy 75.10285 -186.469451)
			(xy 75.056035 -186.52908) (xy 75.003147 -186.583396) (xy 74.944785 -186.631782) (xy 74.88161 -186.67369)
			(xy 74.814339 -186.708646) (xy 74.743734 -186.736253) (xy 74.670593 -186.756199) (xy 74.595748 -186.768258)
			(xy 74.520044 -186.772293) (xy 74.44434 -186.768258) (xy 74.369495 -186.756199) (xy 74.296354 -186.736253)
			(xy 74.225749 -186.708646) (xy 74.158478 -186.67369) (xy 74.095303 -186.631782) (xy 74.036941 -186.583396)
			(xy 73.984053 -186.52908) (xy 73.937238 -186.469451) (xy 73.897026 -186.405183) (xy 73.863874 -186.337006)
			(xy 73.838156 -186.26569) (xy 73.820164 -186.192045) (xy 73.810102 -186.116905) (xy 73.808083 -186.041121)
			(xy 72.692005 -186.041121) (xy 72.689986 -186.116905) (xy 72.679924 -186.192045) (xy 72.661932 -186.26569)
			(xy 72.636214 -186.337006) (xy 72.603062 -186.405183) (xy 72.56285 -186.469451) (xy 72.516035 -186.52908)
			(xy 72.463147 -186.583396) (xy 72.404785 -186.631782) (xy 72.34161 -186.67369) (xy 72.274339 -186.708646)
			(xy 72.203734 -186.736253) (xy 72.130593 -186.756199) (xy 72.055748 -186.768258) (xy 71.980044 -186.772293)
			(xy 71.90434 -186.768258) (xy 71.829495 -186.756199) (xy 71.756354 -186.736253) (xy 71.685749 -186.708646)
			(xy 71.618478 -186.67369) (xy 71.555303 -186.631782) (xy 71.496941 -186.583396) (xy 71.444053 -186.52908)
			(xy 71.397238 -186.469451) (xy 71.357026 -186.405183) (xy 71.323874 -186.337006) (xy 71.298156 -186.26569)
			(xy 71.280164 -186.192045) (xy 71.270102 -186.116905) (xy 71.268083 -186.041121) (xy 70.152005 -186.041121)
			(xy 70.149986 -186.116905) (xy 70.139924 -186.192045) (xy 70.121932 -186.26569) (xy 70.096214 -186.337006)
			(xy 70.063062 -186.405183) (xy 70.02285 -186.469451) (xy 69.976035 -186.52908) (xy 69.923147 -186.583396)
			(xy 69.864785 -186.631782) (xy 69.80161 -186.67369) (xy 69.734339 -186.708646) (xy 69.663734 -186.736253)
			(xy 69.590593 -186.756199) (xy 69.515748 -186.768258) (xy 69.440044 -186.772293) (xy 69.36434 -186.768258)
			(xy 69.289495 -186.756199) (xy 69.216354 -186.736253) (xy 69.145749 -186.708646) (xy 69.078478 -186.67369)
			(xy 69.015303 -186.631782) (xy 68.956941 -186.583396) (xy 68.904053 -186.52908) (xy 68.857238 -186.469451)
			(xy 68.817026 -186.405183) (xy 68.783874 -186.337006) (xy 68.758156 -186.26569) (xy 68.740164 -186.192045)
			(xy 68.730102 -186.116905) (xy 68.728083 -186.041121) (xy 67.612005 -186.041121) (xy 67.609986 -186.116905)
			(xy 67.599924 -186.192045) (xy 67.581932 -186.26569) (xy 67.556214 -186.337006) (xy 67.523062 -186.405183)
			(xy 67.48285 -186.469451) (xy 67.436035 -186.52908) (xy 67.383147 -186.583396) (xy 67.324785 -186.631782)
			(xy 67.26161 -186.67369) (xy 67.194339 -186.708646) (xy 67.123734 -186.736253) (xy 67.050593 -186.756199)
			(xy 66.975748 -186.768258) (xy 66.900044 -186.772293) (xy 66.82434 -186.768258) (xy 66.749495 -186.756199)
			(xy 66.676354 -186.736253) (xy 66.605749 -186.708646) (xy 66.538478 -186.67369) (xy 66.475303 -186.631782)
			(xy 66.416941 -186.583396) (xy 66.364053 -186.52908) (xy 66.317238 -186.469451) (xy 66.277026 -186.405183)
			(xy 66.243874 -186.337006) (xy 66.218156 -186.26569) (xy 66.200164 -186.192045) (xy 66.190102 -186.116905)
			(xy 66.188083 -186.041121) (xy 65.072005 -186.041121) (xy 65.069986 -186.116905) (xy 65.059924 -186.192045)
			(xy 65.041932 -186.26569) (xy 65.016214 -186.337006) (xy 64.983062 -186.405183) (xy 64.94285 -186.469451)
			(xy 64.896035 -186.52908) (xy 64.843147 -186.583396) (xy 64.784785 -186.631782) (xy 64.72161 -186.67369)
			(xy 64.654339 -186.708646) (xy 64.583734 -186.736253) (xy 64.510593 -186.756199) (xy 64.435748 -186.768258)
			(xy 64.360044 -186.772293) (xy 64.28434 -186.768258) (xy 64.209495 -186.756199) (xy 64.136354 -186.736253)
			(xy 64.065749 -186.708646) (xy 63.998478 -186.67369) (xy 63.935303 -186.631782) (xy 63.876941 -186.583396)
			(xy 63.824053 -186.52908) (xy 63.777238 -186.469451) (xy 63.737026 -186.405183) (xy 63.703874 -186.337006)
			(xy 63.678156 -186.26569) (xy 63.660164 -186.192045) (xy 63.650102 -186.116905) (xy 63.648083 -186.041121)
			(xy 42.526271 -186.041121) (xy 42.479121 -186.077408) (xy 42.382454 -186.141698) (xy 42.281582 -186.199165)
			(xy 42.176985 -186.249536) (xy 42.069162 -186.292571) (xy 41.958628 -186.328065) (xy 41.845908 -186.355848)
			(xy 41.73154 -186.375788) (xy 41.616068 -186.38779) (xy 41.500044 -186.391797) (xy 41.38402 -186.38779)
			(xy 41.268548 -186.375788) (xy 41.15418 -186.355848) (xy 41.04146 -186.328065) (xy 40.930926 -186.292571)
			(xy 40.823103 -186.249536) (xy 40.718506 -186.199165) (xy 40.617634 -186.141698) (xy 40.520967 -186.077408)
			(xy 40.428966 -186.006603) (xy 40.342069 -185.929619) (xy 40.26069 -185.846823) (xy 40.185217 -185.75861)
			(xy 40.11601 -185.6654) (xy 40.053398 -185.567637) (xy 39.997681 -185.465788) (xy 39.949123 -185.360338)
			(xy 39.907955 -185.251789) (xy 39.874375 -185.140658) (xy 39.848542 -185.027475) (xy 39.830579 -184.91278)
			(xy 39.820571 -184.797118) (xy 39.818568 -184.681042) (xy 36.104683 -184.681042) (xy 36.071366 -184.706202)
			(xy 35.997482 -184.751949) (xy 35.919693 -184.790683) (xy 35.838661 -184.822075) (xy 35.755079 -184.845856)
			(xy 35.669659 -184.861824) (xy 35.58313 -184.869842) (xy 35.49623 -184.869842) (xy 35.409701 -184.861824)
			(xy 35.324281 -184.845856) (xy 35.240699 -184.822075) (xy 35.159667 -184.790683) (xy 35.081878 -184.751949)
			(xy 35.007994 -184.706202) (xy 34.938647 -184.653833) (xy 34.874427 -184.595289) (xy 34.815883 -184.531069)
			(xy 34.763514 -184.461722) (xy 34.717767 -184.387838) (xy 34.679033 -184.310049) (xy 34.647641 -184.229017)
			(xy 34.62386 -184.145435) (xy 34.607892 -184.060015) (xy 34.599874 -183.973486) (xy 31.399486 -183.973486)
			(xy 31.391468 -184.060015) (xy 31.3755 -184.145435) (xy 31.351719 -184.229017) (xy 31.320327 -184.310049)
			(xy 31.281593 -184.387838) (xy 31.235846 -184.461722) (xy 31.183477 -184.531069) (xy 31.124933 -184.595289)
			(xy 31.060713 -184.653833) (xy 30.991366 -184.706202) (xy 30.917482 -184.751949) (xy 30.839693 -184.790683)
			(xy 30.758661 -184.822075) (xy 30.675079 -184.845856) (xy 30.589659 -184.861824) (xy 30.50313 -184.869842)
			(xy 30.41623 -184.869842) (xy 30.329701 -184.861824) (xy 30.244281 -184.845856) (xy 30.160699 -184.822075)
			(xy 30.079667 -184.790683) (xy 30.001878 -184.751949) (xy 29.927994 -184.706202) (xy 29.858647 -184.653833)
			(xy 29.794427 -184.595289) (xy 29.735883 -184.531069) (xy 29.683514 -184.461722) (xy 29.637767 -184.387838)
			(xy 29.599033 -184.310049) (xy 29.567641 -184.229017) (xy 29.54386 -184.145435) (xy 29.527892 -184.060015)
			(xy 29.519874 -183.973486) (xy 28.466288 -183.973486) (xy 28.466288 -186.513486) (xy 29.519874 -186.513486)
			(xy 29.519874 -186.426586) (xy 29.527892 -186.340057) (xy 29.54386 -186.254637) (xy 29.567641 -186.171055)
			(xy 29.599033 -186.090023) (xy 29.637767 -186.012234) (xy 29.683514 -185.93835) (xy 29.735883 -185.869003)
			(xy 29.794427 -185.804783) (xy 29.858647 -185.746239) (xy 29.927994 -185.69387) (xy 30.001878 -185.648123)
			(xy 30.079667 -185.609389) (xy 30.160699 -185.577997) (xy 30.244281 -185.554216) (xy 30.329701 -185.538248)
			(xy 30.41623 -185.53023) (xy 30.45968 -185.529728) (xy 30.50313 -185.53023) (xy 30.589659 -185.538248)
			(xy 30.675079 -185.554216) (xy 30.758661 -185.577997) (xy 30.839693 -185.609389) (xy 30.917482 -185.648123)
			(xy 30.991366 -185.69387) (xy 31.060713 -185.746239) (xy 31.124933 -185.804783) (xy 31.183477 -185.869003)
			(xy 31.235846 -185.93835) (xy 31.281593 -186.012234) (xy 31.320327 -186.090023) (xy 31.351719 -186.171055)
			(xy 31.3755 -186.254637) (xy 31.391468 -186.340057) (xy 31.399486 -186.426586) (xy 31.399486 -186.513486)
			(xy 34.599874 -186.513486) (xy 34.599874 -186.426586) (xy 34.607892 -186.340057) (xy 34.62386 -186.254637)
			(xy 34.647641 -186.171055) (xy 34.679033 -186.090023) (xy 34.717767 -186.012234) (xy 34.763514 -185.93835)
			(xy 34.815883 -185.869003) (xy 34.874427 -185.804783) (xy 34.938647 -185.746239) (xy 35.007994 -185.69387)
			(xy 35.081878 -185.648123) (xy 35.159667 -185.609389) (xy 35.240699 -185.577997) (xy 35.324281 -185.554216)
			(xy 35.409701 -185.538248) (xy 35.49623 -185.53023) (xy 35.53968 -185.529728) (xy 35.58313 -185.53023)
			(xy 35.669659 -185.538248) (xy 35.755079 -185.554216) (xy 35.838661 -185.577997) (xy 35.919693 -185.609389)
			(xy 35.997482 -185.648123) (xy 36.071366 -185.69387) (xy 36.140713 -185.746239) (xy 36.204933 -185.804783)
			(xy 36.263477 -185.869003) (xy 36.315846 -185.93835) (xy 36.361593 -186.012234) (xy 36.400327 -186.090023)
			(xy 36.431719 -186.171055) (xy 36.4555 -186.254637) (xy 36.471468 -186.340057) (xy 36.479486 -186.426586)
			(xy 36.479486 -186.513486) (xy 36.471468 -186.600015) (xy 36.4555 -186.685435) (xy 36.431719 -186.769017)
			(xy 36.400327 -186.850049) (xy 36.361593 -186.927838) (xy 36.315846 -187.001722) (xy 36.263477 -187.071069)
			(xy 36.204933 -187.135289) (xy 36.140713 -187.193833) (xy 36.071366 -187.246202) (xy 35.997482 -187.291949)
			(xy 35.919693 -187.330683) (xy 35.838661 -187.362075) (xy 35.755079 -187.385856) (xy 35.669659 -187.401824)
			(xy 35.58313 -187.409842) (xy 35.49623 -187.409842) (xy 35.409701 -187.401824) (xy 35.324281 -187.385856)
			(xy 35.240699 -187.362075) (xy 35.159667 -187.330683) (xy 35.081878 -187.291949) (xy 35.007994 -187.246202)
			(xy 34.938647 -187.193833) (xy 34.874427 -187.135289) (xy 34.815883 -187.071069) (xy 34.763514 -187.001722)
			(xy 34.717767 -186.927838) (xy 34.679033 -186.850049) (xy 34.647641 -186.769017) (xy 34.62386 -186.685435)
			(xy 34.607892 -186.600015) (xy 34.599874 -186.513486) (xy 31.399486 -186.513486) (xy 31.391468 -186.600015)
			(xy 31.3755 -186.685435) (xy 31.351719 -186.769017) (xy 31.320327 -186.850049) (xy 31.281593 -186.927838)
			(xy 31.235846 -187.001722) (xy 31.183477 -187.071069) (xy 31.124933 -187.135289) (xy 31.060713 -187.193833)
			(xy 30.991366 -187.246202) (xy 30.917482 -187.291949) (xy 30.839693 -187.330683) (xy 30.758661 -187.362075)
			(xy 30.675079 -187.385856) (xy 30.589659 -187.401824) (xy 30.50313 -187.409842) (xy 30.41623 -187.409842)
			(xy 30.329701 -187.401824) (xy 30.244281 -187.385856) (xy 30.160699 -187.362075) (xy 30.079667 -187.330683)
			(xy 30.001878 -187.291949) (xy 29.927994 -187.246202) (xy 29.858647 -187.193833) (xy 29.794427 -187.135289)
			(xy 29.735883 -187.071069) (xy 29.683514 -187.001722) (xy 29.637767 -186.927838) (xy 29.599033 -186.850049)
			(xy 29.567641 -186.769017) (xy 29.54386 -186.685435) (xy 29.527892 -186.600015) (xy 29.519874 -186.513486)
			(xy 28.466288 -186.513486) (xy 28.466288 -189.053486) (xy 29.519874 -189.053486) (xy 29.519874 -188.966586)
			(xy 29.527892 -188.880057) (xy 29.54386 -188.794637) (xy 29.567641 -188.711055) (xy 29.599033 -188.630023)
			(xy 29.637767 -188.552234) (xy 29.683514 -188.47835) (xy 29.735883 -188.409003) (xy 29.794427 -188.344783)
			(xy 29.858647 -188.286239) (xy 29.927994 -188.23387) (xy 30.001878 -188.188123) (xy 30.079667 -188.149389)
			(xy 30.160699 -188.117997) (xy 30.244281 -188.094216) (xy 30.329701 -188.078248) (xy 30.41623 -188.07023)
			(xy 30.45968 -188.069728) (xy 30.50313 -188.07023) (xy 30.589659 -188.078248) (xy 30.675079 -188.094216)
			(xy 30.758661 -188.117997) (xy 30.839693 -188.149389) (xy 30.917482 -188.188123) (xy 30.991366 -188.23387)
			(xy 31.060713 -188.286239) (xy 31.124933 -188.344783) (xy 31.183477 -188.409003) (xy 31.235846 -188.47835)
			(xy 31.281593 -188.552234) (xy 31.320327 -188.630023) (xy 31.351719 -188.711055) (xy 31.3755 -188.794637)
			(xy 31.391468 -188.880057) (xy 31.399486 -188.966586) (xy 31.399486 -189.053486) (xy 34.599874 -189.053486)
			(xy 34.599874 -188.966586) (xy 34.607892 -188.880057) (xy 34.62386 -188.794637) (xy 34.647641 -188.711055)
			(xy 34.679033 -188.630023) (xy 34.717767 -188.552234) (xy 34.763514 -188.47835) (xy 34.815883 -188.409003)
			(xy 34.874427 -188.344783) (xy 34.938647 -188.286239) (xy 35.007994 -188.23387) (xy 35.081878 -188.188123)
			(xy 35.159667 -188.149389) (xy 35.240699 -188.117997) (xy 35.324281 -188.094216) (xy 35.409701 -188.078248)
			(xy 35.49623 -188.07023) (xy 35.53968 -188.069728) (xy 35.58313 -188.07023) (xy 35.669659 -188.078248)
			(xy 35.755079 -188.094216) (xy 35.838661 -188.117997) (xy 35.919693 -188.149389) (xy 35.997482 -188.188123)
			(xy 36.071366 -188.23387) (xy 36.140713 -188.286239) (xy 36.204933 -188.344783) (xy 36.263477 -188.409003)
			(xy 36.315846 -188.47835) (xy 36.361593 -188.552234) (xy 36.400327 -188.630023) (xy 36.431719 -188.711055)
			(xy 36.4555 -188.794637) (xy 36.471468 -188.880057) (xy 36.479486 -188.966586) (xy 36.479486 -189.053486)
			(xy 36.471468 -189.140015) (xy 36.4555 -189.225435) (xy 36.431719 -189.309017) (xy 36.400327 -189.390049)
			(xy 36.361593 -189.467838) (xy 36.315846 -189.541722) (xy 36.263477 -189.611069) (xy 36.204933 -189.675289)
			(xy 36.140713 -189.733833) (xy 36.071366 -189.786202) (xy 35.997482 -189.831949) (xy 35.919693 -189.870683)
			(xy 35.838661 -189.902075) (xy 35.755079 -189.925856) (xy 35.669659 -189.941824) (xy 35.58313 -189.949842)
			(xy 35.49623 -189.949842) (xy 35.409701 -189.941824) (xy 35.324281 -189.925856) (xy 35.240699 -189.902075)
			(xy 35.159667 -189.870683) (xy 35.081878 -189.831949) (xy 35.007994 -189.786202) (xy 34.938647 -189.733833)
			(xy 34.874427 -189.675289) (xy 34.815883 -189.611069) (xy 34.763514 -189.541722) (xy 34.717767 -189.467838)
			(xy 34.679033 -189.390049) (xy 34.647641 -189.309017) (xy 34.62386 -189.225435) (xy 34.607892 -189.140015)
			(xy 34.599874 -189.053486) (xy 31.399486 -189.053486) (xy 31.391468 -189.140015) (xy 31.3755 -189.225435)
			(xy 31.351719 -189.309017) (xy 31.320327 -189.390049) (xy 31.281593 -189.467838) (xy 31.235846 -189.541722)
			(xy 31.183477 -189.611069) (xy 31.124933 -189.675289) (xy 31.060713 -189.733833) (xy 30.991366 -189.786202)
			(xy 30.917482 -189.831949) (xy 30.839693 -189.870683) (xy 30.758661 -189.902075) (xy 30.675079 -189.925856)
			(xy 30.589659 -189.941824) (xy 30.50313 -189.949842) (xy 30.41623 -189.949842) (xy 30.329701 -189.941824)
			(xy 30.244281 -189.925856) (xy 30.160699 -189.902075) (xy 30.079667 -189.870683) (xy 30.001878 -189.831949)
			(xy 29.927994 -189.786202) (xy 29.858647 -189.733833) (xy 29.794427 -189.675289) (xy 29.735883 -189.611069)
			(xy 29.683514 -189.541722) (xy 29.637767 -189.467838) (xy 29.599033 -189.390049) (xy 29.567641 -189.309017)
			(xy 29.54386 -189.225435) (xy 29.527892 -189.140015) (xy 29.519874 -189.053486) (xy 28.466288 -189.053486)
			(xy 28.466288 -191.593486) (xy 29.519874 -191.593486) (xy 29.519874 -191.506586) (xy 29.527892 -191.420057)
			(xy 29.54386 -191.334637) (xy 29.567641 -191.251055) (xy 29.599033 -191.170023) (xy 29.637767 -191.092234)
			(xy 29.683514 -191.01835) (xy 29.735883 -190.949003) (xy 29.794427 -190.884783) (xy 29.858647 -190.826239)
			(xy 29.927994 -190.77387) (xy 30.001878 -190.728123) (xy 30.079667 -190.689389) (xy 30.160699 -190.657997)
			(xy 30.244281 -190.634216) (xy 30.329701 -190.618248) (xy 30.41623 -190.61023) (xy 30.45968 -190.609728)
			(xy 30.50313 -190.61023) (xy 30.589659 -190.618248) (xy 30.675079 -190.634216) (xy 30.758661 -190.657997)
			(xy 30.839693 -190.689389) (xy 30.917482 -190.728123) (xy 30.991366 -190.77387) (xy 31.060713 -190.826239)
			(xy 31.124933 -190.884783) (xy 31.183477 -190.949003) (xy 31.235846 -191.01835) (xy 31.281593 -191.092234)
			(xy 31.320327 -191.170023) (xy 31.351719 -191.251055) (xy 31.3755 -191.334637) (xy 31.391468 -191.420057)
			(xy 31.399486 -191.506586) (xy 31.399486 -191.593486) (xy 34.599874 -191.593486) (xy 34.599874 -191.506586)
			(xy 34.607892 -191.420057) (xy 34.62386 -191.334637) (xy 34.647641 -191.251055) (xy 34.679033 -191.170023)
			(xy 34.717767 -191.092234) (xy 34.763514 -191.01835) (xy 34.815883 -190.949003) (xy 34.874427 -190.884783)
			(xy 34.938647 -190.826239) (xy 35.007994 -190.77387) (xy 35.081878 -190.728123) (xy 35.159667 -190.689389)
			(xy 35.240699 -190.657997) (xy 35.324281 -190.634216) (xy 35.409701 -190.618248) (xy 35.49623 -190.61023)
			(xy 35.53968 -190.609728) (xy 35.58313 -190.61023) (xy 35.669659 -190.618248) (xy 35.755079 -190.634216)
			(xy 35.838661 -190.657997) (xy 35.919693 -190.689389) (xy 35.997482 -190.728123) (xy 36.042586 -190.75605)
			(xy 39.397177 -190.75605) (xy 39.403277 -190.700613) (xy 39.417383 -190.646656) (xy 39.439195 -190.595327)
			(xy 39.468249 -190.547721) (xy 39.503924 -190.504853) (xy 39.545461 -190.467636) (xy 39.591974 -190.436863)
			(xy 39.642471 -190.413191) (xy 39.695878 -190.397123) (xy 39.751054 -190.389003) (xy 39.77894 -190.388494)
			(xy 39.806826 -190.389003) (xy 39.862002 -190.397123) (xy 39.915409 -190.413191) (xy 39.965906 -190.436863)
			(xy 40.012419 -190.467636) (xy 40.053956 -190.504853) (xy 40.089631 -190.547721) (xy 40.118685 -190.595327)
			(xy 40.140497 -190.646656) (xy 40.154603 -190.700613) (xy 40.160703 -190.75605) (xy 40.158666 -190.811784)
			(xy 40.148536 -190.866627) (xy 40.130529 -190.919411) (xy 40.105028 -190.969011) (xy 40.072577 -191.014369)
			(xy 40.033868 -191.054518) (xy 39.989725 -191.088604) (xy 39.94109 -191.1159) (xy 39.888999 -191.135823)
			(xy 39.834562 -191.147949) (xy 39.77894 -191.15202) (xy 39.723318 -191.147949) (xy 39.668881 -191.135823)
			(xy 39.61679 -191.1159) (xy 39.568155 -191.088604) (xy 39.524012 -191.054518) (xy 39.485303 -191.014369)
			(xy 39.452852 -190.969011) (xy 39.427351 -190.919411) (xy 39.409344 -190.866627) (xy 39.399214 -190.811784)
			(xy 39.397177 -190.75605) (xy 36.042586 -190.75605) (xy 36.071366 -190.77387) (xy 36.140713 -190.826239)
			(xy 36.204933 -190.884783) (xy 36.263477 -190.949003) (xy 36.315846 -191.01835) (xy 36.361593 -191.092234)
			(xy 36.400327 -191.170023) (xy 36.431719 -191.251055) (xy 36.4555 -191.334637) (xy 36.471468 -191.420057)
			(xy 36.479486 -191.506586) (xy 36.479486 -191.593486) (xy 36.471468 -191.680015) (xy 36.458331 -191.750289)
			(xy 58.80404 -191.750289) (xy 58.80404 -191.678967) (xy 58.812026 -191.608093) (xy 58.827896 -191.538558)
			(xy 58.851453 -191.471238) (xy 58.882398 -191.406979) (xy 58.920344 -191.346588) (xy 58.964813 -191.290826)
			(xy 59.015246 -191.240393) (xy 59.071008 -191.195924) (xy 59.131399 -191.157978) (xy 59.195658 -191.127033)
			(xy 59.262978 -191.103476) (xy 59.332513 -191.087606) (xy 59.403387 -191.07962) (xy 59.439048 -191.07912)
			(xy 59.474709 -191.07962) (xy 59.545583 -191.087606) (xy 59.615118 -191.103476) (xy 59.682438 -191.127033)
			(xy 59.746697 -191.157978) (xy 59.807088 -191.195924) (xy 59.86285 -191.240393) (xy 59.913283 -191.290826)
			(xy 59.957752 -191.346588) (xy 59.995698 -191.406979) (xy 60.026643 -191.471238) (xy 60.0502 -191.538558)
			(xy 60.06607 -191.608093) (xy 60.074056 -191.678967) (xy 60.074056 -191.750289) (xy 61.335912 -191.750289)
			(xy 61.335912 -191.678967) (xy 61.343898 -191.608093) (xy 61.359768 -191.538558) (xy 61.383325 -191.471238)
			(xy 61.41427 -191.406979) (xy 61.452216 -191.346588) (xy 61.496685 -191.290826) (xy 61.547118 -191.240393)
			(xy 61.60288 -191.195924) (xy 61.663271 -191.157978) (xy 61.72753 -191.127033) (xy 61.79485 -191.103476)
			(xy 61.864385 -191.087606) (xy 61.935259 -191.07962) (xy 61.97092 -191.07912) (xy 62.006581 -191.07962)
			(xy 62.077455 -191.087606) (xy 62.14699 -191.103476) (xy 62.21431 -191.127033) (xy 62.278569 -191.157978)
			(xy 62.33896 -191.195924) (xy 62.394722 -191.240393) (xy 62.445155 -191.290826) (xy 62.489624 -191.346588)
			(xy 62.52757 -191.406979) (xy 62.558515 -191.471238) (xy 62.582072 -191.538558) (xy 62.597942 -191.608093)
			(xy 62.605928 -191.678967) (xy 62.605928 -191.750289) (xy 64.140326 -191.750289) (xy 64.140326 -191.678967)
			(xy 64.148312 -191.608093) (xy 64.164182 -191.538558) (xy 64.187739 -191.471238) (xy 64.218684 -191.406979)
			(xy 64.25663 -191.346588) (xy 64.301099 -191.290826) (xy 64.351532 -191.240393) (xy 64.407294 -191.195924)
			(xy 64.467685 -191.157978) (xy 64.531944 -191.127033) (xy 64.599264 -191.103476) (xy 64.668799 -191.087606)
			(xy 64.739673 -191.07962) (xy 64.775334 -191.07912) (xy 64.810995 -191.07962) (xy 64.881869 -191.087606)
			(xy 64.951404 -191.103476) (xy 65.018724 -191.127033) (xy 65.082983 -191.157978) (xy 65.143374 -191.195924)
			(xy 65.198224 -191.239666) (xy 83.836509 -191.239666) (xy 83.842609 -191.184229) (xy 83.856715 -191.130272)
			(xy 83.878527 -191.078943) (xy 83.907581 -191.031337) (xy 83.943256 -190.988469) (xy 83.984793 -190.951252)
			(xy 84.031306 -190.920479) (xy 84.081803 -190.896807) (xy 84.13521 -190.880739) (xy 84.190386 -190.872619)
			(xy 84.218272 -190.87211) (xy 84.246158 -190.872619) (xy 84.301334 -190.880739) (xy 84.354741 -190.896807)
			(xy 84.405238 -190.920479) (xy 84.451751 -190.951252) (xy 84.493288 -190.988469) (xy 84.528963 -191.031337)
			(xy 84.558017 -191.078943) (xy 84.579829 -191.130272) (xy 84.593935 -191.184229) (xy 84.597017 -191.212234)
			(xy 85.727285 -191.212234) (xy 85.733385 -191.156797) (xy 85.747491 -191.10284) (xy 85.769303 -191.051511)
			(xy 85.798357 -191.003905) (xy 85.834032 -190.961037) (xy 85.875569 -190.92382) (xy 85.922082 -190.893047)
			(xy 85.972579 -190.869375) (xy 86.025986 -190.853307) (xy 86.081162 -190.845187) (xy 86.109048 -190.844678)
			(xy 86.136934 -190.845187) (xy 86.19211 -190.853307) (xy 86.245517 -190.869375) (xy 86.296014 -190.893047)
			(xy 86.342527 -190.92382) (xy 86.366761 -190.945534) (xy 87.021923 -190.945534) (xy 87.028023 -190.890097)
			(xy 87.042129 -190.83614) (xy 87.063941 -190.784811) (xy 87.092995 -190.737205) (xy 87.12867 -190.694337)
			(xy 87.170207 -190.65712) (xy 87.21672 -190.626347) (xy 87.267217 -190.602675) (xy 87.320624 -190.586607)
			(xy 87.3758 -190.578487) (xy 87.403686 -190.577978) (xy 87.431572 -190.578487) (xy 87.486748 -190.586607)
			(xy 87.540155 -190.602675) (xy 87.590652 -190.626347) (xy 87.637165 -190.65712) (xy 87.678702 -190.694337)
			(xy 87.714377 -190.737205) (xy 87.743431 -190.784811) (xy 87.765243 -190.83614) (xy 87.779349 -190.890097)
			(xy 87.785449 -190.945534) (xy 87.783412 -191.001268) (xy 87.773282 -191.056111) (xy 87.755275 -191.108895)
			(xy 87.729774 -191.158495) (xy 87.697323 -191.203853) (xy 87.658614 -191.244002) (xy 87.614471 -191.278088)
			(xy 87.565836 -191.305384) (xy 87.513745 -191.325307) (xy 87.459308 -191.337433) (xy 87.403686 -191.341504)
			(xy 87.348064 -191.337433) (xy 87.293627 -191.325307) (xy 87.241536 -191.305384) (xy 87.192901 -191.278088)
			(xy 87.148758 -191.244002) (xy 87.110049 -191.203853) (xy 87.077598 -191.158495) (xy 87.052097 -191.108895)
			(xy 87.03409 -191.056111) (xy 87.02396 -191.001268) (xy 87.021923 -190.945534) (xy 86.366761 -190.945534)
			(xy 86.384064 -190.961037) (xy 86.419739 -191.003905) (xy 86.448793 -191.051511) (xy 86.470605 -191.10284)
			(xy 86.484711 -191.156797) (xy 86.490811 -191.212234) (xy 86.488774 -191.267968) (xy 86.478644 -191.322811)
			(xy 86.460637 -191.375595) (xy 86.435136 -191.425195) (xy 86.402685 -191.470553) (xy 86.363976 -191.510702)
			(xy 86.319833 -191.544788) (xy 86.271198 -191.572084) (xy 86.219107 -191.592007) (xy 86.16467 -191.604133)
			(xy 86.109048 -191.608204) (xy 86.053426 -191.604133) (xy 85.998989 -191.592007) (xy 85.946898 -191.572084)
			(xy 85.898263 -191.544788) (xy 85.85412 -191.510702) (xy 85.815411 -191.470553) (xy 85.78296 -191.425195)
			(xy 85.757459 -191.375595) (xy 85.739452 -191.322811) (xy 85.729322 -191.267968) (xy 85.727285 -191.212234)
			(xy 84.597017 -191.212234) (xy 84.600035 -191.239666) (xy 84.597998 -191.2954) (xy 84.587868 -191.350243)
			(xy 84.569861 -191.403027) (xy 84.54436 -191.452627) (xy 84.511909 -191.497985) (xy 84.4732 -191.538134)
			(xy 84.429057 -191.57222) (xy 84.380422 -191.599516) (xy 84.328331 -191.619439) (xy 84.273894 -191.631565)
			(xy 84.218272 -191.635636) (xy 84.16265 -191.631565) (xy 84.108213 -191.619439) (xy 84.056122 -191.599516)
			(xy 84.007487 -191.57222) (xy 83.963344 -191.538134) (xy 83.924635 -191.497985) (xy 83.892184 -191.452627)
			(xy 83.866683 -191.403027) (xy 83.848676 -191.350243) (xy 83.838546 -191.2954) (xy 83.836509 -191.239666)
			(xy 65.198224 -191.239666) (xy 65.199136 -191.240393) (xy 65.249569 -191.290826) (xy 65.294038 -191.346588)
			(xy 65.331984 -191.406979) (xy 65.362929 -191.471238) (xy 65.386486 -191.538558) (xy 65.402356 -191.608093)
			(xy 65.410342 -191.678967) (xy 65.410342 -191.750289) (xy 65.402356 -191.821163) (xy 65.386486 -191.890698)
			(xy 65.362929 -191.958018) (xy 65.331984 -192.022277) (xy 65.294038 -192.082668) (xy 65.249569 -192.13843)
			(xy 65.199136 -192.188863) (xy 65.143374 -192.233332) (xy 65.082983 -192.271278) (xy 65.018724 -192.302223)
			(xy 64.951404 -192.32578) (xy 64.881869 -192.34165) (xy 64.810995 -192.349636) (xy 64.739673 -192.349636)
			(xy 64.668799 -192.34165) (xy 64.599264 -192.32578) (xy 64.531944 -192.302223) (xy 64.467685 -192.271278)
			(xy 64.407294 -192.233332) (xy 64.351532 -192.188863) (xy 64.301099 -192.13843) (xy 64.25663 -192.082668)
			(xy 64.218684 -192.022277) (xy 64.187739 -191.958018) (xy 64.164182 -191.890698) (xy 64.148312 -191.821163)
			(xy 64.140326 -191.750289) (xy 62.605928 -191.750289) (xy 62.597942 -191.821163) (xy 62.582072 -191.890698)
			(xy 62.558515 -191.958018) (xy 62.52757 -192.022277) (xy 62.489624 -192.082668) (xy 62.445155 -192.13843)
			(xy 62.394722 -192.188863) (xy 62.33896 -192.233332) (xy 62.278569 -192.271278) (xy 62.21431 -192.302223)
			(xy 62.14699 -192.32578) (xy 62.077455 -192.34165) (xy 62.006581 -192.349636) (xy 61.935259 -192.349636)
			(xy 61.864385 -192.34165) (xy 61.79485 -192.32578) (xy 61.72753 -192.302223) (xy 61.663271 -192.271278)
			(xy 61.60288 -192.233332) (xy 61.547118 -192.188863) (xy 61.496685 -192.13843) (xy 61.452216 -192.082668)
			(xy 61.41427 -192.022277) (xy 61.383325 -191.958018) (xy 61.359768 -191.890698) (xy 61.343898 -191.821163)
			(xy 61.335912 -191.750289) (xy 60.074056 -191.750289) (xy 60.06607 -191.821163) (xy 60.0502 -191.890698)
			(xy 60.026643 -191.958018) (xy 59.995698 -192.022277) (xy 59.957752 -192.082668) (xy 59.913283 -192.13843)
			(xy 59.86285 -192.188863) (xy 59.807088 -192.233332) (xy 59.746697 -192.271278) (xy 59.682438 -192.302223)
			(xy 59.615118 -192.32578) (xy 59.545583 -192.34165) (xy 59.474709 -192.349636) (xy 59.403387 -192.349636)
			(xy 59.332513 -192.34165) (xy 59.262978 -192.32578) (xy 59.195658 -192.302223) (xy 59.131399 -192.271278)
			(xy 59.071008 -192.233332) (xy 59.015246 -192.188863) (xy 58.964813 -192.13843) (xy 58.920344 -192.082668)
			(xy 58.882398 -192.022277) (xy 58.851453 -191.958018) (xy 58.827896 -191.890698) (xy 58.812026 -191.821163)
			(xy 58.80404 -191.750289) (xy 36.458331 -191.750289) (xy 36.4555 -191.765435) (xy 36.431719 -191.849017)
			(xy 36.400327 -191.930049) (xy 36.361593 -192.007838) (xy 36.315846 -192.081722) (xy 36.263477 -192.151069)
			(xy 36.204933 -192.215289) (xy 36.140713 -192.273833) (xy 36.071366 -192.326202) (xy 35.997482 -192.371949)
			(xy 35.919693 -192.410683) (xy 35.838661 -192.442075) (xy 35.755079 -192.465856) (xy 35.669659 -192.481824)
			(xy 35.58313 -192.489842) (xy 35.49623 -192.489842) (xy 35.409701 -192.481824) (xy 35.324281 -192.465856)
			(xy 35.240699 -192.442075) (xy 35.159667 -192.410683) (xy 35.081878 -192.371949) (xy 35.007994 -192.326202)
			(xy 34.938647 -192.273833) (xy 34.874427 -192.215289) (xy 34.815883 -192.151069) (xy 34.763514 -192.081722)
			(xy 34.717767 -192.007838) (xy 34.679033 -191.930049) (xy 34.647641 -191.849017) (xy 34.62386 -191.765435)
			(xy 34.607892 -191.680015) (xy 34.599874 -191.593486) (xy 31.399486 -191.593486) (xy 31.391468 -191.680015)
			(xy 31.3755 -191.765435) (xy 31.351719 -191.849017) (xy 31.320327 -191.930049) (xy 31.281593 -192.007838)
			(xy 31.235846 -192.081722) (xy 31.183477 -192.151069) (xy 31.124933 -192.215289) (xy 31.060713 -192.273833)
			(xy 30.991366 -192.326202) (xy 30.917482 -192.371949) (xy 30.839693 -192.410683) (xy 30.758661 -192.442075)
			(xy 30.675079 -192.465856) (xy 30.589659 -192.481824) (xy 30.50313 -192.489842) (xy 30.41623 -192.489842)
			(xy 30.329701 -192.481824) (xy 30.244281 -192.465856) (xy 30.160699 -192.442075) (xy 30.079667 -192.410683)
			(xy 30.001878 -192.371949) (xy 29.927994 -192.326202) (xy 29.858647 -192.273833) (xy 29.794427 -192.215289)
			(xy 29.735883 -192.151069) (xy 29.683514 -192.081722) (xy 29.637767 -192.007838) (xy 29.599033 -191.930049)
			(xy 29.567641 -191.849017) (xy 29.54386 -191.765435) (xy 29.527892 -191.680015) (xy 29.519874 -191.593486)
			(xy 28.466288 -191.593486) (xy 28.466288 -192.523128) (xy 82.809333 -192.523128) (xy 82.815433 -192.467691)
			(xy 82.829539 -192.413734) (xy 82.851351 -192.362405) (xy 82.880405 -192.314799) (xy 82.91608 -192.271931)
			(xy 82.957617 -192.234714) (xy 83.00413 -192.203941) (xy 83.054627 -192.180269) (xy 83.108034 -192.164201)
			(xy 83.16321 -192.156081) (xy 83.191096 -192.155572) (xy 83.218982 -192.156081) (xy 83.274158 -192.164201)
			(xy 83.327565 -192.180269) (xy 83.378062 -192.203941) (xy 83.424575 -192.234714) (xy 83.466112 -192.271931)
			(xy 83.501787 -192.314799) (xy 83.530841 -192.362405) (xy 83.552653 -192.413734) (xy 83.566759 -192.467691)
			(xy 83.572859 -192.523128) (xy 83.570822 -192.578862) (xy 83.560692 -192.633705) (xy 83.549197 -192.6674)
			(xy 84.456777 -192.6674) (xy 84.462877 -192.611963) (xy 84.476983 -192.558006) (xy 84.498795 -192.506677)
			(xy 84.527849 -192.459071) (xy 84.563524 -192.416203) (xy 84.605061 -192.378986) (xy 84.651574 -192.348213)
			(xy 84.702071 -192.324541) (xy 84.755478 -192.308473) (xy 84.810654 -192.300353) (xy 84.83854 -192.299844)
			(xy 84.866426 -192.300353) (xy 84.921602 -192.308473) (xy 84.975009 -192.324541) (xy 85.025506 -192.348213)
			(xy 85.072019 -192.378986) (xy 85.113556 -192.416203) (xy 85.149231 -192.459071) (xy 85.178285 -192.506677)
			(xy 85.200097 -192.558006) (xy 85.214203 -192.611963) (xy 85.220303 -192.6674) (xy 85.218266 -192.723134)
			(xy 85.208136 -192.777977) (xy 85.190129 -192.830761) (xy 85.164628 -192.880361) (xy 85.132177 -192.925719)
			(xy 85.093468 -192.965868) (xy 85.049325 -192.999954) (xy 85.00069 -193.02725) (xy 84.948599 -193.047173)
			(xy 84.894162 -193.059299) (xy 84.83854 -193.06337) (xy 84.782918 -193.059299) (xy 84.728481 -193.047173)
			(xy 84.67639 -193.02725) (xy 84.627755 -192.999954) (xy 84.583612 -192.965868) (xy 84.544903 -192.925719)
			(xy 84.512452 -192.880361) (xy 84.486951 -192.830761) (xy 84.468944 -192.777977) (xy 84.458814 -192.723134)
			(xy 84.456777 -192.6674) (xy 83.549197 -192.6674) (xy 83.542685 -192.686489) (xy 83.517184 -192.736089)
			(xy 83.484733 -192.781447) (xy 83.446024 -192.821596) (xy 83.401881 -192.855682) (xy 83.353246 -192.882978)
			(xy 83.301155 -192.902901) (xy 83.246718 -192.915027) (xy 83.191096 -192.919098) (xy 83.135474 -192.915027)
			(xy 83.081037 -192.902901) (xy 83.028946 -192.882978) (xy 82.980311 -192.855682) (xy 82.936168 -192.821596)
			(xy 82.897459 -192.781447) (xy 82.865008 -192.736089) (xy 82.839507 -192.686489) (xy 82.8215 -192.633705)
			(xy 82.81137 -192.578862) (xy 82.809333 -192.523128) (xy 28.466288 -192.523128) (xy 28.466288 -194.75069)
			(xy 28.466852 -194.767337) (xy 28.475466 -194.799497) (xy 28.492111 -194.828332) (xy 28.515651 -194.851876)
			(xy 28.544483 -194.868525) (xy 28.576641 -194.877145) (xy 28.593288 -194.87769) (xy 28.6004 -194.87769)
			(xy 28.607258 -194.876928) (xy 28.620485 -194.875525) (xy 28.647043 -194.873998) (xy 28.660344 -194.87388)
			(xy 29.389324 -194.87388) (xy 29.41277 -194.873352) (xy 29.458864 -194.864727) (xy 29.502593 -194.847793)
			(xy 29.542473 -194.823125) (xy 29.577152 -194.79156) (xy 29.605452 -194.754169) (xy 29.626413 -194.712222)
			(xy 29.639323 -194.667141) (xy 29.643745 -194.620456) (xy 29.639527 -194.573753) (xy 29.626814 -194.528616)
			(xy 29.616908 -194.507358) (xy 29.598093 -194.468236) (xy 29.566902 -194.387215) (xy 29.543312 -194.303665)
			(xy 29.527523 -194.218296) (xy 29.519669 -194.131835) (xy 29.519818 -194.045018) (xy 29.527968 -193.958584)
			(xy 29.544049 -193.873269) (xy 29.567925 -193.7898) (xy 29.599393 -193.708887) (xy 29.638185 -193.631218)
			(xy 29.68397 -193.557456) (xy 29.736359 -193.488227) (xy 29.794905 -193.424122) (xy 29.859111 -193.365685)
			(xy 29.928429 -193.313415) (xy 30.00227 -193.267756) (xy 30.080005 -193.229098) (xy 30.160972 -193.197769)
			(xy 30.244482 -193.174035) (xy 30.329824 -193.1581) (xy 30.416271 -193.150098) (xy 30.503089 -193.150098)
			(xy 30.589536 -193.1581) (xy 30.674878 -193.174035) (xy 30.758388 -193.197769) (xy 30.839355 -193.229098)
			(xy 30.91709 -193.267756) (xy 30.990931 -193.313415) (xy 31.060249 -193.365685) (xy 31.124455 -193.424122)
			(xy 31.183001 -193.488227) (xy 31.23539 -193.557456) (xy 31.281175 -193.631218) (xy 31.319967 -193.708887)
			(xy 31.351435 -193.7898) (xy 31.375311 -193.873269) (xy 31.391392 -193.958584) (xy 31.399542 -194.045018)
			(xy 31.399691 -194.131835) (xy 31.399541 -194.133486) (xy 34.599874 -194.133486) (xy 34.599874 -194.046586)
			(xy 34.607892 -193.960057) (xy 34.62386 -193.874637) (xy 34.647641 -193.791055) (xy 34.679033 -193.710023)
			(xy 34.717767 -193.632234) (xy 34.763514 -193.55835) (xy 34.815883 -193.489003) (xy 34.874427 -193.424783)
			(xy 34.938647 -193.366239) (xy 35.007994 -193.31387) (xy 35.081878 -193.268123) (xy 35.159667 -193.229389)
			(xy 35.240699 -193.197997) (xy 35.324281 -193.174216) (xy 35.409701 -193.158248) (xy 35.49623 -193.15023)
			(xy 35.53968 -193.149728) (xy 35.58313 -193.15023) (xy 35.669659 -193.158248) (xy 35.755079 -193.174216)
			(xy 35.838661 -193.197997) (xy 35.919693 -193.229389) (xy 35.997482 -193.268123) (xy 36.071366 -193.31387)
			(xy 36.140713 -193.366239) (xy 36.204933 -193.424783) (xy 36.263477 -193.489003) (xy 36.315846 -193.55835)
			(xy 36.361593 -193.632234) (xy 36.400327 -193.710023) (xy 36.401558 -193.713201) (xy 58.80404 -193.713201)
			(xy 58.80404 -193.641879) (xy 58.812026 -193.571005) (xy 58.827896 -193.50147) (xy 58.851453 -193.43415)
			(xy 58.882398 -193.369891) (xy 58.920344 -193.3095) (xy 58.964813 -193.253738) (xy 59.015246 -193.203305)
			(xy 59.071008 -193.158836) (xy 59.131399 -193.12089) (xy 59.195658 -193.089945) (xy 59.262978 -193.066388)
			(xy 59.332513 -193.050518) (xy 59.403387 -193.042532) (xy 59.439048 -193.042032) (xy 59.474709 -193.042532)
			(xy 59.545583 -193.050518) (xy 59.615118 -193.066388) (xy 59.682438 -193.089945) (xy 59.746697 -193.12089)
			(xy 59.807088 -193.158836) (xy 59.86285 -193.203305) (xy 59.913283 -193.253738) (xy 59.957752 -193.3095)
			(xy 59.995698 -193.369891) (xy 60.026643 -193.43415) (xy 60.0502 -193.50147) (xy 60.06607 -193.571005)
			(xy 60.074056 -193.641879) (xy 60.074056 -193.713201) (xy 61.335912 -193.713201) (xy 61.335912 -193.641879)
			(xy 61.343898 -193.571005) (xy 61.359768 -193.50147) (xy 61.383325 -193.43415) (xy 61.41427 -193.369891)
			(xy 61.452216 -193.3095) (xy 61.496685 -193.253738) (xy 61.547118 -193.203305) (xy 61.60288 -193.158836)
			(xy 61.663271 -193.12089) (xy 61.72753 -193.089945) (xy 61.79485 -193.066388) (xy 61.864385 -193.050518)
			(xy 61.935259 -193.042532) (xy 61.97092 -193.042032) (xy 62.006581 -193.042532) (xy 62.077455 -193.050518)
			(xy 62.14699 -193.066388) (xy 62.21431 -193.089945) (xy 62.278569 -193.12089) (xy 62.33896 -193.158836)
			(xy 62.394722 -193.203305) (xy 62.445155 -193.253738) (xy 62.489624 -193.3095) (xy 62.52757 -193.369891)
			(xy 62.558515 -193.43415) (xy 62.582072 -193.50147) (xy 62.597942 -193.571005) (xy 62.605928 -193.641879)
			(xy 62.605928 -193.713201) (xy 64.140326 -193.713201) (xy 64.140326 -193.641879) (xy 64.148312 -193.571005)
			(xy 64.164182 -193.50147) (xy 64.187739 -193.43415) (xy 64.218684 -193.369891) (xy 64.25663 -193.3095)
			(xy 64.301099 -193.253738) (xy 64.351532 -193.203305) (xy 64.407294 -193.158836) (xy 64.467685 -193.12089)
			(xy 64.531944 -193.089945) (xy 64.599264 -193.066388) (xy 64.668799 -193.050518) (xy 64.739673 -193.042532)
			(xy 64.775334 -193.042032) (xy 64.810995 -193.042532) (xy 64.881869 -193.050518) (xy 64.951404 -193.066388)
			(xy 65.018724 -193.089945) (xy 65.082983 -193.12089) (xy 65.143374 -193.158836) (xy 65.199136 -193.203305)
			(xy 65.249569 -193.253738) (xy 65.294038 -193.3095) (xy 65.331984 -193.369891) (xy 65.362929 -193.43415)
			(xy 65.386486 -193.50147) (xy 65.402356 -193.571005) (xy 65.410342 -193.641879) (xy 65.410342 -193.71007)
			(xy 83.269581 -193.71007) (xy 83.275681 -193.654633) (xy 83.289787 -193.600676) (xy 83.311599 -193.549347)
			(xy 83.340653 -193.501741) (xy 83.376328 -193.458873) (xy 83.417865 -193.421656) (xy 83.464378 -193.390883)
			(xy 83.514875 -193.367211) (xy 83.568282 -193.351143) (xy 83.623458 -193.343023) (xy 83.651344 -193.342514)
			(xy 83.67923 -193.343023) (xy 83.734406 -193.351143) (xy 83.787813 -193.367211) (xy 83.83831 -193.390883)
			(xy 83.884823 -193.421656) (xy 83.92636 -193.458873) (xy 83.962035 -193.501741) (xy 83.991089 -193.549347)
			(xy 84.012901 -193.600676) (xy 84.027007 -193.654633) (xy 84.033107 -193.71007) (xy 84.03107 -193.765804)
			(xy 84.02094 -193.820647) (xy 84.002933 -193.873431) (xy 83.977432 -193.923031) (xy 83.944981 -193.968389)
			(xy 83.906272 -194.008538) (xy 83.862129 -194.042624) (xy 83.813494 -194.06992) (xy 83.761403 -194.089843)
			(xy 83.706966 -194.101969) (xy 83.651344 -194.10604) (xy 83.595722 -194.101969) (xy 83.541285 -194.089843)
			(xy 83.489194 -194.06992) (xy 83.440559 -194.042624) (xy 83.396416 -194.008538) (xy 83.357707 -193.968389)
			(xy 83.325256 -193.923031) (xy 83.299755 -193.873431) (xy 83.281748 -193.820647) (xy 83.271618 -193.765804)
			(xy 83.269581 -193.71007) (xy 65.410342 -193.71007) (xy 65.410342 -193.713201) (xy 65.402356 -193.784075)
			(xy 65.386486 -193.85361) (xy 65.362929 -193.92093) (xy 65.331984 -193.985189) (xy 65.294038 -194.04558)
			(xy 65.249569 -194.101342) (xy 65.199136 -194.151775) (xy 65.143374 -194.196244) (xy 65.082983 -194.23419)
			(xy 65.018724 -194.265135) (xy 64.951404 -194.288692) (xy 64.881869 -194.304562) (xy 64.810995 -194.312548)
			(xy 64.739673 -194.312548) (xy 64.668799 -194.304562) (xy 64.599264 -194.288692) (xy 64.531944 -194.265135)
			(xy 64.467685 -194.23419) (xy 64.407294 -194.196244) (xy 64.351532 -194.151775) (xy 64.301099 -194.101342)
			(xy 64.25663 -194.04558) (xy 64.218684 -193.985189) (xy 64.187739 -193.92093) (xy 64.164182 -193.85361)
			(xy 64.148312 -193.784075) (xy 64.140326 -193.713201) (xy 62.605928 -193.713201) (xy 62.597942 -193.784075)
			(xy 62.582072 -193.85361) (xy 62.558515 -193.92093) (xy 62.52757 -193.985189) (xy 62.489624 -194.04558)
			(xy 62.445155 -194.101342) (xy 62.394722 -194.151775) (xy 62.33896 -194.196244) (xy 62.278569 -194.23419)
			(xy 62.21431 -194.265135) (xy 62.14699 -194.288692) (xy 62.077455 -194.304562) (xy 62.006581 -194.312548)
			(xy 61.935259 -194.312548) (xy 61.864385 -194.304562) (xy 61.79485 -194.288692) (xy 61.72753 -194.265135)
			(xy 61.663271 -194.23419) (xy 61.60288 -194.196244) (xy 61.547118 -194.151775) (xy 61.496685 -194.101342)
			(xy 61.452216 -194.04558) (xy 61.41427 -193.985189) (xy 61.383325 -193.92093) (xy 61.359768 -193.85361)
			(xy 61.343898 -193.784075) (xy 61.335912 -193.713201) (xy 60.074056 -193.713201) (xy 60.06607 -193.784075)
			(xy 60.0502 -193.85361) (xy 60.026643 -193.92093) (xy 59.995698 -193.985189) (xy 59.957752 -194.04558)
			(xy 59.913283 -194.101342) (xy 59.86285 -194.151775) (xy 59.807088 -194.196244) (xy 59.746697 -194.23419)
			(xy 59.682438 -194.265135) (xy 59.615118 -194.288692) (xy 59.545583 -194.304562) (xy 59.474709 -194.312548)
			(xy 59.403387 -194.312548) (xy 59.332513 -194.304562) (xy 59.262978 -194.288692) (xy 59.195658 -194.265135)
			(xy 59.131399 -194.23419) (xy 59.071008 -194.196244) (xy 59.015246 -194.151775) (xy 58.964813 -194.101342)
			(xy 58.920344 -194.04558) (xy 58.882398 -193.985189) (xy 58.851453 -193.92093) (xy 58.827896 -193.85361)
			(xy 58.812026 -193.784075) (xy 58.80404 -193.713201) (xy 36.401558 -193.713201) (xy 36.431719 -193.791055)
			(xy 36.4555 -193.874637) (xy 36.471468 -193.960057) (xy 36.479486 -194.046586) (xy 36.479486 -194.133486)
			(xy 36.471468 -194.220015) (xy 36.4555 -194.305435) (xy 36.431719 -194.389017) (xy 36.400327 -194.470049)
			(xy 36.361593 -194.547838) (xy 36.315846 -194.621722) (xy 36.263477 -194.691069) (xy 36.204933 -194.755289)
			(xy 36.140713 -194.813833) (xy 36.071366 -194.866202) (xy 35.997482 -194.911949) (xy 35.919693 -194.950683)
			(xy 35.838661 -194.982075) (xy 35.755079 -195.005856) (xy 35.669659 -195.021824) (xy 35.58313 -195.029842)
			(xy 35.49623 -195.029842) (xy 35.409701 -195.021824) (xy 35.324281 -195.005856) (xy 35.240699 -194.982075)
			(xy 35.159667 -194.950683) (xy 35.081878 -194.911949) (xy 35.007994 -194.866202) (xy 34.938647 -194.813833)
			(xy 34.874427 -194.755289) (xy 34.815883 -194.691069) (xy 34.763514 -194.621722) (xy 34.717767 -194.547838)
			(xy 34.679033 -194.470049) (xy 34.647641 -194.389017) (xy 34.62386 -194.305435) (xy 34.607892 -194.220015)
			(xy 34.599874 -194.133486) (xy 31.399541 -194.133486) (xy 31.391837 -194.218296) (xy 31.376048 -194.303665)
			(xy 31.352458 -194.387215) (xy 31.321267 -194.468236) (xy 31.302452 -194.507358) (xy 31.292551 -194.528623)
			(xy 31.279813 -194.57376) (xy 31.275576 -194.620468) (xy 31.279985 -194.66716) (xy 31.292889 -194.71225)
			(xy 31.313851 -194.754205) (xy 31.342157 -194.7916) (xy 31.376846 -194.823164) (xy 31.41674 -194.847824)
			(xy 31.460482 -194.864742) (xy 31.506586 -194.873344) (xy 31.530036 -194.87388) (xy 32.616902 -194.87388)
			(xy 34.214562 -196.471794) (xy 34.230336 -196.48701) (xy 34.266188 -196.512218) (xy 34.305833 -196.530902)
			(xy 34.348096 -196.542506) (xy 34.391723 -196.546688) (xy 34.43542 -196.543322) (xy 34.477892 -196.532509)
			(xy 34.517879 -196.51457) (xy 34.554196 -196.490036) (xy 34.585764 -196.459635) (xy 34.611649 -196.424268)
			(xy 34.631082 -196.384985) (xy 34.637726 -196.364098) (xy 34.650401 -196.3229) (xy 34.682272 -196.242806)
			(xy 34.72134 -196.165965) (xy 34.767277 -196.093022) (xy 34.819697 -196.02459) (xy 34.878161 -195.961244)
			(xy 34.942177 -195.903514) (xy 35.011208 -195.851886) (xy 35.084676 -195.806793) (xy 35.161962 -195.768613)
			(xy 35.242418 -195.737667) (xy 35.325368 -195.714216) (xy 35.410118 -195.698455) (xy 35.495953 -195.690517)
			(xy 35.582156 -195.690469) (xy 35.668 -195.698311) (xy 35.752767 -195.713977) (xy 35.835744 -195.737336)
			(xy 35.916235 -195.768191) (xy 35.993563 -195.806284) (xy 36.067081 -195.851295) (xy 36.074334 -195.856707)
			(xy 58.80404 -195.856707) (xy 58.80404 -195.785385) (xy 58.812026 -195.714511) (xy 58.827896 -195.644976)
			(xy 58.851453 -195.577656) (xy 58.882398 -195.513397) (xy 58.920344 -195.453006) (xy 58.964813 -195.397244)
			(xy 59.015246 -195.346811) (xy 59.071008 -195.302342) (xy 59.131399 -195.264396) (xy 59.195658 -195.233451)
			(xy 59.262978 -195.209894) (xy 59.332513 -195.194024) (xy 59.403387 -195.186038) (xy 59.439048 -195.185538)
			(xy 59.474709 -195.186038) (xy 59.545583 -195.194024) (xy 59.615118 -195.209894) (xy 59.682438 -195.233451)
			(xy 59.746697 -195.264396) (xy 59.807088 -195.302342) (xy 59.86285 -195.346811) (xy 59.913283 -195.397244)
			(xy 59.957752 -195.453006) (xy 59.995698 -195.513397) (xy 60.026643 -195.577656) (xy 60.0502 -195.644976)
			(xy 60.06607 -195.714511) (xy 60.074056 -195.785385) (xy 60.074056 -195.856707) (xy 61.335912 -195.856707)
			(xy 61.335912 -195.785385) (xy 61.343898 -195.714511) (xy 61.359768 -195.644976) (xy 61.383325 -195.577656)
			(xy 61.41427 -195.513397) (xy 61.452216 -195.453006) (xy 61.496685 -195.397244) (xy 61.547118 -195.346811)
			(xy 61.60288 -195.302342) (xy 61.663271 -195.264396) (xy 61.72753 -195.233451) (xy 61.79485 -195.209894)
			(xy 61.864385 -195.194024) (xy 61.935259 -195.186038) (xy 61.97092 -195.185538) (xy 62.006581 -195.186038)
			(xy 62.077455 -195.194024) (xy 62.14699 -195.209894) (xy 62.21431 -195.233451) (xy 62.278569 -195.264396)
			(xy 62.33896 -195.302342) (xy 62.394722 -195.346811) (xy 62.445155 -195.397244) (xy 62.489624 -195.453006)
			(xy 62.52757 -195.513397) (xy 62.558515 -195.577656) (xy 62.582072 -195.644976) (xy 62.597942 -195.714511)
			(xy 62.605928 -195.785385) (xy 62.605928 -195.856707) (xy 64.140326 -195.856707) (xy 64.140326 -195.785385)
			(xy 64.148312 -195.714511) (xy 64.164182 -195.644976) (xy 64.187739 -195.577656) (xy 64.218684 -195.513397)
			(xy 64.25663 -195.453006) (xy 64.301099 -195.397244) (xy 64.351532 -195.346811) (xy 64.407294 -195.302342)
			(xy 64.467685 -195.264396) (xy 64.531944 -195.233451) (xy 64.599264 -195.209894) (xy 64.668799 -195.194024)
			(xy 64.739673 -195.186038) (xy 64.775334 -195.185538) (xy 64.810995 -195.186038) (xy 64.881869 -195.194024)
			(xy 64.951404 -195.209894) (xy 65.018724 -195.233451) (xy 65.082983 -195.264396) (xy 65.143374 -195.302342)
			(xy 65.199136 -195.346811) (xy 65.249569 -195.397244) (xy 65.294038 -195.453006) (xy 65.331984 -195.513397)
			(xy 65.362929 -195.577656) (xy 65.386486 -195.644976) (xy 65.402356 -195.714511) (xy 65.410342 -195.785385)
			(xy 65.410342 -195.856707) (xy 65.402356 -195.927581) (xy 65.386486 -195.997116) (xy 65.362929 -196.064436)
			(xy 65.331984 -196.128695) (xy 65.294038 -196.189086) (xy 65.249569 -196.244848) (xy 65.199136 -196.295281)
			(xy 65.143374 -196.33975) (xy 65.082983 -196.377696) (xy 65.018724 -196.408641) (xy 64.951404 -196.432198)
			(xy 64.881869 -196.448068) (xy 64.810995 -196.456054) (xy 64.739673 -196.456054) (xy 64.668799 -196.448068)
			(xy 64.599264 -196.432198) (xy 64.531944 -196.408641) (xy 64.467685 -196.377696) (xy 64.407294 -196.33975)
			(xy 64.351532 -196.295281) (xy 64.301099 -196.244848) (xy 64.25663 -196.189086) (xy 64.218684 -196.128695)
			(xy 64.187739 -196.064436) (xy 64.164182 -195.997116) (xy 64.148312 -195.927581) (xy 64.140326 -195.856707)
			(xy 62.605928 -195.856707) (xy 62.597942 -195.927581) (xy 62.582072 -195.997116) (xy 62.558515 -196.064436)
			(xy 62.52757 -196.128695) (xy 62.489624 -196.189086) (xy 62.445155 -196.244848) (xy 62.394722 -196.295281)
			(xy 62.33896 -196.33975) (xy 62.278569 -196.377696) (xy 62.21431 -196.408641) (xy 62.14699 -196.432198)
			(xy 62.077455 -196.448068) (xy 62.006581 -196.456054) (xy 61.935259 -196.456054) (xy 61.864385 -196.448068)
			(xy 61.79485 -196.432198) (xy 61.72753 -196.408641) (xy 61.663271 -196.377696) (xy 61.60288 -196.33975)
			(xy 61.547118 -196.295281) (xy 61.496685 -196.244848) (xy 61.452216 -196.189086) (xy 61.41427 -196.128695)
			(xy 61.383325 -196.064436) (xy 61.359768 -195.997116) (xy 61.343898 -195.927581) (xy 61.335912 -195.856707)
			(xy 60.074056 -195.856707) (xy 60.06607 -195.927581) (xy 60.0502 -195.997116) (xy 60.026643 -196.064436)
			(xy 59.995698 -196.128695) (xy 59.957752 -196.189086) (xy 59.913283 -196.244848) (xy 59.86285 -196.295281)
			(xy 59.807088 -196.33975) (xy 59.746697 -196.377696) (xy 59.682438 -196.408641) (xy 59.615118 -196.432198)
			(xy 59.545583 -196.448068) (xy 59.474709 -196.456054) (xy 59.403387 -196.456054) (xy 59.332513 -196.448068)
			(xy 59.262978 -196.432198) (xy 59.195658 -196.408641) (xy 59.131399 -196.377696) (xy 59.071008 -196.33975)
			(xy 59.015246 -196.295281) (xy 58.964813 -196.244848) (xy 58.920344 -196.189086) (xy 58.882398 -196.128695)
			(xy 58.851453 -196.064436) (xy 58.827896 -195.997116) (xy 58.812026 -195.927581) (xy 58.80404 -195.856707)
			(xy 36.074334 -195.856707) (xy 36.13617 -195.902846) (xy 36.200251 -195.960505) (xy 36.258785 -196.023786)
			(xy 36.311282 -196.092159) (xy 36.3573 -196.16505) (xy 36.396454 -196.241847) (xy 36.428414 -196.321906)
			(xy 36.452913 -196.404554) (xy 36.469744 -196.489097) (xy 36.478766 -196.574825) (xy 36.479904 -196.66102)
			(xy 36.473148 -196.746957) (xy 36.469163 -196.770159) (xy 51.403494 -196.770159) (xy 51.403494 -196.689049)
			(xy 51.411444 -196.60833) (xy 51.427267 -196.528779) (xy 51.450812 -196.451163) (xy 51.481851 -196.376227)
			(xy 51.520086 -196.304695) (xy 51.565148 -196.237255) (xy 51.616603 -196.174556) (xy 51.673956 -196.117203)
			(xy 51.736655 -196.065748) (xy 51.804095 -196.020686) (xy 51.875627 -195.982451) (xy 51.950563 -195.951412)
			(xy 52.028179 -195.927867) (xy 52.10773 -195.912044) (xy 52.188449 -195.904094) (xy 52.229004 -195.903596)
			(xy 52.269559 -195.904094) (xy 52.350278 -195.912044) (xy 52.429829 -195.927867) (xy 52.507445 -195.951412)
			(xy 52.582381 -195.982451) (xy 52.653913 -196.020686) (xy 52.721353 -196.065748) (xy 52.784052 -196.117203)
			(xy 52.841405 -196.174556) (xy 52.89286 -196.237255) (xy 52.937922 -196.304695) (xy 52.976157 -196.376227)
			(xy 53.007196 -196.451163) (xy 53.030741 -196.528779) (xy 53.046564 -196.60833) (xy 53.054514 -196.689049)
			(xy 53.054514 -196.770159) (xy 53.046564 -196.850878) (xy 53.030741 -196.930429) (xy 53.007196 -197.008045)
			(xy 52.976157 -197.082981) (xy 52.937922 -197.154513) (xy 52.89286 -197.221953) (xy 52.841405 -197.284652)
			(xy 52.784052 -197.342005) (xy 52.721353 -197.39346) (xy 52.653913 -197.438522) (xy 52.582381 -197.476757)
			(xy 52.507445 -197.507796) (xy 52.429829 -197.531341) (xy 52.350278 -197.547164) (xy 52.269559 -197.555114)
			(xy 52.188449 -197.555114) (xy 52.10773 -197.547164) (xy 52.028179 -197.531341) (xy 51.950563 -197.507796)
			(xy 51.875627 -197.476757) (xy 51.804095 -197.438522) (xy 51.736655 -197.39346) (xy 51.673956 -197.342005)
			(xy 51.616603 -197.284652) (xy 51.565148 -197.221953) (xy 51.520086 -197.154513) (xy 51.481851 -197.082981)
			(xy 51.450812 -197.008045) (xy 51.427267 -196.930429) (xy 51.411444 -196.850878) (xy 51.403494 -196.770159)
			(xy 36.469163 -196.770159) (xy 36.458555 -196.831915) (xy 36.436247 -196.91518) (xy 36.406412 -196.996055)
			(xy 36.388294 -197.035166) (xy 36.378736 -197.056407) (xy 36.366689 -197.101396) (xy 36.363037 -197.147827)
			(xy 36.367901 -197.194146) (xy 36.381118 -197.238805) (xy 36.402247 -197.28031) (xy 36.430581 -197.317274)
			(xy 36.465173 -197.34846) (xy 36.504865 -197.372826) (xy 36.54833 -197.389555) (xy 36.594116 -197.39809)
			(xy 36.617402 -197.39864) (xy 37.76853 -197.39864) (xy 38.13683 -197.03034) (xy 45.234098 -197.03034)
			(xy 46.061554 -197.857796) (xy 86.877655 -197.857796) (xy 86.879665 -197.667113) (xy 86.889712 -197.476684)
			(xy 86.907778 -197.286848) (xy 86.933831 -197.097942) (xy 86.967824 -196.910303) (xy 87.009697 -196.724263)
			(xy 87.059376 -196.540154) (xy 87.116772 -196.358303) (xy 87.181783 -196.179033) (xy 87.254294 -196.002663)
			(xy 87.334175 -195.829507) (xy 87.421285 -195.659872) (xy 87.515469 -195.49406) (xy 87.61656 -195.332366)
			(xy 87.724376 -195.175078) (xy 87.838728 -195.022475) (xy 87.959411 -194.874827) (xy 88.086212 -194.732399)
			(xy 88.218903 -194.595443) (xy 88.357251 -194.464202) (xy 88.501008 -194.33891) (xy 88.649919 -194.21979)
			(xy 88.80372 -194.107054) (xy 88.962136 -194.000901) (xy 89.124887 -193.901521) (xy 89.291682 -193.809091)
			(xy 89.462226 -193.723774) (xy 89.636214 -193.645722) (xy 89.813339 -193.575075) (xy 89.993284 -193.511957)
			(xy 90.17573 -193.456481) (xy 90.360353 -193.408746) (xy 90.546823 -193.368836) (xy 90.734811 -193.336823)
			(xy 90.923981 -193.312763) (xy 91.113997 -193.2967) (xy 91.304521 -193.288661) (xy 91.399868 -193.288158)
			(xy 91.495215 -193.288661) (xy 91.685739 -193.2967) (xy 91.875755 -193.312763) (xy 92.064925 -193.336823)
			(xy 92.252913 -193.368836) (xy 92.439383 -193.408746) (xy 92.624006 -193.456481) (xy 92.806452 -193.511957)
			(xy 92.986397 -193.575075) (xy 93.163522 -193.645722) (xy 93.33751 -193.723774) (xy 93.508054 -193.809091)
			(xy 93.674849 -193.901521) (xy 93.8376 -194.000901) (xy 93.996016 -194.107054) (xy 94.149817 -194.21979)
			(xy 94.298728 -194.33891) (xy 94.442485 -194.464202) (xy 94.580833 -194.595443) (xy 94.713524 -194.732399)
			(xy 94.840325 -194.874827) (xy 94.961008 -195.022475) (xy 95.07536 -195.175078) (xy 95.183176 -195.332366)
			(xy 95.284267 -195.49406) (xy 95.378451 -195.659872) (xy 95.465561 -195.829507) (xy 95.545442 -196.002663)
			(xy 95.617953 -196.179033) (xy 95.682964 -196.358303) (xy 95.74036 -196.540154) (xy 95.790039 -196.724263)
			(xy 95.831912 -196.910303) (xy 95.865905 -197.097942) (xy 95.891958 -197.286848) (xy 95.910024 -197.476684)
			(xy 95.920071 -197.667113) (xy 95.922081 -197.857796) (xy 95.916051 -198.048395) (xy 95.901992 -198.238569)
			(xy 95.879927 -198.427982) (xy 95.849898 -198.616297) (xy 95.811956 -198.803178) (xy 95.76617 -198.988294)
			(xy 95.712621 -199.171314) (xy 95.651403 -199.351915) (xy 95.582627 -199.529774) (xy 95.506414 -199.704576)
			(xy 95.4229 -199.87601) (xy 95.332233 -200.04377) (xy 95.234574 -200.207559) (xy 95.130097 -200.367086)
			(xy 95.018988 -200.522067) (xy 94.901445 -200.672225) (xy 94.777675 -200.817295) (xy 94.6479 -200.957019)
			(xy 94.512351 -201.091147) (xy 94.371267 -201.219441) (xy 94.2249 -201.341675) (xy 94.073511 -201.457629)
			(xy 93.917368 -201.567098) (xy 93.756749 -201.669887) (xy 93.591939 -201.765813) (xy 93.423232 -201.854707)
			(xy 93.250927 -201.936409) (xy 93.075332 -202.010775) (xy 92.896757 -202.077673) (xy 92.715521 -202.136983)
			(xy 92.531946 -202.1886) (xy 92.346358 -202.232432) (xy 92.159088 -202.268401) (xy 91.970467 -202.296444)
			(xy 91.780832 -202.31651) (xy 91.590519 -202.328564) (xy 91.399868 -202.332585) (xy 91.209217 -202.328564)
			(xy 91.018904 -202.31651) (xy 90.829269 -202.296444) (xy 90.640648 -202.268401) (xy 90.453378 -202.232432)
			(xy 90.26779 -202.1886) (xy 90.084215 -202.136983) (xy 89.902979 -202.077673) (xy 89.724404 -202.010775)
			(xy 89.548809 -201.936409) (xy 89.376504 -201.854707) (xy 89.207797 -201.765813) (xy 89.042987 -201.669887)
			(xy 88.882368 -201.567098) (xy 88.726225 -201.457629) (xy 88.574836 -201.341675) (xy 88.428469 -201.219441)
			(xy 88.287385 -201.091147) (xy 88.151836 -200.957019) (xy 88.022061 -200.817295) (xy 87.898291 -200.672225)
			(xy 87.780748 -200.522067) (xy 87.669639 -200.367086) (xy 87.565162 -200.207559) (xy 87.467503 -200.04377)
			(xy 87.376836 -199.87601) (xy 87.293322 -199.704576) (xy 87.217109 -199.529774) (xy 87.148333 -199.351915)
			(xy 87.087115 -199.171314) (xy 87.033566 -198.988294) (xy 86.98778 -198.803178) (xy 86.949838 -198.616297)
			(xy 86.919809 -198.427982) (xy 86.897744 -198.238569) (xy 86.883685 -198.048395) (xy 86.877655 -197.857796)
			(xy 46.061554 -197.857796) (xy 49.503838 -201.30008) (xy 55.00116 -201.30008) (xy 60.23737 -206.536036)
			(xy 64.02197 -206.536036) (xy 64.602868 -205.955138) (xy 64.625601 -205.933136) (xy 64.675793 -205.894623)
			(xy 64.730582 -205.86299) (xy 64.789032 -205.838779) (xy 64.850141 -205.822405) (xy 64.912865 -205.814147)
			(xy 64.976131 -205.814147) (xy 65.038855 -205.822405) (xy 65.099964 -205.838779) (xy 65.158414 -205.86299)
			(xy 65.213203 -205.894623) (xy 65.263395 -205.933136) (xy 65.30813 -205.977871) (xy 65.346643 -206.028063)
			(xy 65.378276 -206.082852) (xy 65.402487 -206.141302) (xy 65.418861 -206.202411) (xy 65.427119 -206.265135)
			(xy 65.427119 -206.328401) (xy 65.418861 -206.391125) (xy 65.402487 -206.452234) (xy 65.378276 -206.510684)
			(xy 65.346643 -206.565473) (xy 65.30813 -206.615665) (xy 65.286128 -206.638398) (xy 64.422274 -207.502252)
			(xy 60.298838 -207.502252) (xy 60.282196 -207.502688) (xy 60.250047 -207.511312) (xy 60.221222 -207.527956)
			(xy 60.197682 -207.551489) (xy 60.181028 -207.580308) (xy 60.172394 -207.612454) (xy 60.172367 -207.645739)
			(xy 60.180948 -207.677899) (xy 60.197555 -207.706746) (xy 60.208922 -207.718914) (xy 60.457842 -207.96758)
			(xy 64.432434 -207.96758) (xy 65.324228 -208.859374) (xy 65.34623 -208.882107) (xy 65.384743 -208.932299)
			(xy 65.416376 -208.987088) (xy 65.440587 -209.045538) (xy 65.456961 -209.106647) (xy 65.465219 -209.169371)
			(xy 65.465219 -209.232637) (xy 65.456961 -209.295361) (xy 65.440587 -209.35647) (xy 65.416376 -209.41492)
			(xy 65.384743 -209.469709) (xy 65.34623 -209.519901) (xy 65.301495 -209.564636) (xy 65.251303 -209.603149)
			(xy 65.196514 -209.634782) (xy 65.138064 -209.658993) (xy 65.076955 -209.675367) (xy 65.014231 -209.683625)
			(xy 64.950965 -209.683625) (xy 64.888241 -209.675367) (xy 64.827132 -209.658993) (xy 64.768682 -209.634782)
			(xy 64.713893 -209.603149) (xy 64.663701 -209.564636) (xy 64.640968 -209.542634) (xy 64.03213 -208.933796)
			(xy 60.057538 -208.933796) (xy 54.335426 -203.211684) (xy 48.62576 -203.211684) (xy 44.266612 -198.852536)
			(xy 41.647872 -198.852536) (xy 41.62424 -198.853029) (xy 41.577788 -198.861753) (xy 41.53375 -198.878914)
			(xy 41.493643 -198.90392) (xy 41.45885 -198.93591) (xy 41.430571 -198.973781) (xy 41.40978 -199.016226)
			(xy 41.397194 -199.061784) (xy 41.393247 -199.108882) (xy 41.395142 -199.132444) (xy 41.397497 -199.159013)
			(xy 41.395556 -199.212317) (xy 41.38621 -199.264831) (xy 41.36964 -199.315531) (xy 41.34617 -199.36343)
			(xy 41.316257 -199.407592) (xy 41.280484 -199.447157) (xy 41.23955 -199.481354) (xy 41.194251 -199.509516)
			(xy 41.145471 -199.531094) (xy 41.094161 -199.545667) (xy 41.041321 -199.552951) (xy 41.01465 -199.553322)
			(xy 40.991381 -199.553793) (xy 40.945604 -199.562166) (xy 40.902117 -199.578735) (xy 40.862374 -199.602944)
			(xy 40.827703 -199.633984) (xy 40.799263 -199.670819) (xy 40.778004 -199.712216) (xy 40.764638 -199.756791)
			(xy 40.759612 -199.803055) (xy 40.763093 -199.849461) (xy 40.768524 -199.872092) (xy 40.77508 -199.899225)
			(xy 40.781253 -199.954698) (xy 40.779277 -200.010479) (xy 40.769194 -200.065377) (xy 40.751219 -200.118219)
			(xy 40.725736 -200.167878) (xy 40.693289 -200.213294) (xy 40.65457 -200.253497) (xy 40.610407 -200.287629)
			(xy 40.561742 -200.314962) (xy 40.509613 -200.334911) (xy 40.455133 -200.347052) (xy 40.399466 -200.351124)
			(xy 40.3438 -200.347042) (xy 40.289322 -200.334892) (xy 40.237197 -200.314933) (xy 40.188536 -200.287592)
			(xy 40.144379 -200.253452) (xy 40.105668 -200.213242) (xy 40.073229 -200.16782) (xy 40.047755 -200.118156)
			(xy 40.029789 -200.065311) (xy 40.019716 -200.010412) (xy 40.01775 -199.95463) (xy 40.023933 -199.899158)
			(xy 40.038133 -199.845179) (xy 40.060047 -199.793845) (xy 40.089208 -199.746252) (xy 40.124992 -199.703416)
			(xy 40.166636 -199.666252) (xy 40.213251 -199.635553) (xy 40.263842 -199.611974) (xy 40.317328 -199.596018)
			(xy 40.372569 -199.588026) (xy 40.400478 -199.587612) (xy 40.423745 -199.587124) (xy 40.469518 -199.578747)
			(xy 40.513001 -199.562177) (xy 40.55274 -199.537968) (xy 40.587409 -199.50693) (xy 40.615848 -199.470099)
			(xy 40.637107 -199.428706) (xy 40.650475 -199.384135) (xy 40.655506 -199.337875) (xy 40.652032 -199.291472)
			(xy 40.646604 -199.268842) (xy 40.638577 -199.235371) (xy 40.633344 -199.166746) (xy 40.63619 -199.132444)
			(xy 40.638032 -199.108884) (xy 40.63407 -199.061799) (xy 40.621477 -199.016256) (xy 40.600686 -198.973825)
			(xy 40.572414 -198.935965) (xy 40.537634 -198.903981) (xy 40.497542 -198.878973) (xy 40.453521 -198.861803)
			(xy 40.407086 -198.853062) (xy 40.38346 -198.852536) (xy 40.374824 -198.852536) (xy 40.342605 -198.851979)
			(xy 40.278739 -198.843424) (xy 40.216577 -198.82645) (xy 40.157227 -198.801358) (xy 40.101741 -198.768594)
			(xy 40.051106 -198.72874) (xy 40.006223 -198.682506) (xy 39.967888 -198.630712) (xy 39.936784 -198.574279)
			(xy 39.913463 -198.51421) (xy 39.898339 -198.451573) (xy 39.891682 -198.387481) (xy 39.893609 -198.323073)
			(xy 39.89832 -198.291196) (xy 39.901406 -198.269378) (xy 39.900928 -198.22532) (xy 39.892859 -198.182004)
			(xy 39.877441 -198.140729) (xy 39.855137 -198.102731) (xy 39.826614 -198.069149) (xy 39.792726 -198.040989)
			(xy 39.754491 -198.019095) (xy 39.713052 -198.004122) (xy 39.669652 -197.99652) (xy 39.647622 -197.996048)
			(xy 38.537134 -197.996048) (xy 38.168834 -198.364348) (xy 36.599114 -198.364348) (xy 36.577387 -198.364706)
			(xy 36.534566 -198.372095) (xy 36.493626 -198.386661) (xy 36.45576 -198.407979) (xy 36.422072 -198.435427)
			(xy 36.393544 -198.468206) (xy 36.371008 -198.505359) (xy 36.355121 -198.545805) (xy 36.346345 -198.588364)
			(xy 36.344936 -198.631795) (xy 36.350936 -198.674833) (xy 36.364169 -198.716223) (xy 36.373816 -198.735696)
			(xy 36.393229 -198.774008) (xy 36.425786 -198.853493) (xy 36.450959 -198.935616) (xy 36.468537 -199.019692)
			(xy 36.478375 -199.105022) (xy 36.480389 -199.190892) (xy 36.474564 -199.276589) (xy 36.460948 -199.361397)
			(xy 36.439653 -199.44461) (xy 36.410859 -199.525534) (xy 36.374805 -199.603495) (xy 36.33179 -199.677843)
			(xy 36.282175 -199.747958) (xy 36.226372 -199.813256) (xy 36.164846 -199.873193) (xy 36.098111 -199.927269)
			(xy 36.026722 -199.975033) (xy 35.951274 -200.016088) (xy 35.872397 -200.050091) (xy 35.790747 -200.076759)
			(xy 35.707006 -200.095869) (xy 35.62187 -200.107262) (xy 35.536051 -200.110844) (xy 35.450262 -200.106584)
			(xy 35.365219 -200.094518) (xy 35.281632 -200.074746) (xy 35.200195 -200.047434) (xy 35.121589 -200.012808)
			(xy 35.046469 -199.971158) (xy 34.97546 -199.922831) (xy 34.909154 -199.868229) (xy 34.848104 -199.807808)
			(xy 34.792819 -199.742071) (xy 34.743759 -199.671565) (xy 34.701334 -199.59688) (xy 34.665897 -199.518636)
			(xy 34.637744 -199.437487) (xy 34.617108 -199.354108) (xy 34.604163 -199.269195) (xy 34.599015 -199.183455)
			(xy 34.601708 -199.097603) (xy 34.61222 -199.012354) (xy 34.630463 -198.928419) (xy 34.656284 -198.846498)
			(xy 34.689469 -198.767273) (xy 34.729741 -198.691405) (xy 34.776764 -198.619525) (xy 34.80308 -198.585582)
			(xy 34.803334 -198.585328) (xy 34.812614 -198.572993) (xy 34.825382 -198.544895) (xy 34.831022 -198.514552)
			(xy 34.829204 -198.483743) (xy 34.820035 -198.454274) (xy 34.804052 -198.427872) (xy 34.793428 -198.416672)
			(xy 32.216598 -195.840096) (xy 31.526988 -195.840096) (xy 31.50347 -195.840611) (xy 31.457237 -195.849266)
			(xy 31.413386 -195.866279) (xy 31.373413 -195.891069) (xy 31.338683 -195.92279) (xy 31.310382 -195.960358)
			(xy 31.289475 -196.002492) (xy 31.276676 -196.047753) (xy 31.272422 -196.094596) (xy 31.276858 -196.141422)
			(xy 31.289833 -196.186633) (xy 31.299912 -196.207888) (xy 31.319016 -196.247002) (xy 31.350741 -196.328071)
			(xy 31.374837 -196.411725) (xy 31.391098 -196.497248) (xy 31.399384 -196.583908) (xy 31.399625 -196.670962)
			(xy 31.391819 -196.757667) (xy 31.376031 -196.843278) (xy 31.352399 -196.927064) (xy 31.321122 -197.008307)
			(xy 31.282471 -197.086311) (xy 31.236775 -197.160409) (xy 31.184426 -197.229966) (xy 31.125871 -197.294386)
			(xy 31.061613 -197.353119) (xy 30.992202 -197.40566) (xy 30.918231 -197.451561) (xy 30.840334 -197.490428)
			(xy 30.759178 -197.521929) (xy 30.675458 -197.545794) (xy 30.58989 -197.561818) (xy 30.503208 -197.569864)
			(xy 30.416152 -197.569864) (xy 30.32947 -197.561818) (xy 30.243902 -197.545794) (xy 30.160182 -197.521929)
			(xy 30.079026 -197.490428) (xy 30.001129 -197.451561) (xy 29.927158 -197.40566) (xy 29.857747 -197.353119)
			(xy 29.793489 -197.294386) (xy 29.734934 -197.229966) (xy 29.682585 -197.160409) (xy 29.636889 -197.086311)
			(xy 29.598238 -197.008307) (xy 29.566961 -196.927064) (xy 29.543329 -196.843278) (xy 29.527541 -196.757667)
			(xy 29.519735 -196.670962) (xy 29.519976 -196.583908) (xy 29.528262 -196.497248) (xy 29.544523 -196.411725)
			(xy 29.568619 -196.328071) (xy 29.600344 -196.247002) (xy 29.619448 -196.207888) (xy 29.629564 -196.186648)
			(xy 29.642543 -196.141433) (xy 29.646981 -196.094601) (xy 29.642727 -196.047752) (xy 29.629926 -196.002486)
			(xy 29.609015 -195.960347) (xy 29.580708 -195.922776) (xy 29.545971 -195.891054) (xy 29.505991 -195.866265)
			(xy 29.462132 -195.849255) (xy 29.415893 -195.840605) (xy 29.392372 -195.840096) (xy 28.660344 -195.840096)
			(xy 28.647043 -195.839968) (xy 28.620486 -195.838445) (xy 28.607258 -195.837048) (xy 28.6004 -195.836286)
			(xy 28.593288 -195.836286) (xy 28.57664 -195.836833) (xy 28.54448 -195.845452) (xy 28.515645 -195.862101)
			(xy 28.492102 -195.885644) (xy 28.475453 -195.914478) (xy 28.466833 -195.946638) (xy 28.466288 -195.963286)
			(xy 28.466288 -199.213486) (xy 29.519874 -199.213486) (xy 29.519874 -199.126586) (xy 29.527892 -199.040057)
			(xy 29.54386 -198.954637) (xy 29.567641 -198.871055) (xy 29.599033 -198.790023) (xy 29.637767 -198.712234)
			(xy 29.683514 -198.63835) (xy 29.735883 -198.569003) (xy 29.794427 -198.504783) (xy 29.858647 -198.446239)
			(xy 29.927994 -198.39387) (xy 30.001878 -198.348123) (xy 30.079667 -198.309389) (xy 30.160699 -198.277997)
			(xy 30.244281 -198.254216) (xy 30.329701 -198.238248) (xy 30.41623 -198.23023) (xy 30.45968 -198.229728)
			(xy 30.50313 -198.23023) (xy 30.589659 -198.238248) (xy 30.675079 -198.254216) (xy 30.758661 -198.277997)
			(xy 30.839693 -198.309389) (xy 30.917482 -198.348123) (xy 30.991366 -198.39387) (xy 31.060713 -198.446239)
			(xy 31.124933 -198.504783) (xy 31.183477 -198.569003) (xy 31.235846 -198.63835) (xy 31.281593 -198.712234)
			(xy 31.320327 -198.790023) (xy 31.351719 -198.871055) (xy 31.3755 -198.954637) (xy 31.391468 -199.040057)
			(xy 31.399486 -199.126586) (xy 31.399486 -199.213486) (xy 31.391468 -199.300015) (xy 31.3755 -199.385435)
			(xy 31.351719 -199.469017) (xy 31.320327 -199.550049) (xy 31.281593 -199.627838) (xy 31.235846 -199.701722)
			(xy 31.183477 -199.771069) (xy 31.124933 -199.835289) (xy 31.060713 -199.893833) (xy 30.991366 -199.946202)
			(xy 30.917482 -199.991949) (xy 30.839693 -200.030683) (xy 30.758661 -200.062075) (xy 30.675079 -200.085856)
			(xy 30.589659 -200.101824) (xy 30.50313 -200.109842) (xy 30.41623 -200.109842) (xy 30.329701 -200.101824)
			(xy 30.244281 -200.085856) (xy 30.160699 -200.062075) (xy 30.079667 -200.030683) (xy 30.001878 -199.991949)
			(xy 29.927994 -199.946202) (xy 29.858647 -199.893833) (xy 29.794427 -199.835289) (xy 29.735883 -199.771069)
			(xy 29.683514 -199.701722) (xy 29.637767 -199.627838) (xy 29.599033 -199.550049) (xy 29.567641 -199.469017)
			(xy 29.54386 -199.385435) (xy 29.527892 -199.300015) (xy 29.519874 -199.213486) (xy 28.466288 -199.213486)
			(xy 28.466288 -201.13498) (xy 28.4667 -201.158171) (xy 28.475077 -201.20379) (xy 28.491593 -201.247131)
			(xy 28.515699 -201.286756) (xy 28.546595 -201.321348) (xy 28.583256 -201.34976) (xy 28.624463 -201.371048)
			(xy 28.66885 -201.384505) (xy 28.714941 -201.389684) (xy 28.761207 -201.386414) (xy 28.783788 -201.381106)
			(xy 28.810849 -201.374607) (xy 28.866188 -201.368692) (xy 28.921798 -201.370883) (xy 28.9765 -201.381132)
			(xy 29.029131 -201.399222) (xy 29.078575 -201.42477) (xy 29.12378 -201.457231) (xy 29.163788 -201.495918)
			(xy 29.197749 -201.540009) (xy 29.224941 -201.588567) (xy 29.244788 -201.640562) (xy 29.256867 -201.694889)
			(xy 29.260923 -201.750395) (xy 29.256869 -201.8059) (xy 29.244791 -201.860228) (xy 29.224946 -201.912223)
			(xy 29.197755 -201.960782) (xy 29.163796 -202.004873) (xy 29.123789 -202.043562) (xy 29.078584 -202.076025)
			(xy 29.029141 -202.101573) (xy 28.97651 -202.119665) (xy 28.921809 -202.129916) (xy 28.866199 -202.132108)
			(xy 28.81086 -202.126195) (xy 28.783788 -202.119738) (xy 28.761203 -202.114516) (xy 28.714967 -202.111304)
			(xy 28.668914 -202.116521) (xy 28.624568 -202.129996) (xy 28.583398 -202.151282) (xy 28.546765 -202.179675)
			(xy 28.515883 -202.214235) (xy 28.491773 -202.253818) (xy 28.475234 -202.297114) (xy 28.466812 -202.34269)
			(xy 28.466288 -202.365864) (xy 28.466288 -210.048956) (xy 72.868285 -210.048956) (xy 72.874295 -209.846255)
			(xy 72.888307 -209.64395) (xy 72.910302 -209.442356) (xy 72.940243 -209.241789) (xy 72.978084 -209.042561)
			(xy 73.023767 -208.844983) (xy 73.07722 -208.649365) (xy 73.138359 -208.456011) (xy 73.20709 -208.265223)
			(xy 73.283304 -208.0773) (xy 73.366883 -207.892534) (xy 73.457696 -207.711215) (xy 73.555601 -207.533625)
			(xy 73.660446 -207.360041) (xy 73.772067 -207.190735) (xy 73.890289 -207.02597) (xy 74.014929 -206.866005)
			(xy 74.14579 -206.711089) (xy 74.28267 -206.561464) (xy 74.425354 -206.417364) (xy 74.57362 -206.279012)
			(xy 74.727236 -206.146627) (xy 74.885961 -206.020413) (xy 75.04955 -205.900569) (xy 75.217745 -205.787281)
			(xy 75.390284 -205.680726) (xy 75.566899 -205.581071) (xy 75.747312 -205.488471) (xy 75.931243 -205.403071)
			(xy 76.118404 -205.325004) (xy 76.308504 -205.254392) (xy 76.501244 -205.191346) (xy 76.696325 -205.135963)
			(xy 76.893442 -205.088331) (xy 77.092286 -205.048523) (xy 77.292548 -205.016601) (xy 77.493914 -204.992617)
			(xy 77.696071 -204.976606) (xy 77.898703 -204.968595) (xy 78.000098 -204.968094) (xy 78.101493 -204.968595)
			(xy 78.304125 -204.976606) (xy 78.506282 -204.992617) (xy 78.707648 -205.016601) (xy 78.90791 -205.048523)
			(xy 79.106754 -205.088331) (xy 79.303871 -205.135963) (xy 79.498952 -205.191346) (xy 79.691692 -205.254392)
			(xy 79.881792 -205.325004) (xy 80.068953 -205.403071) (xy 80.252884 -205.488471) (xy 80.433297 -205.581071)
			(xy 80.609912 -205.680726) (xy 80.782451 -205.787281) (xy 80.950646 -205.900569) (xy 81.114235 -206.020413)
			(xy 81.27296 -206.146627) (xy 81.426576 -206.279012) (xy 81.574842 -206.417364) (xy 81.717526 -206.561464)
			(xy 81.854406 -206.711089) (xy 81.985267 -206.866005) (xy 82.109907 -207.02597) (xy 82.228129 -207.190735)
			(xy 82.33975 -207.360041) (xy 82.444595 -207.533625) (xy 82.5425 -207.711215) (xy 82.633313 -207.892534)
			(xy 82.716892 -208.0773) (xy 82.793106 -208.265223) (xy 82.861837 -208.456011) (xy 82.922976 -208.649365)
			(xy 82.976429 -208.844983) (xy 83.022112 -209.042561) (xy 83.059953 -209.241789) (xy 83.089894 -209.442356)
			(xy 83.111889 -209.64395) (xy 83.125901 -209.846255) (xy 83.131911 -210.048956) (xy 83.129907 -210.251736)
			(xy 83.119894 -210.454279) (xy 83.101887 -210.656268) (xy 83.075915 -210.857387) (xy 83.042017 -211.057324)
			(xy 83.000246 -211.255766) (xy 82.950669 -211.452402) (xy 82.893361 -211.646926) (xy 82.828414 -211.839034)
			(xy 82.755927 -212.028427) (xy 82.676015 -212.214808) (xy 82.588803 -212.397886) (xy 82.494425 -212.577376)
			(xy 82.39303 -212.752997) (xy 82.284776 -212.924476) (xy 82.169832 -213.091543) (xy 82.048377 -213.25394)
			(xy 81.920602 -213.411411) (xy 81.786705 -213.563711) (xy 81.646896 -213.710603) (xy 81.501392 -213.851856)
			(xy 81.350422 -213.987251) (xy 81.194221 -214.116576) (xy 81.033032 -214.239629) (xy 80.867108 -214.356218)
			(xy 80.696708 -214.466161) (xy 80.522097 -214.569286) (xy 80.343548 -214.665432) (xy 80.16134 -214.75445)
			(xy 79.975758 -214.836199) (xy 79.787091 -214.910553) (xy 79.595633 -214.977395) (xy 79.401685 -215.036621)
			(xy 79.205548 -215.088139) (xy 79.007529 -215.131868) (xy 78.807937 -215.167739) (xy 78.607083 -215.195698)
			(xy 78.405282 -215.215699) (xy 78.202848 -215.227712) (xy 78.000098 -215.231719) (xy 77.797348 -215.227712)
			(xy 77.594914 -215.215699) (xy 77.393113 -215.195698) (xy 77.192259 -215.167739) (xy 76.992667 -215.131868)
			(xy 76.794648 -215.088139) (xy 76.598511 -215.036621) (xy 76.404563 -214.977395) (xy 76.213105 -214.910553)
			(xy 76.024438 -214.836199) (xy 75.838856 -214.75445) (xy 75.656648 -214.665432) (xy 75.478099 -214.569286)
			(xy 75.303488 -214.466161) (xy 75.133088 -214.356218) (xy 74.967164 -214.239629) (xy 74.805975 -214.116576)
			(xy 74.649774 -213.987251) (xy 74.498804 -213.851856) (xy 74.3533 -213.710603) (xy 74.213491 -213.563711)
			(xy 74.079594 -213.411411) (xy 73.951819 -213.25394) (xy 73.830364 -213.091543) (xy 73.71542 -212.924476)
			(xy 73.607166 -212.752997) (xy 73.505771 -212.577376) (xy 73.411393 -212.397886) (xy 73.324181 -212.214808)
			(xy 73.244269 -212.028427) (xy 73.171782 -211.839034) (xy 73.106835 -211.646926) (xy 73.049527 -211.452402)
			(xy 72.99995 -211.255766) (xy 72.958179 -211.057324) (xy 72.924281 -210.857387) (xy 72.898309 -210.656268)
			(xy 72.880302 -210.454279) (xy 72.870289 -210.251736) (xy 72.868285 -210.048956) (xy 28.466288 -210.048956)
			(xy 28.466288 -217.526531) (xy 51.342534 -217.526531) (xy 51.342534 -217.445421) (xy 51.350484 -217.364702)
			(xy 51.366307 -217.285151) (xy 51.389852 -217.207535) (xy 51.420891 -217.132599) (xy 51.459126 -217.061067)
			(xy 51.504188 -216.993627) (xy 51.555643 -216.930928) (xy 51.612996 -216.873575) (xy 51.675695 -216.82212)
			(xy 51.743135 -216.777058) (xy 51.814667 -216.738823) (xy 51.889603 -216.707784) (xy 51.967219 -216.684239)
			(xy 52.04677 -216.668416) (xy 52.127489 -216.660466) (xy 52.168044 -216.659968) (xy 52.208599 -216.660466)
			(xy 52.289318 -216.668416) (xy 52.368869 -216.684239) (xy 52.446485 -216.707784) (xy 52.521421 -216.738823)
			(xy 52.592953 -216.777058) (xy 52.660393 -216.82212) (xy 52.723092 -216.873575) (xy 52.780445 -216.930928)
			(xy 52.8319 -216.993627) (xy 52.876962 -217.061067) (xy 52.915197 -217.132599) (xy 52.946236 -217.207535)
			(xy 52.957919 -217.246047) (xy 63.219576 -217.246047) (xy 63.219576 -217.174725) (xy 63.227562 -217.103851)
			(xy 63.243432 -217.034316) (xy 63.266989 -216.966996) (xy 63.297934 -216.902737) (xy 63.33588 -216.842346)
			(xy 63.380349 -216.786584) (xy 63.430782 -216.736151) (xy 63.486544 -216.691682) (xy 63.546935 -216.653736)
			(xy 63.611194 -216.622791) (xy 63.678514 -216.599234) (xy 63.748049 -216.583364) (xy 63.818923 -216.575378)
			(xy 63.854584 -216.574878) (xy 63.890245 -216.575378) (xy 63.961119 -216.583364) (xy 64.030654 -216.599234)
			(xy 64.097974 -216.622791) (xy 64.162233 -216.653736) (xy 64.222624 -216.691682) (xy 64.278386 -216.736151)
			(xy 64.328819 -216.786584) (xy 64.373288 -216.842346) (xy 64.411234 -216.902737) (xy 64.442179 -216.966996)
			(xy 64.465736 -217.034316) (xy 64.481606 -217.103851) (xy 64.489592 -217.174725) (xy 64.489592 -217.246047)
			(xy 66.211188 -217.246047) (xy 66.211188 -217.174725) (xy 66.219174 -217.103851) (xy 66.235044 -217.034316)
			(xy 66.258601 -216.966996) (xy 66.289546 -216.902737) (xy 66.327492 -216.842346) (xy 66.371961 -216.786584)
			(xy 66.422394 -216.736151) (xy 66.478156 -216.691682) (xy 66.538547 -216.653736) (xy 66.602806 -216.622791)
			(xy 66.670126 -216.599234) (xy 66.739661 -216.583364) (xy 66.810535 -216.575378) (xy 66.846196 -216.574878)
			(xy 66.881857 -216.575378) (xy 66.952731 -216.583364) (xy 67.022266 -216.599234) (xy 67.089586 -216.622791)
			(xy 67.153845 -216.653736) (xy 67.214236 -216.691682) (xy 67.269998 -216.736151) (xy 67.320431 -216.786584)
			(xy 67.3649 -216.842346) (xy 67.402846 -216.902737) (xy 67.433791 -216.966996) (xy 67.457348 -217.034316)
			(xy 67.473218 -217.103851) (xy 67.481204 -217.174725) (xy 67.481204 -217.246047) (xy 67.473218 -217.316921)
			(xy 67.457348 -217.386456) (xy 67.433791 -217.453776) (xy 67.402846 -217.518035) (xy 67.3649 -217.578426)
			(xy 67.320431 -217.634188) (xy 67.269998 -217.684621) (xy 67.214236 -217.72909) (xy 67.153845 -217.767036)
			(xy 67.089586 -217.797981) (xy 67.022266 -217.821538) (xy 66.952731 -217.837408) (xy 66.881857 -217.845394)
			(xy 66.810535 -217.845394) (xy 66.739661 -217.837408) (xy 66.670126 -217.821538) (xy 66.602806 -217.797981)
			(xy 66.538547 -217.767036) (xy 66.478156 -217.72909) (xy 66.422394 -217.684621) (xy 66.371961 -217.634188)
			(xy 66.327492 -217.578426) (xy 66.289546 -217.518035) (xy 66.258601 -217.453776) (xy 66.235044 -217.386456)
			(xy 66.219174 -217.316921) (xy 66.211188 -217.246047) (xy 64.489592 -217.246047) (xy 64.481606 -217.316921)
			(xy 64.465736 -217.386456) (xy 64.442179 -217.453776) (xy 64.411234 -217.518035) (xy 64.373288 -217.578426)
			(xy 64.328819 -217.634188) (xy 64.278386 -217.684621) (xy 64.222624 -217.72909) (xy 64.162233 -217.767036)
			(xy 64.097974 -217.797981) (xy 64.030654 -217.821538) (xy 63.961119 -217.837408) (xy 63.890245 -217.845394)
			(xy 63.818923 -217.845394) (xy 63.748049 -217.837408) (xy 63.678514 -217.821538) (xy 63.611194 -217.797981)
			(xy 63.546935 -217.767036) (xy 63.486544 -217.72909) (xy 63.430782 -217.684621) (xy 63.380349 -217.634188)
			(xy 63.33588 -217.578426) (xy 63.297934 -217.518035) (xy 63.266989 -217.453776) (xy 63.243432 -217.386456)
			(xy 63.227562 -217.316921) (xy 63.219576 -217.246047) (xy 52.957919 -217.246047) (xy 52.969781 -217.285151)
			(xy 52.985604 -217.364702) (xy 52.993554 -217.445421) (xy 52.993554 -217.526531) (xy 52.985604 -217.60725)
			(xy 52.969781 -217.686801) (xy 52.946236 -217.764417) (xy 52.915197 -217.839353) (xy 52.876962 -217.910885)
			(xy 52.8319 -217.978325) (xy 52.780445 -218.041024) (xy 52.723092 -218.098377) (xy 52.660393 -218.149832)
			(xy 52.592953 -218.194894) (xy 52.521421 -218.233129) (xy 52.446485 -218.264168) (xy 52.368869 -218.287713)
			(xy 52.289318 -218.303536) (xy 52.208599 -218.311486) (xy 52.127489 -218.311486) (xy 52.04677 -218.303536)
			(xy 51.967219 -218.287713) (xy 51.889603 -218.264168) (xy 51.814667 -218.233129) (xy 51.743135 -218.194894)
			(xy 51.675695 -218.149832) (xy 51.612996 -218.098377) (xy 51.555643 -218.041024) (xy 51.504188 -217.978325)
			(xy 51.459126 -217.910885) (xy 51.420891 -217.839353) (xy 51.389852 -217.764417) (xy 51.366307 -217.686801)
			(xy 51.350484 -217.60725) (xy 51.342534 -217.526531) (xy 28.466288 -217.526531) (xy 28.466288 -219.101924)
			(xy 28.359253 -219.208959) (xy 63.219576 -219.208959) (xy 63.219576 -219.137637) (xy 63.227562 -219.066763)
			(xy 63.243432 -218.997228) (xy 63.266989 -218.929908) (xy 63.297934 -218.865649) (xy 63.33588 -218.805258)
			(xy 63.380349 -218.749496) (xy 63.430782 -218.699063) (xy 63.486544 -218.654594) (xy 63.546935 -218.616648)
			(xy 63.611194 -218.585703) (xy 63.678514 -218.562146) (xy 63.748049 -218.546276) (xy 63.818923 -218.53829)
			(xy 63.854584 -218.53779) (xy 63.890245 -218.53829) (xy 63.961119 -218.546276) (xy 64.030654 -218.562146)
			(xy 64.097974 -218.585703) (xy 64.162233 -218.616648) (xy 64.222624 -218.654594) (xy 64.278386 -218.699063)
			(xy 64.328819 -218.749496) (xy 64.373288 -218.805258) (xy 64.411234 -218.865649) (xy 64.442179 -218.929908)
			(xy 64.465736 -218.997228) (xy 64.481606 -219.066763) (xy 64.489592 -219.137637) (xy 64.489592 -219.208959)
			(xy 66.211188 -219.208959) (xy 66.211188 -219.137637) (xy 66.219174 -219.066763) (xy 66.235044 -218.997228)
			(xy 66.258601 -218.929908) (xy 66.289546 -218.865649) (xy 66.327492 -218.805258) (xy 66.371961 -218.749496)
			(xy 66.422394 -218.699063) (xy 66.478156 -218.654594) (xy 66.538547 -218.616648) (xy 66.602806 -218.585703)
			(xy 66.670126 -218.562146) (xy 66.739661 -218.546276) (xy 66.810535 -218.53829) (xy 66.846196 -218.53779)
			(xy 66.881857 -218.53829) (xy 66.952731 -218.546276) (xy 67.022266 -218.562146) (xy 67.089586 -218.585703)
			(xy 67.153845 -218.616648) (xy 67.214236 -218.654594) (xy 67.269998 -218.699063) (xy 67.320431 -218.749496)
			(xy 67.3649 -218.805258) (xy 67.402846 -218.865649) (xy 67.433791 -218.929908) (xy 67.457348 -218.997228)
			(xy 67.473218 -219.066763) (xy 67.481204 -219.137637) (xy 67.481204 -219.208959) (xy 67.473218 -219.279833)
			(xy 67.457348 -219.349368) (xy 67.433791 -219.416688) (xy 67.402846 -219.480947) (xy 67.3649 -219.541338)
			(xy 67.320431 -219.5971) (xy 67.269998 -219.647533) (xy 67.214236 -219.692002) (xy 67.153845 -219.729948)
			(xy 67.089586 -219.760893) (xy 67.022266 -219.78445) (xy 66.952731 -219.80032) (xy 66.881857 -219.808306)
			(xy 66.810535 -219.808306) (xy 66.739661 -219.80032) (xy 66.670126 -219.78445) (xy 66.602806 -219.760893)
			(xy 66.538547 -219.729948) (xy 66.478156 -219.692002) (xy 66.422394 -219.647533) (xy 66.371961 -219.5971)
			(xy 66.327492 -219.541338) (xy 66.289546 -219.480947) (xy 66.258601 -219.416688) (xy 66.235044 -219.349368)
			(xy 66.219174 -219.279833) (xy 66.211188 -219.208959) (xy 64.489592 -219.208959) (xy 64.481606 -219.279833)
			(xy 64.465736 -219.349368) (xy 64.442179 -219.416688) (xy 64.411234 -219.480947) (xy 64.373288 -219.541338)
			(xy 64.328819 -219.5971) (xy 64.278386 -219.647533) (xy 64.222624 -219.692002) (xy 64.162233 -219.729948)
			(xy 64.097974 -219.760893) (xy 64.030654 -219.78445) (xy 63.961119 -219.80032) (xy 63.890245 -219.808306)
			(xy 63.818923 -219.808306) (xy 63.748049 -219.80032) (xy 63.678514 -219.78445) (xy 63.611194 -219.760893)
			(xy 63.546935 -219.729948) (xy 63.486544 -219.692002) (xy 63.430782 -219.647533) (xy 63.380349 -219.5971)
			(xy 63.33588 -219.541338) (xy 63.297934 -219.480947) (xy 63.266989 -219.416688) (xy 63.243432 -219.349368)
			(xy 63.227562 -219.279833) (xy 63.219576 -219.208959) (xy 28.359253 -219.208959) (xy 27.747976 -219.820236)
			(xy 27.747976 -221.352465) (xy 63.219576 -221.352465) (xy 63.219576 -221.281143) (xy 63.227562 -221.210269)
			(xy 63.243432 -221.140734) (xy 63.266989 -221.073414) (xy 63.297934 -221.009155) (xy 63.33588 -220.948764)
			(xy 63.380349 -220.893002) (xy 63.430782 -220.842569) (xy 63.486544 -220.7981) (xy 63.546935 -220.760154)
			(xy 63.611194 -220.729209) (xy 63.678514 -220.705652) (xy 63.748049 -220.689782) (xy 63.818923 -220.681796)
			(xy 63.854584 -220.681296) (xy 63.890245 -220.681796) (xy 63.961119 -220.689782) (xy 64.030654 -220.705652)
			(xy 64.097974 -220.729209) (xy 64.162233 -220.760154) (xy 64.222624 -220.7981) (xy 64.278386 -220.842569)
			(xy 64.328819 -220.893002) (xy 64.373288 -220.948764) (xy 64.411234 -221.009155) (xy 64.442179 -221.073414)
			(xy 64.465736 -221.140734) (xy 64.481606 -221.210269) (xy 64.489592 -221.281143) (xy 64.489592 -221.352465)
			(xy 66.211188 -221.352465) (xy 66.211188 -221.281143) (xy 66.219174 -221.210269) (xy 66.235044 -221.140734)
			(xy 66.258601 -221.073414) (xy 66.289546 -221.009155) (xy 66.327492 -220.948764) (xy 66.371961 -220.893002)
			(xy 66.422394 -220.842569) (xy 66.478156 -220.7981) (xy 66.538547 -220.760154) (xy 66.602806 -220.729209)
			(xy 66.670126 -220.705652) (xy 66.739661 -220.689782) (xy 66.810535 -220.681796) (xy 66.846196 -220.681296)
			(xy 66.881857 -220.681796) (xy 66.952731 -220.689782) (xy 67.022266 -220.705652) (xy 67.089586 -220.729209)
			(xy 67.153845 -220.760154) (xy 67.214236 -220.7981) (xy 67.269998 -220.842569) (xy 67.320431 -220.893002)
			(xy 67.3649 -220.948764) (xy 67.402846 -221.009155) (xy 67.433791 -221.073414) (xy 67.457348 -221.140734)
			(xy 67.473218 -221.210269) (xy 67.481204 -221.281143) (xy 67.481204 -221.352465) (xy 67.473218 -221.423339)
			(xy 67.457348 -221.492874) (xy 67.433791 -221.560194) (xy 67.402846 -221.624453) (xy 67.3649 -221.684844)
			(xy 67.320431 -221.740606) (xy 67.269998 -221.791039) (xy 67.214236 -221.835508) (xy 67.153845 -221.873454)
			(xy 67.089586 -221.904399) (xy 67.022266 -221.927956) (xy 66.952731 -221.943826) (xy 66.881857 -221.951812)
			(xy 66.810535 -221.951812) (xy 66.739661 -221.943826) (xy 66.670126 -221.927956) (xy 66.602806 -221.904399)
			(xy 66.538547 -221.873454) (xy 66.478156 -221.835508) (xy 66.422394 -221.791039) (xy 66.371961 -221.740606)
			(xy 66.327492 -221.684844) (xy 66.289546 -221.624453) (xy 66.258601 -221.560194) (xy 66.235044 -221.492874)
			(xy 66.219174 -221.423339) (xy 66.211188 -221.352465) (xy 64.489592 -221.352465) (xy 64.481606 -221.423339)
			(xy 64.465736 -221.492874) (xy 64.442179 -221.560194) (xy 64.411234 -221.624453) (xy 64.373288 -221.684844)
			(xy 64.328819 -221.740606) (xy 64.278386 -221.791039) (xy 64.222624 -221.835508) (xy 64.162233 -221.873454)
			(xy 64.097974 -221.904399) (xy 64.030654 -221.927956) (xy 63.961119 -221.943826) (xy 63.890245 -221.951812)
			(xy 63.818923 -221.951812) (xy 63.748049 -221.943826) (xy 63.678514 -221.927956) (xy 63.611194 -221.904399)
			(xy 63.546935 -221.873454) (xy 63.486544 -221.835508) (xy 63.430782 -221.791039) (xy 63.380349 -221.740606)
			(xy 63.33588 -221.684844) (xy 63.297934 -221.624453) (xy 63.266989 -221.560194) (xy 63.243432 -221.492874)
			(xy 63.227562 -221.423339) (xy 63.219576 -221.352465) (xy 27.747976 -221.352465) (xy 27.747976 -229.131042)
			(xy 39.818314 -229.131042) (xy 39.824323 -229.015104) (xy 39.838316 -228.899857) (xy 39.860227 -228.785851)
			(xy 39.889952 -228.673627) (xy 39.927348 -228.563721) (xy 39.972237 -228.456658) (xy 40.024406 -228.352946)
			(xy 40.083606 -228.253081) (xy 40.149555 -228.157538) (xy 40.221938 -228.066772) (xy 40.300411 -227.981217)
			(xy 40.384599 -227.901279) (xy 40.474101 -227.82734) (xy 40.568492 -227.759752) (xy 40.66732 -227.698838)
			(xy 40.770116 -227.644886) (xy 40.876389 -227.598156) (xy 40.985633 -227.558868) (xy 41.097326 -227.527211)
			(xy 41.210938 -227.503335) (xy 41.325926 -227.487354) (xy 41.441743 -227.479345) (xy 41.49979 -227.478844)
			(xy 41.557837 -227.479345) (xy 41.673654 -227.487354) (xy 41.788642 -227.503335) (xy 41.902254 -227.527211)
			(xy 42.013947 -227.558868) (xy 42.123191 -227.598156) (xy 42.229464 -227.644886) (xy 42.33226 -227.698838)
			(xy 42.431088 -227.759752) (xy 42.474869 -227.791101) (xy 63.647829 -227.791101) (xy 63.653878 -227.715531)
			(xy 63.667925 -227.641033) (xy 63.689811 -227.56845) (xy 63.719288 -227.498604) (xy 63.756023 -227.432287)
			(xy 63.799598 -227.370251) (xy 63.84952 -227.313198) (xy 63.905224 -227.261774) (xy 63.966079 -227.216563)
			(xy 64.031394 -227.178076) (xy 64.10043 -227.14675) (xy 64.172405 -227.12294) (xy 64.246503 -227.106915)
			(xy 64.321884 -227.098856) (xy 64.35979 -227.098352) (xy 64.397696 -227.098856) (xy 64.473077 -227.106915)
			(xy 64.547175 -227.12294) (xy 64.61915 -227.14675) (xy 64.688186 -227.178076) (xy 64.753501 -227.216563)
			(xy 64.814356 -227.261774) (xy 64.87006 -227.313198) (xy 64.919982 -227.370251) (xy 64.963557 -227.432287)
			(xy 65.000292 -227.498604) (xy 65.029769 -227.56845) (xy 65.051655 -227.641033) (xy 65.065702 -227.715531)
			(xy 65.071751 -227.791101) (xy 66.187829 -227.791101) (xy 66.193878 -227.715531) (xy 66.207925 -227.641033)
			(xy 66.229811 -227.56845) (xy 66.259288 -227.498604) (xy 66.296023 -227.432287) (xy 66.339598 -227.370251)
			(xy 66.38952 -227.313198) (xy 66.445224 -227.261774) (xy 66.506079 -227.216563) (xy 66.571394 -227.178076)
			(xy 66.64043 -227.14675) (xy 66.712405 -227.12294) (xy 66.786503 -227.106915) (xy 66.861884 -227.098856)
			(xy 66.89979 -227.098352) (xy 66.937696 -227.098856) (xy 67.013077 -227.106915) (xy 67.087175 -227.12294)
			(xy 67.15915 -227.14675) (xy 67.228186 -227.178076) (xy 67.293501 -227.216563) (xy 67.354356 -227.261774)
			(xy 67.41006 -227.313198) (xy 67.459982 -227.370251) (xy 67.503557 -227.432287) (xy 67.540292 -227.498604)
			(xy 67.569769 -227.56845) (xy 67.591655 -227.641033) (xy 67.605702 -227.715531) (xy 67.611751 -227.791101)
			(xy 68.727829 -227.791101) (xy 68.733878 -227.715531) (xy 68.747925 -227.641033) (xy 68.769811 -227.56845)
			(xy 68.799288 -227.498604) (xy 68.836023 -227.432287) (xy 68.879598 -227.370251) (xy 68.92952 -227.313198)
			(xy 68.985224 -227.261774) (xy 69.046079 -227.216563) (xy 69.111394 -227.178076) (xy 69.18043 -227.14675)
			(xy 69.252405 -227.12294) (xy 69.326503 -227.106915) (xy 69.401884 -227.098856) (xy 69.43979 -227.098352)
			(xy 69.477696 -227.098856) (xy 69.553077 -227.106915) (xy 69.627175 -227.12294) (xy 69.69915 -227.14675)
			(xy 69.768186 -227.178076) (xy 69.833501 -227.216563) (xy 69.894356 -227.261774) (xy 69.95006 -227.313198)
			(xy 69.999982 -227.370251) (xy 70.043557 -227.432287) (xy 70.080292 -227.498604) (xy 70.109769 -227.56845)
			(xy 70.131655 -227.641033) (xy 70.145702 -227.715531) (xy 70.151751 -227.791101) (xy 71.267829 -227.791101)
			(xy 71.273878 -227.715531) (xy 71.287925 -227.641033) (xy 71.309811 -227.56845) (xy 71.339288 -227.498604)
			(xy 71.376023 -227.432287) (xy 71.419598 -227.370251) (xy 71.46952 -227.313198) (xy 71.525224 -227.261774)
			(xy 71.586079 -227.216563) (xy 71.651394 -227.178076) (xy 71.72043 -227.14675) (xy 71.792405 -227.12294)
			(xy 71.866503 -227.106915) (xy 71.941884 -227.098856) (xy 71.97979 -227.098352) (xy 72.017696 -227.098856)
			(xy 72.093077 -227.106915) (xy 72.167175 -227.12294) (xy 72.23915 -227.14675) (xy 72.308186 -227.178076)
			(xy 72.373501 -227.216563) (xy 72.434356 -227.261774) (xy 72.49006 -227.313198) (xy 72.539982 -227.370251)
			(xy 72.583557 -227.432287) (xy 72.620292 -227.498604) (xy 72.649769 -227.56845) (xy 72.671655 -227.641033)
			(xy 72.685702 -227.715531) (xy 72.691751 -227.791101) (xy 73.807829 -227.791101) (xy 73.813878 -227.715531)
			(xy 73.827925 -227.641033) (xy 73.849811 -227.56845) (xy 73.879288 -227.498604) (xy 73.916023 -227.432287)
			(xy 73.959598 -227.370251) (xy 74.00952 -227.313198) (xy 74.065224 -227.261774) (xy 74.126079 -227.216563)
			(xy 74.191394 -227.178076) (xy 74.26043 -227.14675) (xy 74.332405 -227.12294) (xy 74.406503 -227.106915)
			(xy 74.481884 -227.098856) (xy 74.51979 -227.098352) (xy 74.557696 -227.098856) (xy 74.633077 -227.106915)
			(xy 74.707175 -227.12294) (xy 74.77915 -227.14675) (xy 74.848186 -227.178076) (xy 74.913501 -227.216563)
			(xy 74.974356 -227.261774) (xy 75.03006 -227.313198) (xy 75.079982 -227.370251) (xy 75.123557 -227.432287)
			(xy 75.160292 -227.498604) (xy 75.189769 -227.56845) (xy 75.211655 -227.641033) (xy 75.225702 -227.715531)
			(xy 75.231751 -227.791101) (xy 76.347829 -227.791101) (xy 76.353878 -227.715531) (xy 76.367925 -227.641033)
			(xy 76.389811 -227.56845) (xy 76.419288 -227.498604) (xy 76.456023 -227.432287) (xy 76.499598 -227.370251)
			(xy 76.54952 -227.313198) (xy 76.605224 -227.261774) (xy 76.666079 -227.216563) (xy 76.731394 -227.178076)
			(xy 76.80043 -227.14675) (xy 76.872405 -227.12294) (xy 76.946503 -227.106915) (xy 77.021884 -227.098856)
			(xy 77.05979 -227.098352) (xy 77.097696 -227.098856) (xy 77.173077 -227.106915) (xy 77.247175 -227.12294)
			(xy 77.31915 -227.14675) (xy 77.388186 -227.178076) (xy 77.453501 -227.216563) (xy 77.514356 -227.261774)
			(xy 77.57006 -227.313198) (xy 77.619982 -227.370251) (xy 77.663557 -227.432287) (xy 77.700292 -227.498604)
			(xy 77.729769 -227.56845) (xy 77.751655 -227.641033) (xy 77.765702 -227.715531) (xy 77.771751 -227.791101)
			(xy 78.887829 -227.791101) (xy 78.893878 -227.715531) (xy 78.907925 -227.641033) (xy 78.929811 -227.56845)
			(xy 78.959288 -227.498604) (xy 78.996023 -227.432287) (xy 79.039598 -227.370251) (xy 79.08952 -227.313198)
			(xy 79.145224 -227.261774) (xy 79.206079 -227.216563) (xy 79.271394 -227.178076) (xy 79.34043 -227.14675)
			(xy 79.412405 -227.12294) (xy 79.486503 -227.106915) (xy 79.561884 -227.098856) (xy 79.59979 -227.098352)
			(xy 79.637696 -227.098856) (xy 79.713077 -227.106915) (xy 79.787175 -227.12294) (xy 79.85915 -227.14675)
			(xy 79.928186 -227.178076) (xy 79.993501 -227.216563) (xy 80.054356 -227.261774) (xy 80.11006 -227.313198)
			(xy 80.159982 -227.370251) (xy 80.203557 -227.432287) (xy 80.240292 -227.498604) (xy 80.269769 -227.56845)
			(xy 80.291655 -227.641033) (xy 80.305702 -227.715531) (xy 80.311751 -227.791101) (xy 81.427829 -227.791101)
			(xy 81.433878 -227.715531) (xy 81.447925 -227.641033) (xy 81.469811 -227.56845) (xy 81.499288 -227.498604)
			(xy 81.536023 -227.432287) (xy 81.579598 -227.370251) (xy 81.62952 -227.313198) (xy 81.685224 -227.261774)
			(xy 81.746079 -227.216563) (xy 81.811394 -227.178076) (xy 81.88043 -227.14675) (xy 81.952405 -227.12294)
			(xy 82.026503 -227.106915) (xy 82.101884 -227.098856) (xy 82.13979 -227.098352) (xy 82.177696 -227.098856)
			(xy 82.253077 -227.106915) (xy 82.327175 -227.12294) (xy 82.39915 -227.14675) (xy 82.468186 -227.178076)
			(xy 82.533501 -227.216563) (xy 82.594356 -227.261774) (xy 82.65006 -227.313198) (xy 82.699982 -227.370251)
			(xy 82.743557 -227.432287) (xy 82.780292 -227.498604) (xy 82.809769 -227.56845) (xy 82.831655 -227.641033)
			(xy 82.845702 -227.715531) (xy 82.851751 -227.791101) (xy 82.849732 -227.866885) (xy 82.83967 -227.942025)
			(xy 82.821678 -228.01567) (xy 82.79596 -228.086986) (xy 82.762808 -228.155163) (xy 82.722596 -228.219431)
			(xy 82.675781 -228.27906) (xy 82.622893 -228.333376) (xy 82.564531 -228.381762) (xy 82.501356 -228.42367)
			(xy 82.434085 -228.458626) (xy 82.36348 -228.486233) (xy 82.290339 -228.506179) (xy 82.215494 -228.518238)
			(xy 82.13979 -228.522273) (xy 82.064086 -228.518238) (xy 81.989241 -228.506179) (xy 81.9161 -228.486233)
			(xy 81.845495 -228.458626) (xy 81.778224 -228.42367) (xy 81.715049 -228.381762) (xy 81.656687 -228.333376)
			(xy 81.603799 -228.27906) (xy 81.556984 -228.219431) (xy 81.516772 -228.155163) (xy 81.48362 -228.086986)
			(xy 81.457902 -228.01567) (xy 81.43991 -227.942025) (xy 81.429848 -227.866885) (xy 81.427829 -227.791101)
			(xy 80.311751 -227.791101) (xy 80.309732 -227.866885) (xy 80.29967 -227.942025) (xy 80.281678 -228.01567)
			(xy 80.25596 -228.086986) (xy 80.222808 -228.155163) (xy 80.182596 -228.219431) (xy 80.135781 -228.27906)
			(xy 80.082893 -228.333376) (xy 80.024531 -228.381762) (xy 79.961356 -228.42367) (xy 79.894085 -228.458626)
			(xy 79.82348 -228.486233) (xy 79.750339 -228.506179) (xy 79.675494 -228.518238) (xy 79.59979 -228.522273)
			(xy 79.524086 -228.518238) (xy 79.449241 -228.506179) (xy 79.3761 -228.486233) (xy 79.305495 -228.458626)
			(xy 79.238224 -228.42367) (xy 79.175049 -228.381762) (xy 79.116687 -228.333376) (xy 79.063799 -228.27906)
			(xy 79.016984 -228.219431) (xy 78.976772 -228.155163) (xy 78.94362 -228.086986) (xy 78.917902 -228.01567)
			(xy 78.89991 -227.942025) (xy 78.889848 -227.866885) (xy 78.887829 -227.791101) (xy 77.771751 -227.791101)
			(xy 77.769732 -227.866885) (xy 77.75967 -227.942025) (xy 77.741678 -228.01567) (xy 77.71596 -228.086986)
			(xy 77.682808 -228.155163) (xy 77.642596 -228.219431) (xy 77.595781 -228.27906) (xy 77.542893 -228.333376)
			(xy 77.484531 -228.381762) (xy 77.421356 -228.42367) (xy 77.354085 -228.458626) (xy 77.28348 -228.486233)
			(xy 77.210339 -228.506179) (xy 77.135494 -228.518238) (xy 77.05979 -228.522273) (xy 76.984086 -228.518238)
			(xy 76.909241 -228.506179) (xy 76.8361 -228.486233) (xy 76.765495 -228.458626) (xy 76.698224 -228.42367)
			(xy 76.635049 -228.381762) (xy 76.576687 -228.333376) (xy 76.523799 -228.27906) (xy 76.476984 -228.219431)
			(xy 76.436772 -228.155163) (xy 76.40362 -228.086986) (xy 76.377902 -228.01567) (xy 76.35991 -227.942025)
			(xy 76.349848 -227.866885) (xy 76.347829 -227.791101) (xy 75.231751 -227.791101) (xy 75.229732 -227.866885)
			(xy 75.21967 -227.942025) (xy 75.201678 -228.01567) (xy 75.17596 -228.086986) (xy 75.142808 -228.155163)
			(xy 75.102596 -228.219431) (xy 75.055781 -228.27906) (xy 75.002893 -228.333376) (xy 74.944531 -228.381762)
			(xy 74.881356 -228.42367) (xy 74.814085 -228.458626) (xy 74.74348 -228.486233) (xy 74.670339 -228.506179)
			(xy 74.595494 -228.518238) (xy 74.51979 -228.522273) (xy 74.444086 -228.518238) (xy 74.369241 -228.506179)
			(xy 74.2961 -228.486233) (xy 74.225495 -228.458626) (xy 74.158224 -228.42367) (xy 74.095049 -228.381762)
			(xy 74.036687 -228.333376) (xy 73.983799 -228.27906) (xy 73.936984 -228.219431) (xy 73.896772 -228.155163)
			(xy 73.86362 -228.086986) (xy 73.837902 -228.01567) (xy 73.81991 -227.942025) (xy 73.809848 -227.866885)
			(xy 73.807829 -227.791101) (xy 72.691751 -227.791101) (xy 72.689732 -227.866885) (xy 72.67967 -227.942025)
			(xy 72.661678 -228.01567) (xy 72.63596 -228.086986) (xy 72.602808 -228.155163) (xy 72.562596 -228.219431)
			(xy 72.515781 -228.27906) (xy 72.462893 -228.333376) (xy 72.404531 -228.381762) (xy 72.341356 -228.42367)
			(xy 72.274085 -228.458626) (xy 72.20348 -228.486233) (xy 72.130339 -228.506179) (xy 72.055494 -228.518238)
			(xy 71.97979 -228.522273) (xy 71.904086 -228.518238) (xy 71.829241 -228.506179) (xy 71.7561 -228.486233)
			(xy 71.685495 -228.458626) (xy 71.618224 -228.42367) (xy 71.555049 -228.381762) (xy 71.496687 -228.333376)
			(xy 71.443799 -228.27906) (xy 71.396984 -228.219431) (xy 71.356772 -228.155163) (xy 71.32362 -228.086986)
			(xy 71.297902 -228.01567) (xy 71.27991 -227.942025) (xy 71.269848 -227.866885) (xy 71.267829 -227.791101)
			(xy 70.151751 -227.791101) (xy 70.149732 -227.866885) (xy 70.13967 -227.942025) (xy 70.121678 -228.01567)
			(xy 70.09596 -228.086986) (xy 70.062808 -228.155163) (xy 70.022596 -228.219431) (xy 69.975781 -228.27906)
			(xy 69.922893 -228.333376) (xy 69.864531 -228.381762) (xy 69.801356 -228.42367) (xy 69.734085 -228.458626)
			(xy 69.66348 -228.486233) (xy 69.590339 -228.506179) (xy 69.515494 -228.518238) (xy 69.43979 -228.522273)
			(xy 69.364086 -228.518238) (xy 69.289241 -228.506179) (xy 69.2161 -228.486233) (xy 69.145495 -228.458626)
			(xy 69.078224 -228.42367) (xy 69.015049 -228.381762) (xy 68.956687 -228.333376) (xy 68.903799 -228.27906)
			(xy 68.856984 -228.219431) (xy 68.816772 -228.155163) (xy 68.78362 -228.086986) (xy 68.757902 -228.01567)
			(xy 68.73991 -227.942025) (xy 68.729848 -227.866885) (xy 68.727829 -227.791101) (xy 67.611751 -227.791101)
			(xy 67.609732 -227.866885) (xy 67.59967 -227.942025) (xy 67.581678 -228.01567) (xy 67.55596 -228.086986)
			(xy 67.522808 -228.155163) (xy 67.482596 -228.219431) (xy 67.435781 -228.27906) (xy 67.382893 -228.333376)
			(xy 67.324531 -228.381762) (xy 67.261356 -228.42367) (xy 67.194085 -228.458626) (xy 67.12348 -228.486233)
			(xy 67.050339 -228.506179) (xy 66.975494 -228.518238) (xy 66.89979 -228.522273) (xy 66.824086 -228.518238)
			(xy 66.749241 -228.506179) (xy 66.6761 -228.486233) (xy 66.605495 -228.458626) (xy 66.538224 -228.42367)
			(xy 66.475049 -228.381762) (xy 66.416687 -228.333376) (xy 66.363799 -228.27906) (xy 66.316984 -228.219431)
			(xy 66.276772 -228.155163) (xy 66.24362 -228.086986) (xy 66.217902 -228.01567) (xy 66.19991 -227.942025)
			(xy 66.189848 -227.866885) (xy 66.187829 -227.791101) (xy 65.071751 -227.791101) (xy 65.069732 -227.866885)
			(xy 65.05967 -227.942025) (xy 65.041678 -228.01567) (xy 65.01596 -228.086986) (xy 64.982808 -228.155163)
			(xy 64.942596 -228.219431) (xy 64.895781 -228.27906) (xy 64.842893 -228.333376) (xy 64.784531 -228.381762)
			(xy 64.721356 -228.42367) (xy 64.654085 -228.458626) (xy 64.58348 -228.486233) (xy 64.510339 -228.506179)
			(xy 64.435494 -228.518238) (xy 64.35979 -228.522273) (xy 64.284086 -228.518238) (xy 64.209241 -228.506179)
			(xy 64.1361 -228.486233) (xy 64.065495 -228.458626) (xy 63.998224 -228.42367) (xy 63.935049 -228.381762)
			(xy 63.876687 -228.333376) (xy 63.823799 -228.27906) (xy 63.776984 -228.219431) (xy 63.736772 -228.155163)
			(xy 63.70362 -228.086986) (xy 63.677902 -228.01567) (xy 63.65991 -227.942025) (xy 63.649848 -227.866885)
			(xy 63.647829 -227.791101) (xy 42.474869 -227.791101) (xy 42.525479 -227.82734) (xy 42.614981 -227.901279)
			(xy 42.699169 -227.981217) (xy 42.777642 -228.066772) (xy 42.850025 -228.157538) (xy 42.915974 -228.253081)
			(xy 42.975174 -228.352946) (xy 43.027343 -228.456658) (xy 43.072232 -228.563721) (xy 43.109628 -228.673627)
			(xy 43.139353 -228.785851) (xy 43.161264 -228.899857) (xy 43.175257 -229.015104) (xy 43.181266 -229.131042)
			(xy 43.179263 -229.247118) (xy 43.169255 -229.36278) (xy 43.151292 -229.477475) (xy 43.125459 -229.590658)
			(xy 43.091879 -229.701789) (xy 43.050711 -229.810338) (xy 43.002153 -229.915788) (xy 42.946436 -230.017637)
			(xy 42.883824 -230.1154) (xy 42.814617 -230.20861) (xy 42.739144 -230.296823) (xy 42.657765 -230.379619)
			(xy 42.570868 -230.456603) (xy 42.526017 -230.491121) (xy 63.647829 -230.491121) (xy 63.653878 -230.415551)
			(xy 63.667925 -230.341053) (xy 63.689811 -230.26847) (xy 63.719288 -230.198624) (xy 63.756023 -230.132307)
			(xy 63.799598 -230.070271) (xy 63.84952 -230.013218) (xy 63.905224 -229.961794) (xy 63.966079 -229.916583)
			(xy 64.031394 -229.878096) (xy 64.10043 -229.84677) (xy 64.172405 -229.82296) (xy 64.246503 -229.806935)
			(xy 64.321884 -229.798876) (xy 64.35979 -229.798372) (xy 64.397696 -229.798876) (xy 64.473077 -229.806935)
			(xy 64.547175 -229.82296) (xy 64.61915 -229.84677) (xy 64.688186 -229.878096) (xy 64.753501 -229.916583)
			(xy 64.814356 -229.961794) (xy 64.87006 -230.013218) (xy 64.919982 -230.070271) (xy 64.963557 -230.132307)
			(xy 65.000292 -230.198624) (xy 65.029769 -230.26847) (xy 65.051655 -230.341053) (xy 65.065702 -230.415551)
			(xy 65.071751 -230.491121) (xy 66.187829 -230.491121) (xy 66.193878 -230.415551) (xy 66.207925 -230.341053)
			(xy 66.229811 -230.26847) (xy 66.259288 -230.198624) (xy 66.296023 -230.132307) (xy 66.339598 -230.070271)
			(xy 66.38952 -230.013218) (xy 66.445224 -229.961794) (xy 66.506079 -229.916583) (xy 66.571394 -229.878096)
			(xy 66.64043 -229.84677) (xy 66.712405 -229.82296) (xy 66.786503 -229.806935) (xy 66.861884 -229.798876)
			(xy 66.89979 -229.798372) (xy 66.937696 -229.798876) (xy 67.013077 -229.806935) (xy 67.087175 -229.82296)
			(xy 67.15915 -229.84677) (xy 67.228186 -229.878096) (xy 67.293501 -229.916583) (xy 67.354356 -229.961794)
			(xy 67.41006 -230.013218) (xy 67.459982 -230.070271) (xy 67.503557 -230.132307) (xy 67.540292 -230.198624)
			(xy 67.569769 -230.26847) (xy 67.591655 -230.341053) (xy 67.605702 -230.415551) (xy 67.611751 -230.491121)
			(xy 68.727829 -230.491121) (xy 68.733878 -230.415551) (xy 68.747925 -230.341053) (xy 68.769811 -230.26847)
			(xy 68.799288 -230.198624) (xy 68.836023 -230.132307) (xy 68.879598 -230.070271) (xy 68.92952 -230.013218)
			(xy 68.985224 -229.961794) (xy 69.046079 -229.916583) (xy 69.111394 -229.878096) (xy 69.18043 -229.84677)
			(xy 69.252405 -229.82296) (xy 69.326503 -229.806935) (xy 69.401884 -229.798876) (xy 69.43979 -229.798372)
			(xy 69.477696 -229.798876) (xy 69.553077 -229.806935) (xy 69.627175 -229.82296) (xy 69.69915 -229.84677)
			(xy 69.768186 -229.878096) (xy 69.833501 -229.916583) (xy 69.894356 -229.961794) (xy 69.95006 -230.013218)
			(xy 69.999982 -230.070271) (xy 70.043557 -230.132307) (xy 70.080292 -230.198624) (xy 70.109769 -230.26847)
			(xy 70.131655 -230.341053) (xy 70.145702 -230.415551) (xy 70.151751 -230.491121) (xy 71.267829 -230.491121)
			(xy 71.273878 -230.415551) (xy 71.287925 -230.341053) (xy 71.309811 -230.26847) (xy 71.339288 -230.198624)
			(xy 71.376023 -230.132307) (xy 71.419598 -230.070271) (xy 71.46952 -230.013218) (xy 71.525224 -229.961794)
			(xy 71.586079 -229.916583) (xy 71.651394 -229.878096) (xy 71.72043 -229.84677) (xy 71.792405 -229.82296)
			(xy 71.866503 -229.806935) (xy 71.941884 -229.798876) (xy 71.97979 -229.798372) (xy 72.017696 -229.798876)
			(xy 72.093077 -229.806935) (xy 72.167175 -229.82296) (xy 72.23915 -229.84677) (xy 72.308186 -229.878096)
			(xy 72.373501 -229.916583) (xy 72.434356 -229.961794) (xy 72.49006 -230.013218) (xy 72.539982 -230.070271)
			(xy 72.583557 -230.132307) (xy 72.620292 -230.198624) (xy 72.649769 -230.26847) (xy 72.671655 -230.341053)
			(xy 72.685702 -230.415551) (xy 72.691751 -230.491121) (xy 73.807829 -230.491121) (xy 73.813878 -230.415551)
			(xy 73.827925 -230.341053) (xy 73.849811 -230.26847) (xy 73.879288 -230.198624) (xy 73.916023 -230.132307)
			(xy 73.959598 -230.070271) (xy 74.00952 -230.013218) (xy 74.065224 -229.961794) (xy 74.126079 -229.916583)
			(xy 74.191394 -229.878096) (xy 74.26043 -229.84677) (xy 74.332405 -229.82296) (xy 74.406503 -229.806935)
			(xy 74.481884 -229.798876) (xy 74.51979 -229.798372) (xy 74.557696 -229.798876) (xy 74.633077 -229.806935)
			(xy 74.707175 -229.82296) (xy 74.77915 -229.84677) (xy 74.848186 -229.878096) (xy 74.913501 -229.916583)
			(xy 74.974356 -229.961794) (xy 75.03006 -230.013218) (xy 75.079982 -230.070271) (xy 75.123557 -230.132307)
			(xy 75.160292 -230.198624) (xy 75.189769 -230.26847) (xy 75.211655 -230.341053) (xy 75.225702 -230.415551)
			(xy 75.231751 -230.491121) (xy 76.347829 -230.491121) (xy 76.353878 -230.415551) (xy 76.367925 -230.341053)
			(xy 76.389811 -230.26847) (xy 76.419288 -230.198624) (xy 76.456023 -230.132307) (xy 76.499598 -230.070271)
			(xy 76.54952 -230.013218) (xy 76.605224 -229.961794) (xy 76.666079 -229.916583) (xy 76.731394 -229.878096)
			(xy 76.80043 -229.84677) (xy 76.872405 -229.82296) (xy 76.946503 -229.806935) (xy 77.021884 -229.798876)
			(xy 77.05979 -229.798372) (xy 77.097696 -229.798876) (xy 77.173077 -229.806935) (xy 77.247175 -229.82296)
			(xy 77.31915 -229.84677) (xy 77.388186 -229.878096) (xy 77.453501 -229.916583) (xy 77.514356 -229.961794)
			(xy 77.57006 -230.013218) (xy 77.619982 -230.070271) (xy 77.663557 -230.132307) (xy 77.700292 -230.198624)
			(xy 77.729769 -230.26847) (xy 77.751655 -230.341053) (xy 77.765702 -230.415551) (xy 77.771751 -230.491121)
			(xy 78.887829 -230.491121) (xy 78.893878 -230.415551) (xy 78.907925 -230.341053) (xy 78.929811 -230.26847)
			(xy 78.959288 -230.198624) (xy 78.996023 -230.132307) (xy 79.039598 -230.070271) (xy 79.08952 -230.013218)
			(xy 79.145224 -229.961794) (xy 79.206079 -229.916583) (xy 79.271394 -229.878096) (xy 79.34043 -229.84677)
			(xy 79.412405 -229.82296) (xy 79.486503 -229.806935) (xy 79.561884 -229.798876) (xy 79.59979 -229.798372)
			(xy 79.637696 -229.798876) (xy 79.713077 -229.806935) (xy 79.787175 -229.82296) (xy 79.85915 -229.84677)
			(xy 79.928186 -229.878096) (xy 79.993501 -229.916583) (xy 80.054356 -229.961794) (xy 80.11006 -230.013218)
			(xy 80.159982 -230.070271) (xy 80.203557 -230.132307) (xy 80.240292 -230.198624) (xy 80.269769 -230.26847)
			(xy 80.291655 -230.341053) (xy 80.305702 -230.415551) (xy 80.311751 -230.491121) (xy 80.309732 -230.566905)
			(xy 80.29967 -230.642045) (xy 80.281678 -230.71569) (xy 80.25596 -230.787006) (xy 80.222808 -230.855183)
			(xy 80.182596 -230.919451) (xy 80.135781 -230.97908) (xy 80.082893 -231.033396) (xy 80.024531 -231.081782)
			(xy 79.961356 -231.12369) (xy 79.894085 -231.158646) (xy 79.82348 -231.186253) (xy 79.750339 -231.206199)
			(xy 79.675494 -231.218258) (xy 79.59979 -231.222293) (xy 79.524086 -231.218258) (xy 79.449241 -231.206199)
			(xy 79.3761 -231.186253) (xy 79.305495 -231.158646) (xy 79.238224 -231.12369) (xy 79.175049 -231.081782)
			(xy 79.116687 -231.033396) (xy 79.063799 -230.97908) (xy 79.016984 -230.919451) (xy 78.976772 -230.855183)
			(xy 78.94362 -230.787006) (xy 78.917902 -230.71569) (xy 78.89991 -230.642045) (xy 78.889848 -230.566905)
			(xy 78.887829 -230.491121) (xy 77.771751 -230.491121) (xy 77.769732 -230.566905) (xy 77.75967 -230.642045)
			(xy 77.741678 -230.71569) (xy 77.71596 -230.787006) (xy 77.682808 -230.855183) (xy 77.642596 -230.919451)
			(xy 77.595781 -230.97908) (xy 77.542893 -231.033396) (xy 77.484531 -231.081782) (xy 77.421356 -231.12369)
			(xy 77.354085 -231.158646) (xy 77.28348 -231.186253) (xy 77.210339 -231.206199) (xy 77.135494 -231.218258)
			(xy 77.05979 -231.222293) (xy 76.984086 -231.218258) (xy 76.909241 -231.206199) (xy 76.8361 -231.186253)
			(xy 76.765495 -231.158646) (xy 76.698224 -231.12369) (xy 76.635049 -231.081782) (xy 76.576687 -231.033396)
			(xy 76.523799 -230.97908) (xy 76.476984 -230.919451) (xy 76.436772 -230.855183) (xy 76.40362 -230.787006)
			(xy 76.377902 -230.71569) (xy 76.35991 -230.642045) (xy 76.349848 -230.566905) (xy 76.347829 -230.491121)
			(xy 75.231751 -230.491121) (xy 75.229732 -230.566905) (xy 75.21967 -230.642045) (xy 75.201678 -230.71569)
			(xy 75.17596 -230.787006) (xy 75.142808 -230.855183) (xy 75.102596 -230.919451) (xy 75.055781 -230.97908)
			(xy 75.002893 -231.033396) (xy 74.944531 -231.081782) (xy 74.881356 -231.12369) (xy 74.814085 -231.158646)
			(xy 74.74348 -231.186253) (xy 74.670339 -231.206199) (xy 74.595494 -231.218258) (xy 74.51979 -231.222293)
			(xy 74.444086 -231.218258) (xy 74.369241 -231.206199) (xy 74.2961 -231.186253) (xy 74.225495 -231.158646)
			(xy 74.158224 -231.12369) (xy 74.095049 -231.081782) (xy 74.036687 -231.033396) (xy 73.983799 -230.97908)
			(xy 73.936984 -230.919451) (xy 73.896772 -230.855183) (xy 73.86362 -230.787006) (xy 73.837902 -230.71569)
			(xy 73.81991 -230.642045) (xy 73.809848 -230.566905) (xy 73.807829 -230.491121) (xy 72.691751 -230.491121)
			(xy 72.689732 -230.566905) (xy 72.67967 -230.642045) (xy 72.661678 -230.71569) (xy 72.63596 -230.787006)
			(xy 72.602808 -230.855183) (xy 72.562596 -230.919451) (xy 72.515781 -230.97908) (xy 72.462893 -231.033396)
			(xy 72.404531 -231.081782) (xy 72.341356 -231.12369) (xy 72.274085 -231.158646) (xy 72.20348 -231.186253)
			(xy 72.130339 -231.206199) (xy 72.055494 -231.218258) (xy 71.97979 -231.222293) (xy 71.904086 -231.218258)
			(xy 71.829241 -231.206199) (xy 71.7561 -231.186253) (xy 71.685495 -231.158646) (xy 71.618224 -231.12369)
			(xy 71.555049 -231.081782) (xy 71.496687 -231.033396) (xy 71.443799 -230.97908) (xy 71.396984 -230.919451)
			(xy 71.356772 -230.855183) (xy 71.32362 -230.787006) (xy 71.297902 -230.71569) (xy 71.27991 -230.642045)
			(xy 71.269848 -230.566905) (xy 71.267829 -230.491121) (xy 70.151751 -230.491121) (xy 70.149732 -230.566905)
			(xy 70.13967 -230.642045) (xy 70.121678 -230.71569) (xy 70.09596 -230.787006) (xy 70.062808 -230.855183)
			(xy 70.022596 -230.919451) (xy 69.975781 -230.97908) (xy 69.922893 -231.033396) (xy 69.864531 -231.081782)
			(xy 69.801356 -231.12369) (xy 69.734085 -231.158646) (xy 69.66348 -231.186253) (xy 69.590339 -231.206199)
			(xy 69.515494 -231.218258) (xy 69.43979 -231.222293) (xy 69.364086 -231.218258) (xy 69.289241 -231.206199)
			(xy 69.2161 -231.186253) (xy 69.145495 -231.158646) (xy 69.078224 -231.12369) (xy 69.015049 -231.081782)
			(xy 68.956687 -231.033396) (xy 68.903799 -230.97908) (xy 68.856984 -230.919451) (xy 68.816772 -230.855183)
			(xy 68.78362 -230.787006) (xy 68.757902 -230.71569) (xy 68.73991 -230.642045) (xy 68.729848 -230.566905)
			(xy 68.727829 -230.491121) (xy 67.611751 -230.491121) (xy 67.609732 -230.566905) (xy 67.59967 -230.642045)
			(xy 67.581678 -230.71569) (xy 67.55596 -230.787006) (xy 67.522808 -230.855183) (xy 67.482596 -230.919451)
			(xy 67.435781 -230.97908) (xy 67.382893 -231.033396) (xy 67.324531 -231.081782) (xy 67.261356 -231.12369)
			(xy 67.194085 -231.158646) (xy 67.12348 -231.186253) (xy 67.050339 -231.206199) (xy 66.975494 -231.218258)
			(xy 66.89979 -231.222293) (xy 66.824086 -231.218258) (xy 66.749241 -231.206199) (xy 66.6761 -231.186253)
			(xy 66.605495 -231.158646) (xy 66.538224 -231.12369) (xy 66.475049 -231.081782) (xy 66.416687 -231.033396)
			(xy 66.363799 -230.97908) (xy 66.316984 -230.919451) (xy 66.276772 -230.855183) (xy 66.24362 -230.787006)
			(xy 66.217902 -230.71569) (xy 66.19991 -230.642045) (xy 66.189848 -230.566905) (xy 66.187829 -230.491121)
			(xy 65.071751 -230.491121) (xy 65.069732 -230.566905) (xy 65.05967 -230.642045) (xy 65.041678 -230.71569)
			(xy 65.01596 -230.787006) (xy 64.982808 -230.855183) (xy 64.942596 -230.919451) (xy 64.895781 -230.97908)
			(xy 64.842893 -231.033396) (xy 64.784531 -231.081782) (xy 64.721356 -231.12369) (xy 64.654085 -231.158646)
			(xy 64.58348 -231.186253) (xy 64.510339 -231.206199) (xy 64.435494 -231.218258) (xy 64.35979 -231.222293)
			(xy 64.284086 -231.218258) (xy 64.209241 -231.206199) (xy 64.1361 -231.186253) (xy 64.065495 -231.158646)
			(xy 63.998224 -231.12369) (xy 63.935049 -231.081782) (xy 63.876687 -231.033396) (xy 63.823799 -230.97908)
			(xy 63.776984 -230.919451) (xy 63.736772 -230.855183) (xy 63.70362 -230.787006) (xy 63.677902 -230.71569)
			(xy 63.65991 -230.642045) (xy 63.649848 -230.566905) (xy 63.647829 -230.491121) (xy 42.526017 -230.491121)
			(xy 42.478867 -230.527408) (xy 42.3822 -230.591698) (xy 42.281328 -230.649165) (xy 42.176731 -230.699536)
			(xy 42.068908 -230.742571) (xy 41.958374 -230.778065) (xy 41.845654 -230.805848) (xy 41.731286 -230.825788)
			(xy 41.615814 -230.83779) (xy 41.49979 -230.841797) (xy 41.383766 -230.83779) (xy 41.268294 -230.825788)
			(xy 41.153926 -230.805848) (xy 41.041206 -230.778065) (xy 40.930672 -230.742571) (xy 40.822849 -230.699536)
			(xy 40.718252 -230.649165) (xy 40.61738 -230.591698) (xy 40.520713 -230.527408) (xy 40.428712 -230.456603)
			(xy 40.341815 -230.379619) (xy 40.260436 -230.296823) (xy 40.184963 -230.20861) (xy 40.115756 -230.1154)
			(xy 40.053144 -230.017637) (xy 39.997427 -229.915788) (xy 39.948869 -229.810338) (xy 39.907701 -229.701789)
			(xy 39.874121 -229.590658) (xy 39.848288 -229.477475) (xy 39.830325 -229.36278) (xy 39.820317 -229.247118)
			(xy 39.818314 -229.131042) (xy 27.747976 -229.131042) (xy 27.747976 -231.13365) (xy 26.648213 -232.233486)
			(xy 29.519874 -232.233486) (xy 29.519874 -232.146586) (xy 29.527892 -232.060057) (xy 29.54386 -231.974637)
			(xy 29.567641 -231.891055) (xy 29.599033 -231.810023) (xy 29.637767 -231.732234) (xy 29.683514 -231.65835)
			(xy 29.735883 -231.589003) (xy 29.794427 -231.524783) (xy 29.858647 -231.466239) (xy 29.927994 -231.41387)
			(xy 30.001878 -231.368123) (xy 30.079667 -231.329389) (xy 30.160699 -231.297997) (xy 30.244281 -231.274216)
			(xy 30.329701 -231.258248) (xy 30.41623 -231.25023) (xy 30.45968 -231.249728) (xy 30.50313 -231.25023)
			(xy 30.589659 -231.258248) (xy 30.675079 -231.274216) (xy 30.758661 -231.297997) (xy 30.839693 -231.329389)
			(xy 30.917482 -231.368123) (xy 30.991366 -231.41387) (xy 31.060713 -231.466239) (xy 31.124933 -231.524783)
			(xy 31.183477 -231.589003) (xy 31.235846 -231.65835) (xy 31.281593 -231.732234) (xy 31.320327 -231.810023)
			(xy 31.351719 -231.891055) (xy 31.3755 -231.974637) (xy 31.391468 -232.060057) (xy 31.399486 -232.146586)
			(xy 31.399486 -232.233486) (xy 34.599874 -232.233486) (xy 34.599874 -232.146586) (xy 34.607892 -232.060057)
			(xy 34.62386 -231.974637) (xy 34.647641 -231.891055) (xy 34.679033 -231.810023) (xy 34.717767 -231.732234)
			(xy 34.763514 -231.65835) (xy 34.815883 -231.589003) (xy 34.874427 -231.524783) (xy 34.938647 -231.466239)
			(xy 35.007994 -231.41387) (xy 35.081878 -231.368123) (xy 35.159667 -231.329389) (xy 35.240699 -231.297997)
			(xy 35.324281 -231.274216) (xy 35.409701 -231.258248) (xy 35.49623 -231.25023) (xy 35.53968 -231.249728)
			(xy 35.58313 -231.25023) (xy 35.669659 -231.258248) (xy 35.755079 -231.274216) (xy 35.838661 -231.297997)
			(xy 35.919693 -231.329389) (xy 35.997482 -231.368123) (xy 36.071366 -231.41387) (xy 36.140713 -231.466239)
			(xy 36.204933 -231.524783) (xy 36.263477 -231.589003) (xy 36.315846 -231.65835) (xy 36.361593 -231.732234)
			(xy 36.400327 -231.810023) (xy 36.431719 -231.891055) (xy 36.4555 -231.974637) (xy 36.471468 -232.060057)
			(xy 36.479486 -232.146586) (xy 36.479486 -232.233486) (xy 36.471468 -232.320015) (xy 36.4555 -232.405435)
			(xy 36.431719 -232.489017) (xy 36.400327 -232.570049) (xy 36.361593 -232.647838) (xy 36.315846 -232.721722)
			(xy 36.263477 -232.791069) (xy 36.204933 -232.855289) (xy 36.140713 -232.913833) (xy 36.071366 -232.966202)
			(xy 35.997482 -233.011949) (xy 35.919693 -233.050683) (xy 35.838661 -233.082075) (xy 35.755079 -233.105856)
			(xy 35.669659 -233.121824) (xy 35.58313 -233.129842) (xy 35.49623 -233.129842) (xy 35.409701 -233.121824)
			(xy 35.324281 -233.105856) (xy 35.240699 -233.082075) (xy 35.159667 -233.050683) (xy 35.081878 -233.011949)
			(xy 35.007994 -232.966202) (xy 34.938647 -232.913833) (xy 34.874427 -232.855289) (xy 34.815883 -232.791069)
			(xy 34.763514 -232.721722) (xy 34.717767 -232.647838) (xy 34.679033 -232.570049) (xy 34.647641 -232.489017)
			(xy 34.62386 -232.405435) (xy 34.607892 -232.320015) (xy 34.599874 -232.233486) (xy 31.399486 -232.233486)
			(xy 31.391468 -232.320015) (xy 31.3755 -232.405435) (xy 31.351719 -232.489017) (xy 31.320327 -232.570049)
			(xy 31.281593 -232.647838) (xy 31.235846 -232.721722) (xy 31.183477 -232.791069) (xy 31.124933 -232.855289)
			(xy 31.060713 -232.913833) (xy 30.991366 -232.966202) (xy 30.917482 -233.011949) (xy 30.839693 -233.050683)
			(xy 30.758661 -233.082075) (xy 30.675079 -233.105856) (xy 30.589659 -233.121824) (xy 30.50313 -233.129842)
			(xy 30.41623 -233.129842) (xy 30.329701 -233.121824) (xy 30.244281 -233.105856) (xy 30.160699 -233.082075)
			(xy 30.079667 -233.050683) (xy 30.001878 -233.011949) (xy 29.927994 -232.966202) (xy 29.858647 -232.913833)
			(xy 29.794427 -232.855289) (xy 29.735883 -232.791069) (xy 29.683514 -232.721722) (xy 29.637767 -232.647838)
			(xy 29.599033 -232.570049) (xy 29.567641 -232.489017) (xy 29.54386 -232.405435) (xy 29.527892 -232.320015)
			(xy 29.519874 -232.233486) (xy 26.648213 -232.233486) (xy 24.108382 -234.773486) (xy 29.519874 -234.773486)
			(xy 29.519874 -234.686586) (xy 29.527892 -234.600057) (xy 29.54386 -234.514637) (xy 29.567641 -234.431055)
			(xy 29.599033 -234.350023) (xy 29.637767 -234.272234) (xy 29.683514 -234.19835) (xy 29.735883 -234.129003)
			(xy 29.794427 -234.064783) (xy 29.858647 -234.006239) (xy 29.927994 -233.95387) (xy 30.001878 -233.908123)
			(xy 30.079667 -233.869389) (xy 30.160699 -233.837997) (xy 30.244281 -233.814216) (xy 30.329701 -233.798248)
			(xy 30.41623 -233.79023) (xy 30.45968 -233.789728) (xy 30.50313 -233.79023) (xy 30.589659 -233.798248)
			(xy 30.675079 -233.814216) (xy 30.758661 -233.837997) (xy 30.839693 -233.869389) (xy 30.917482 -233.908123)
			(xy 30.991366 -233.95387) (xy 31.060713 -234.006239) (xy 31.124933 -234.064783) (xy 31.183477 -234.129003)
			(xy 31.235846 -234.19835) (xy 31.281593 -234.272234) (xy 31.320327 -234.350023) (xy 31.351719 -234.431055)
			(xy 31.3755 -234.514637) (xy 31.391468 -234.600057) (xy 31.399486 -234.686586) (xy 31.399486 -234.773486)
			(xy 34.599874 -234.773486) (xy 34.599874 -234.686586) (xy 34.607892 -234.600057) (xy 34.62386 -234.514637)
			(xy 34.647641 -234.431055) (xy 34.679033 -234.350023) (xy 34.717767 -234.272234) (xy 34.763514 -234.19835)
			(xy 34.815883 -234.129003) (xy 34.874427 -234.064783) (xy 34.938647 -234.006239) (xy 35.007994 -233.95387)
			(xy 35.081878 -233.908123) (xy 35.159667 -233.869389) (xy 35.240699 -233.837997) (xy 35.324281 -233.814216)
			(xy 35.409701 -233.798248) (xy 35.49623 -233.79023) (xy 35.53968 -233.789728) (xy 35.58313 -233.79023)
			(xy 35.669659 -233.798248) (xy 35.755079 -233.814216) (xy 35.838661 -233.837997) (xy 35.919693 -233.869389)
			(xy 35.997482 -233.908123) (xy 36.071366 -233.95387) (xy 36.140713 -234.006239) (xy 36.204933 -234.064783)
			(xy 36.263477 -234.129003) (xy 36.315846 -234.19835) (xy 36.361593 -234.272234) (xy 36.400327 -234.350023)
			(xy 36.431719 -234.431055) (xy 36.4555 -234.514637) (xy 36.471468 -234.600057) (xy 36.479486 -234.686586)
			(xy 36.479486 -234.773486) (xy 36.471468 -234.860015) (xy 36.4555 -234.945435) (xy 36.431719 -235.029017)
			(xy 36.400327 -235.110049) (xy 36.361593 -235.187838) (xy 36.315846 -235.261722) (xy 36.263477 -235.331069)
			(xy 36.204933 -235.395289) (xy 36.140713 -235.453833) (xy 36.071366 -235.506202) (xy 35.997482 -235.551949)
			(xy 35.919693 -235.590683) (xy 35.838661 -235.622075) (xy 35.755079 -235.645856) (xy 35.669659 -235.661824)
			(xy 35.58313 -235.669842) (xy 35.49623 -235.669842) (xy 35.409701 -235.661824) (xy 35.324281 -235.645856)
			(xy 35.240699 -235.622075) (xy 35.159667 -235.590683) (xy 35.081878 -235.551949) (xy 35.007994 -235.506202)
			(xy 34.938647 -235.453833) (xy 34.874427 -235.395289) (xy 34.815883 -235.331069) (xy 34.763514 -235.261722)
			(xy 34.717767 -235.187838) (xy 34.679033 -235.110049) (xy 34.647641 -235.029017) (xy 34.62386 -234.945435)
			(xy 34.607892 -234.860015) (xy 34.599874 -234.773486) (xy 31.399486 -234.773486) (xy 31.391468 -234.860015)
			(xy 31.3755 -234.945435) (xy 31.351719 -235.029017) (xy 31.320327 -235.110049) (xy 31.281593 -235.187838)
			(xy 31.235846 -235.261722) (xy 31.183477 -235.331069) (xy 31.124933 -235.395289) (xy 31.060713 -235.453833)
			(xy 30.991366 -235.506202) (xy 30.917482 -235.551949) (xy 30.839693 -235.590683) (xy 30.758661 -235.622075)
			(xy 30.675079 -235.645856) (xy 30.589659 -235.661824) (xy 30.50313 -235.669842) (xy 30.41623 -235.669842)
			(xy 30.329701 -235.661824) (xy 30.244281 -235.645856) (xy 30.160699 -235.622075) (xy 30.079667 -235.590683)
			(xy 30.001878 -235.551949) (xy 29.927994 -235.506202) (xy 29.858647 -235.453833) (xy 29.794427 -235.395289)
			(xy 29.735883 -235.331069) (xy 29.683514 -235.261722) (xy 29.637767 -235.187838) (xy 29.599033 -235.110049)
			(xy 29.567641 -235.029017) (xy 29.54386 -234.945435) (xy 29.527892 -234.860015) (xy 29.519874 -234.773486)
			(xy 24.108382 -234.773486) (xy 23.9268 -234.95508) (xy 23.910477 -234.972071) (xy 23.883851 -235.010939)
			(xy 23.864847 -235.054049) (xy 23.854116 -235.099924) (xy 23.852025 -235.14699) (xy 23.858647 -235.193636)
			(xy 23.873754 -235.238261) (xy 23.896829 -235.279336) (xy 23.91156 -235.297726) (xy 23.928507 -235.318789)
			(xy 23.957047 -235.364699) (xy 23.978821 -235.414178) (xy 23.993391 -235.466235) (xy 24.000466 -235.519828)
			(xy 23.999905 -235.573883) (xy 23.991719 -235.627317) (xy 23.976071 -235.67906) (xy 23.953275 -235.728077)
			(xy 23.923788 -235.773384) (xy 23.8882 -235.814075) (xy 23.847224 -235.849334) (xy 23.80168 -235.878455)
			(xy 23.752482 -235.900856) (xy 23.700614 -235.916086) (xy 23.647116 -235.923842) (xy 23.593058 -235.923968)
			(xy 23.539524 -235.916462) (xy 23.487586 -235.901472) (xy 23.462742 -235.890816) (xy 23.441509 -235.881851)
			(xy 23.396767 -235.870811) (xy 23.350768 -235.868018) (xy 23.305019 -235.873563) (xy 23.261019 -235.887264)
			(xy 23.220209 -235.908672) (xy 23.183927 -235.937086) (xy 23.153362 -235.971574) (xy 23.129514 -236.011008)
			(xy 23.113166 -236.054095) (xy 23.104852 -236.099422) (xy 23.104348 -236.122464) (xy 23.104348 -237.313486)
			(xy 29.519874 -237.313486) (xy 29.519874 -237.226586) (xy 29.527892 -237.140057) (xy 29.54386 -237.054637)
			(xy 29.567641 -236.971055) (xy 29.599033 -236.890023) (xy 29.637767 -236.812234) (xy 29.683514 -236.73835)
			(xy 29.735883 -236.669003) (xy 29.794427 -236.604783) (xy 29.858647 -236.546239) (xy 29.927994 -236.49387)
			(xy 30.001878 -236.448123) (xy 30.079667 -236.409389) (xy 30.160699 -236.377997) (xy 30.244281 -236.354216)
			(xy 30.329701 -236.338248) (xy 30.41623 -236.33023) (xy 30.45968 -236.329728) (xy 30.50313 -236.33023)
			(xy 30.589659 -236.338248) (xy 30.675079 -236.354216) (xy 30.758661 -236.377997) (xy 30.839693 -236.409389)
			(xy 30.917482 -236.448123) (xy 30.991366 -236.49387) (xy 31.060713 -236.546239) (xy 31.124933 -236.604783)
			(xy 31.183477 -236.669003) (xy 31.235846 -236.73835) (xy 31.281593 -236.812234) (xy 31.320327 -236.890023)
			(xy 31.351719 -236.971055) (xy 31.3755 -237.054637) (xy 31.391468 -237.140057) (xy 31.399486 -237.226586)
			(xy 31.399486 -237.313486) (xy 34.599874 -237.313486) (xy 34.599874 -237.226586) (xy 34.607892 -237.140057)
			(xy 34.62386 -237.054637) (xy 34.647641 -236.971055) (xy 34.679033 -236.890023) (xy 34.717767 -236.812234)
			(xy 34.763514 -236.73835) (xy 34.815883 -236.669003) (xy 34.874427 -236.604783) (xy 34.938647 -236.546239)
			(xy 35.007994 -236.49387) (xy 35.081878 -236.448123) (xy 35.159667 -236.409389) (xy 35.240699 -236.377997)
			(xy 35.324281 -236.354216) (xy 35.409701 -236.338248) (xy 35.49623 -236.33023) (xy 35.53968 -236.329728)
			(xy 35.58313 -236.33023) (xy 35.669659 -236.338248) (xy 35.755079 -236.354216) (xy 35.838661 -236.377997)
			(xy 35.919693 -236.409389) (xy 35.997482 -236.448123) (xy 36.071366 -236.49387) (xy 36.140713 -236.546239)
			(xy 36.204933 -236.604783) (xy 36.263477 -236.669003) (xy 36.315846 -236.73835) (xy 36.361593 -236.812234)
			(xy 36.400327 -236.890023) (xy 36.431719 -236.971055) (xy 36.4555 -237.054637) (xy 36.471468 -237.140057)
			(xy 36.479486 -237.226586) (xy 36.479486 -237.313486) (xy 36.471468 -237.400015) (xy 36.4555 -237.485435)
			(xy 36.431719 -237.569017) (xy 36.400327 -237.650049) (xy 36.361593 -237.727838) (xy 36.315846 -237.801722)
			(xy 36.263477 -237.871069) (xy 36.204933 -237.935289) (xy 36.199092 -237.940614) (xy 44.325031 -237.940614)
			(xy 44.331131 -237.885177) (xy 44.345237 -237.83122) (xy 44.367049 -237.779891) (xy 44.396103 -237.732285)
			(xy 44.431778 -237.689417) (xy 44.473315 -237.6522) (xy 44.519828 -237.621427) (xy 44.570325 -237.597755)
			(xy 44.623732 -237.581687) (xy 44.678908 -237.573567) (xy 44.706794 -237.573058) (xy 44.73468 -237.573567)
			(xy 44.789856 -237.581687) (xy 44.843263 -237.597755) (xy 44.89376 -237.621427) (xy 44.940273 -237.6522)
			(xy 44.98181 -237.689417) (xy 45.017485 -237.732285) (xy 45.046539 -237.779891) (xy 45.068351 -237.83122)
			(xy 45.082457 -237.885177) (xy 45.088557 -237.940614) (xy 45.08652 -237.996348) (xy 45.07639 -238.051191)
			(xy 45.058383 -238.103975) (xy 45.032882 -238.153575) (xy 45.000431 -238.198933) (xy 44.961722 -238.239082)
			(xy 44.917579 -238.273168) (xy 44.868944 -238.300464) (xy 44.816853 -238.320387) (xy 44.762416 -238.332513)
			(xy 44.706794 -238.336584) (xy 44.651172 -238.332513) (xy 44.596735 -238.320387) (xy 44.544644 -238.300464)
			(xy 44.496009 -238.273168) (xy 44.451866 -238.239082) (xy 44.413157 -238.198933) (xy 44.380706 -238.153575)
			(xy 44.355205 -238.103975) (xy 44.337198 -238.051191) (xy 44.327068 -237.996348) (xy 44.325031 -237.940614)
			(xy 36.199092 -237.940614) (xy 36.140713 -237.993833) (xy 36.071366 -238.046202) (xy 35.997482 -238.091949)
			(xy 35.919693 -238.130683) (xy 35.838661 -238.162075) (xy 35.755079 -238.185856) (xy 35.669659 -238.201824)
			(xy 35.58313 -238.209842) (xy 35.49623 -238.209842) (xy 35.409701 -238.201824) (xy 35.324281 -238.185856)
			(xy 35.240699 -238.162075) (xy 35.159667 -238.130683) (xy 35.081878 -238.091949) (xy 35.007994 -238.046202)
			(xy 34.938647 -237.993833) (xy 34.874427 -237.935289) (xy 34.815883 -237.871069) (xy 34.763514 -237.801722)
			(xy 34.717767 -237.727838) (xy 34.679033 -237.650049) (xy 34.647641 -237.569017) (xy 34.62386 -237.485435)
			(xy 34.607892 -237.400015) (xy 34.599874 -237.313486) (xy 31.399486 -237.313486) (xy 31.391468 -237.400015)
			(xy 31.3755 -237.485435) (xy 31.351719 -237.569017) (xy 31.320327 -237.650049) (xy 31.281593 -237.727838)
			(xy 31.235846 -237.801722) (xy 31.183477 -237.871069) (xy 31.124933 -237.935289) (xy 31.060713 -237.993833)
			(xy 30.991366 -238.046202) (xy 30.917482 -238.091949) (xy 30.839693 -238.130683) (xy 30.758661 -238.162075)
			(xy 30.675079 -238.185856) (xy 30.589659 -238.201824) (xy 30.50313 -238.209842) (xy 30.41623 -238.209842)
			(xy 30.329701 -238.201824) (xy 30.244281 -238.185856) (xy 30.160699 -238.162075) (xy 30.079667 -238.130683)
			(xy 30.001878 -238.091949) (xy 29.927994 -238.046202) (xy 29.858647 -237.993833) (xy 29.794427 -237.935289)
			(xy 29.735883 -237.871069) (xy 29.683514 -237.801722) (xy 29.637767 -237.727838) (xy 29.599033 -237.650049)
			(xy 29.567641 -237.569017) (xy 29.54386 -237.485435) (xy 29.527892 -237.400015) (xy 29.519874 -237.313486)
			(xy 23.104348 -237.313486) (xy 23.104348 -237.690152) (xy 20.941014 -239.853486) (xy 29.519874 -239.853486)
			(xy 29.519874 -239.766586) (xy 29.527892 -239.680057) (xy 29.54386 -239.594637) (xy 29.567641 -239.511055)
			(xy 29.599033 -239.430023) (xy 29.637767 -239.352234) (xy 29.683514 -239.27835) (xy 29.735883 -239.209003)
			(xy 29.794427 -239.144783) (xy 29.858647 -239.086239) (xy 29.927994 -239.03387) (xy 30.001878 -238.988123)
			(xy 30.079667 -238.949389) (xy 30.160699 -238.917997) (xy 30.244281 -238.894216) (xy 30.329701 -238.878248)
			(xy 30.41623 -238.87023) (xy 30.45968 -238.869728) (xy 30.50313 -238.87023) (xy 30.589659 -238.878248)
			(xy 30.675079 -238.894216) (xy 30.758661 -238.917997) (xy 30.839693 -238.949389) (xy 30.917482 -238.988123)
			(xy 30.991366 -239.03387) (xy 31.060713 -239.086239) (xy 31.124933 -239.144783) (xy 31.183477 -239.209003)
			(xy 31.235846 -239.27835) (xy 31.281593 -239.352234) (xy 31.320327 -239.430023) (xy 31.351719 -239.511055)
			(xy 31.3755 -239.594637) (xy 31.391468 -239.680057) (xy 31.399486 -239.766586) (xy 31.399486 -239.853486)
			(xy 34.599874 -239.853486) (xy 34.599874 -239.766586) (xy 34.607892 -239.680057) (xy 34.62386 -239.594637)
			(xy 34.647641 -239.511055) (xy 34.679033 -239.430023) (xy 34.717767 -239.352234) (xy 34.763514 -239.27835)
			(xy 34.815883 -239.209003) (xy 34.874427 -239.144783) (xy 34.938647 -239.086239) (xy 35.007994 -239.03387)
			(xy 35.081878 -238.988123) (xy 35.159667 -238.949389) (xy 35.240699 -238.917997) (xy 35.324281 -238.894216)
			(xy 35.409701 -238.878248) (xy 35.49623 -238.87023) (xy 35.53968 -238.869728) (xy 35.58313 -238.87023)
			(xy 35.669659 -238.878248) (xy 35.755079 -238.894216) (xy 35.838661 -238.917997) (xy 35.919693 -238.949389)
			(xy 35.997482 -238.988123) (xy 36.071366 -239.03387) (xy 36.140713 -239.086239) (xy 36.204933 -239.144783)
			(xy 36.263477 -239.209003) (xy 36.315846 -239.27835) (xy 36.361593 -239.352234) (xy 36.400327 -239.430023)
			(xy 36.431719 -239.511055) (xy 36.4555 -239.594637) (xy 36.471468 -239.680057) (xy 36.479486 -239.766586)
			(xy 36.479486 -239.853486) (xy 36.47532 -239.898446) (xy 44.319443 -239.898446) (xy 44.325543 -239.843009)
			(xy 44.339649 -239.789052) (xy 44.361461 -239.737723) (xy 44.390515 -239.690117) (xy 44.42619 -239.647249)
			(xy 44.467727 -239.610032) (xy 44.51424 -239.579259) (xy 44.564737 -239.555587) (xy 44.618144 -239.539519)
			(xy 44.67332 -239.531399) (xy 44.701206 -239.53089) (xy 44.729092 -239.531399) (xy 44.784268 -239.539519)
			(xy 44.837675 -239.555587) (xy 44.888172 -239.579259) (xy 44.934685 -239.610032) (xy 44.976222 -239.647249)
			(xy 45.011897 -239.690117) (xy 45.040951 -239.737723) (xy 45.062763 -239.789052) (xy 45.076869 -239.843009)
			(xy 45.082969 -239.898446) (xy 45.080932 -239.95418) (xy 45.070802 -240.009023) (xy 45.052795 -240.061807)
			(xy 45.027294 -240.111407) (xy 44.994843 -240.156765) (xy 44.956134 -240.196914) (xy 44.911991 -240.231)
			(xy 44.863356 -240.258296) (xy 44.811265 -240.278219) (xy 44.756828 -240.290345) (xy 44.701206 -240.294416)
			(xy 44.645584 -240.290345) (xy 44.591147 -240.278219) (xy 44.539056 -240.258296) (xy 44.490421 -240.231)
			(xy 44.446278 -240.196914) (xy 44.407569 -240.156765) (xy 44.375118 -240.111407) (xy 44.349617 -240.061807)
			(xy 44.33161 -240.009023) (xy 44.32148 -239.95418) (xy 44.319443 -239.898446) (xy 36.47532 -239.898446)
			(xy 36.471468 -239.940015) (xy 36.4555 -240.025435) (xy 36.431719 -240.109017) (xy 36.400327 -240.190049)
			(xy 36.361593 -240.267838) (xy 36.315846 -240.341722) (xy 36.263477 -240.411069) (xy 36.204933 -240.475289)
			(xy 36.140713 -240.533833) (xy 36.071366 -240.586202) (xy 36.000851 -240.629863) (xy 52.537604 -240.629863)
			(xy 52.537604 -240.548753) (xy 52.545554 -240.468034) (xy 52.561377 -240.388483) (xy 52.584922 -240.310867)
			(xy 52.615961 -240.235931) (xy 52.654196 -240.164399) (xy 52.699258 -240.096959) (xy 52.750713 -240.03426)
			(xy 52.808066 -239.976907) (xy 52.870765 -239.925452) (xy 52.938205 -239.88039) (xy 53.009737 -239.842155)
			(xy 53.084673 -239.811116) (xy 53.162289 -239.787571) (xy 53.24184 -239.771748) (xy 53.322559 -239.763798)
			(xy 53.363114 -239.7633) (xy 53.403669 -239.763798) (xy 53.484388 -239.771748) (xy 53.563939 -239.787571)
			(xy 53.641555 -239.811116) (xy 53.716491 -239.842155) (xy 53.788023 -239.88039) (xy 53.855463 -239.925452)
			(xy 53.918162 -239.976907) (xy 53.975515 -240.03426) (xy 54.02697 -240.096959) (xy 54.072032 -240.164399)
			(xy 54.110267 -240.235931) (xy 54.141306 -240.310867) (xy 54.164851 -240.388483) (xy 54.180674 -240.468034)
			(xy 54.188624 -240.548753) (xy 54.188624 -240.629863) (xy 54.180674 -240.710582) (xy 54.164851 -240.790133)
			(xy 54.141306 -240.867749) (xy 54.110267 -240.942685) (xy 54.072032 -241.014217) (xy 54.02697 -241.081657)
			(xy 53.975515 -241.144356) (xy 53.950834 -241.169037) (xy 66.107556 -241.169037) (xy 66.107556 -241.097715)
			(xy 66.115542 -241.026841) (xy 66.131412 -240.957306) (xy 66.154969 -240.889986) (xy 66.185914 -240.825727)
			(xy 66.22386 -240.765336) (xy 66.268329 -240.709574) (xy 66.318762 -240.659141) (xy 66.374524 -240.614672)
			(xy 66.434915 -240.576726) (xy 66.499174 -240.545781) (xy 66.566494 -240.522224) (xy 66.636029 -240.506354)
			(xy 66.706903 -240.498368) (xy 66.742564 -240.497868) (xy 66.778225 -240.498368) (xy 66.849099 -240.506354)
			(xy 66.918634 -240.522224) (xy 66.985954 -240.545781) (xy 67.050213 -240.576726) (xy 67.110604 -240.614672)
			(xy 67.166366 -240.659141) (xy 67.216799 -240.709574) (xy 67.261268 -240.765336) (xy 67.299214 -240.825727)
			(xy 67.330159 -240.889986) (xy 67.353716 -240.957306) (xy 67.369586 -241.026841) (xy 67.377572 -241.097715)
			(xy 67.377572 -241.169037) (xy 69.099168 -241.169037) (xy 69.099168 -241.097715) (xy 69.107154 -241.026841)
			(xy 69.123024 -240.957306) (xy 69.146581 -240.889986) (xy 69.177526 -240.825727) (xy 69.215472 -240.765336)
			(xy 69.259941 -240.709574) (xy 69.310374 -240.659141) (xy 69.366136 -240.614672) (xy 69.426527 -240.576726)
			(xy 69.490786 -240.545781) (xy 69.558106 -240.522224) (xy 69.627641 -240.506354) (xy 69.698515 -240.498368)
			(xy 69.734176 -240.497868) (xy 69.769837 -240.498368) (xy 69.840711 -240.506354) (xy 69.910246 -240.522224)
			(xy 69.977566 -240.545781) (xy 70.041825 -240.576726) (xy 70.102216 -240.614672) (xy 70.157978 -240.659141)
			(xy 70.208411 -240.709574) (xy 70.25288 -240.765336) (xy 70.290826 -240.825727) (xy 70.321771 -240.889986)
			(xy 70.345328 -240.957306) (xy 70.361198 -241.026841) (xy 70.369184 -241.097715) (xy 70.369184 -241.169037)
			(xy 70.361198 -241.239911) (xy 70.345328 -241.309446) (xy 70.321771 -241.376766) (xy 70.290826 -241.441025)
			(xy 70.25288 -241.501416) (xy 70.208411 -241.557178) (xy 70.157978 -241.607611) (xy 70.102216 -241.65208)
			(xy 70.041825 -241.690026) (xy 69.977566 -241.720971) (xy 69.910246 -241.744528) (xy 69.840711 -241.760398)
			(xy 69.769837 -241.768384) (xy 69.698515 -241.768384) (xy 69.627641 -241.760398) (xy 69.558106 -241.744528)
			(xy 69.490786 -241.720971) (xy 69.426527 -241.690026) (xy 69.366136 -241.65208) (xy 69.310374 -241.607611)
			(xy 69.259941 -241.557178) (xy 69.215472 -241.501416) (xy 69.177526 -241.441025) (xy 69.146581 -241.376766)
			(xy 69.123024 -241.309446) (xy 69.107154 -241.239911) (xy 69.099168 -241.169037) (xy 67.377572 -241.169037)
			(xy 67.369586 -241.239911) (xy 67.353716 -241.309446) (xy 67.330159 -241.376766) (xy 67.299214 -241.441025)
			(xy 67.261268 -241.501416) (xy 67.216799 -241.557178) (xy 67.166366 -241.607611) (xy 67.110604 -241.65208)
			(xy 67.050213 -241.690026) (xy 66.985954 -241.720971) (xy 66.918634 -241.744528) (xy 66.849099 -241.760398)
			(xy 66.778225 -241.768384) (xy 66.706903 -241.768384) (xy 66.636029 -241.760398) (xy 66.566494 -241.744528)
			(xy 66.499174 -241.720971) (xy 66.434915 -241.690026) (xy 66.374524 -241.65208) (xy 66.318762 -241.607611)
			(xy 66.268329 -241.557178) (xy 66.22386 -241.501416) (xy 66.185914 -241.441025) (xy 66.154969 -241.376766)
			(xy 66.131412 -241.309446) (xy 66.115542 -241.239911) (xy 66.107556 -241.169037) (xy 53.950834 -241.169037)
			(xy 53.918162 -241.201709) (xy 53.855463 -241.253164) (xy 53.788023 -241.298226) (xy 53.716491 -241.336461)
			(xy 53.641555 -241.3675) (xy 53.563939 -241.391045) (xy 53.484388 -241.406868) (xy 53.403669 -241.414818)
			(xy 53.322559 -241.414818) (xy 53.24184 -241.406868) (xy 53.162289 -241.391045) (xy 53.084673 -241.3675)
			(xy 53.009737 -241.336461) (xy 52.938205 -241.298226) (xy 52.870765 -241.253164) (xy 52.808066 -241.201709)
			(xy 52.750713 -241.144356) (xy 52.699258 -241.081657) (xy 52.654196 -241.014217) (xy 52.615961 -240.942685)
			(xy 52.584922 -240.867749) (xy 52.561377 -240.790133) (xy 52.545554 -240.710582) (xy 52.537604 -240.629863)
			(xy 36.000851 -240.629863) (xy 35.997482 -240.631949) (xy 35.919693 -240.670683) (xy 35.838661 -240.702075)
			(xy 35.755079 -240.725856) (xy 35.669659 -240.741824) (xy 35.58313 -240.749842) (xy 35.49623 -240.749842)
			(xy 35.409701 -240.741824) (xy 35.324281 -240.725856) (xy 35.240699 -240.702075) (xy 35.159667 -240.670683)
			(xy 35.081878 -240.631949) (xy 35.007994 -240.586202) (xy 34.938647 -240.533833) (xy 34.874427 -240.475289)
			(xy 34.815883 -240.411069) (xy 34.763514 -240.341722) (xy 34.717767 -240.267838) (xy 34.679033 -240.190049)
			(xy 34.647641 -240.109017) (xy 34.62386 -240.025435) (xy 34.607892 -239.940015) (xy 34.599874 -239.853486)
			(xy 31.399486 -239.853486) (xy 31.391468 -239.940015) (xy 31.3755 -240.025435) (xy 31.351719 -240.109017)
			(xy 31.320327 -240.190049) (xy 31.281593 -240.267838) (xy 31.235846 -240.341722) (xy 31.183477 -240.411069)
			(xy 31.124933 -240.475289) (xy 31.060713 -240.533833) (xy 30.991366 -240.586202) (xy 30.917482 -240.631949)
			(xy 30.839693 -240.670683) (xy 30.758661 -240.702075) (xy 30.675079 -240.725856) (xy 30.589659 -240.741824)
			(xy 30.50313 -240.749842) (xy 30.41623 -240.749842) (xy 30.329701 -240.741824) (xy 30.244281 -240.725856)
			(xy 30.160699 -240.702075) (xy 30.079667 -240.670683) (xy 30.001878 -240.631949) (xy 29.927994 -240.586202)
			(xy 29.858647 -240.533833) (xy 29.794427 -240.475289) (xy 29.735883 -240.411069) (xy 29.683514 -240.341722)
			(xy 29.637767 -240.267838) (xy 29.599033 -240.190049) (xy 29.567641 -240.109017) (xy 29.54386 -240.025435)
			(xy 29.527892 -239.940015) (xy 29.519874 -239.853486) (xy 20.941014 -239.853486) (xy 18.401014 -242.393486)
			(xy 29.519874 -242.393486) (xy 29.519874 -242.306586) (xy 29.527892 -242.220057) (xy 29.54386 -242.134637)
			(xy 29.567641 -242.051055) (xy 29.599033 -241.970023) (xy 29.637767 -241.892234) (xy 29.683514 -241.81835)
			(xy 29.735883 -241.749003) (xy 29.794427 -241.684783) (xy 29.858647 -241.626239) (xy 29.927994 -241.57387)
			(xy 30.001878 -241.528123) (xy 30.079667 -241.489389) (xy 30.160699 -241.457997) (xy 30.244281 -241.434216)
			(xy 30.329701 -241.418248) (xy 30.41623 -241.41023) (xy 30.45968 -241.409728) (xy 30.50313 -241.41023)
			(xy 30.589659 -241.418248) (xy 30.675079 -241.434216) (xy 30.758661 -241.457997) (xy 30.839693 -241.489389)
			(xy 30.917482 -241.528123) (xy 30.991366 -241.57387) (xy 31.060713 -241.626239) (xy 31.124933 -241.684783)
			(xy 31.183477 -241.749003) (xy 31.235846 -241.81835) (xy 31.281593 -241.892234) (xy 31.320327 -241.970023)
			(xy 31.351719 -242.051055) (xy 31.3755 -242.134637) (xy 31.391468 -242.220057) (xy 31.399486 -242.306586)
			(xy 31.399486 -242.393486) (xy 34.599874 -242.393486) (xy 34.599874 -242.306586) (xy 34.607892 -242.220057)
			(xy 34.62386 -242.134637) (xy 34.647641 -242.051055) (xy 34.679033 -241.970023) (xy 34.717767 -241.892234)
			(xy 34.763514 -241.81835) (xy 34.815883 -241.749003) (xy 34.874427 -241.684783) (xy 34.938647 -241.626239)
			(xy 35.007994 -241.57387) (xy 35.081878 -241.528123) (xy 35.159667 -241.489389) (xy 35.240699 -241.457997)
			(xy 35.324281 -241.434216) (xy 35.409701 -241.418248) (xy 35.49623 -241.41023) (xy 35.53968 -241.409728)
			(xy 35.58313 -241.41023) (xy 35.669659 -241.418248) (xy 35.755079 -241.434216) (xy 35.838661 -241.457997)
			(xy 35.919693 -241.489389) (xy 35.997482 -241.528123) (xy 36.071366 -241.57387) (xy 36.140713 -241.626239)
			(xy 36.204933 -241.684783) (xy 36.263477 -241.749003) (xy 36.315846 -241.81835) (xy 36.361593 -241.892234)
			(xy 36.400327 -241.970023) (xy 36.431719 -242.051055) (xy 36.4555 -242.134637) (xy 36.471468 -242.220057)
			(xy 36.479486 -242.306586) (xy 36.479486 -242.393486) (xy 36.471468 -242.480015) (xy 36.4555 -242.565435)
			(xy 36.431719 -242.649017) (xy 36.400327 -242.730049) (xy 36.365046 -242.800904) (xy 44.210731 -242.800904)
			(xy 44.216831 -242.745467) (xy 44.230937 -242.69151) (xy 44.252749 -242.640181) (xy 44.281803 -242.592575)
			(xy 44.317478 -242.549707) (xy 44.359015 -242.51249) (xy 44.405528 -242.481717) (xy 44.456025 -242.458045)
			(xy 44.509432 -242.441977) (xy 44.564608 -242.433857) (xy 44.592494 -242.433348) (xy 44.62038 -242.433857)
			(xy 44.675556 -242.441977) (xy 44.728963 -242.458045) (xy 44.77946 -242.481717) (xy 44.825973 -242.51249)
			(xy 44.86751 -242.549707) (xy 44.903185 -242.592575) (xy 44.932239 -242.640181) (xy 44.954051 -242.69151)
			(xy 44.968157 -242.745467) (xy 44.974257 -242.800904) (xy 44.97222 -242.856638) (xy 44.96209 -242.911481)
			(xy 44.944083 -242.964265) (xy 44.918582 -243.013865) (xy 44.886131 -243.059223) (xy 44.847422 -243.099372)
			(xy 44.803279 -243.133458) (xy 44.754644 -243.160754) (xy 44.702553 -243.180677) (xy 44.648116 -243.192803)
			(xy 44.592494 -243.196874) (xy 44.536872 -243.192803) (xy 44.482435 -243.180677) (xy 44.430344 -243.160754)
			(xy 44.381709 -243.133458) (xy 44.337566 -243.099372) (xy 44.298857 -243.059223) (xy 44.266406 -243.013865)
			(xy 44.240905 -242.964265) (xy 44.222898 -242.911481) (xy 44.212768 -242.856638) (xy 44.210731 -242.800904)
			(xy 36.365046 -242.800904) (xy 36.361593 -242.807838) (xy 36.315846 -242.881722) (xy 36.263477 -242.951069)
			(xy 36.204933 -243.015289) (xy 36.140713 -243.073833) (xy 36.071366 -243.126202) (xy 35.997482 -243.171949)
			(xy 35.919693 -243.210683) (xy 35.838661 -243.242075) (xy 35.755079 -243.265856) (xy 35.669659 -243.281824)
			(xy 35.58313 -243.289842) (xy 35.49623 -243.289842) (xy 35.409701 -243.281824) (xy 35.324281 -243.265856)
			(xy 35.240699 -243.242075) (xy 35.159667 -243.210683) (xy 35.081878 -243.171949) (xy 35.007994 -243.126202)
			(xy 34.938647 -243.073833) (xy 34.874427 -243.015289) (xy 34.815883 -242.951069) (xy 34.763514 -242.881722)
			(xy 34.717767 -242.807838) (xy 34.679033 -242.730049) (xy 34.647641 -242.649017) (xy 34.62386 -242.565435)
			(xy 34.607892 -242.480015) (xy 34.599874 -242.393486) (xy 31.399486 -242.393486) (xy 31.391468 -242.480015)
			(xy 31.3755 -242.565435) (xy 31.351719 -242.649017) (xy 31.320327 -242.730049) (xy 31.281593 -242.807838)
			(xy 31.235846 -242.881722) (xy 31.183477 -242.951069) (xy 31.124933 -243.015289) (xy 31.060713 -243.073833)
			(xy 30.991366 -243.126202) (xy 30.917482 -243.171949) (xy 30.839693 -243.210683) (xy 30.758661 -243.242075)
			(xy 30.675079 -243.265856) (xy 30.589659 -243.281824) (xy 30.50313 -243.289842) (xy 30.41623 -243.289842)
			(xy 30.329701 -243.281824) (xy 30.244281 -243.265856) (xy 30.160699 -243.242075) (xy 30.079667 -243.210683)
			(xy 30.001878 -243.171949) (xy 29.927994 -243.126202) (xy 29.858647 -243.073833) (xy 29.794427 -243.015289)
			(xy 29.735883 -242.951069) (xy 29.683514 -242.881722) (xy 29.637767 -242.807838) (xy 29.599033 -242.730049)
			(xy 29.567641 -242.649017) (xy 29.54386 -242.565435) (xy 29.527892 -242.480015) (xy 29.519874 -242.393486)
			(xy 18.401014 -242.393486) (xy 16.954653 -243.839847) (xy 66.107556 -243.839847) (xy 66.107556 -243.768525)
			(xy 66.115542 -243.697651) (xy 66.131412 -243.628116) (xy 66.154969 -243.560796) (xy 66.185914 -243.496537)
			(xy 66.22386 -243.436146) (xy 66.268329 -243.380384) (xy 66.318762 -243.329951) (xy 66.374524 -243.285482)
			(xy 66.434915 -243.247536) (xy 66.499174 -243.216591) (xy 66.566494 -243.193034) (xy 66.636029 -243.177164)
			(xy 66.706903 -243.169178) (xy 66.742564 -243.168678) (xy 66.778225 -243.169178) (xy 66.849099 -243.177164)
			(xy 66.918634 -243.193034) (xy 66.985954 -243.216591) (xy 67.050213 -243.247536) (xy 67.110604 -243.285482)
			(xy 67.166366 -243.329951) (xy 67.216799 -243.380384) (xy 67.261268 -243.436146) (xy 67.299214 -243.496537)
			(xy 67.330159 -243.560796) (xy 67.353716 -243.628116) (xy 67.369586 -243.697651) (xy 67.377572 -243.768525)
			(xy 67.377572 -243.839847) (xy 69.099168 -243.839847) (xy 69.099168 -243.768525) (xy 69.107154 -243.697651)
			(xy 69.123024 -243.628116) (xy 69.146581 -243.560796) (xy 69.177526 -243.496537) (xy 69.215472 -243.436146)
			(xy 69.259941 -243.380384) (xy 69.310374 -243.329951) (xy 69.366136 -243.285482) (xy 69.426527 -243.247536)
			(xy 69.490786 -243.216591) (xy 69.558106 -243.193034) (xy 69.627641 -243.177164) (xy 69.698515 -243.169178)
			(xy 69.734176 -243.168678) (xy 69.769837 -243.169178) (xy 69.840711 -243.177164) (xy 69.910246 -243.193034)
			(xy 69.977566 -243.216591) (xy 70.041825 -243.247536) (xy 70.102216 -243.285482) (xy 70.157978 -243.329951)
			(xy 70.208411 -243.380384) (xy 70.25288 -243.436146) (xy 70.290826 -243.496537) (xy 70.321771 -243.560796)
			(xy 70.345328 -243.628116) (xy 70.361198 -243.697651) (xy 70.369184 -243.768525) (xy 70.369184 -243.839847)
			(xy 70.361198 -243.910721) (xy 70.345328 -243.980256) (xy 70.321771 -244.047576) (xy 70.290826 -244.111835)
			(xy 70.25288 -244.172226) (xy 70.208411 -244.227988) (xy 70.157978 -244.278421) (xy 70.102216 -244.32289)
			(xy 70.041825 -244.360836) (xy 69.977566 -244.391781) (xy 69.910246 -244.415338) (xy 69.840711 -244.431208)
			(xy 69.769837 -244.439194) (xy 69.698515 -244.439194) (xy 69.627641 -244.431208) (xy 69.558106 -244.415338)
			(xy 69.490786 -244.391781) (xy 69.426527 -244.360836) (xy 69.366136 -244.32289) (xy 69.310374 -244.278421)
			(xy 69.259941 -244.227988) (xy 69.215472 -244.172226) (xy 69.177526 -244.111835) (xy 69.146581 -244.047576)
			(xy 69.123024 -243.980256) (xy 69.107154 -243.910721) (xy 69.099168 -243.839847) (xy 67.377572 -243.839847)
			(xy 67.369586 -243.910721) (xy 67.353716 -243.980256) (xy 67.330159 -244.047576) (xy 67.299214 -244.111835)
			(xy 67.261268 -244.172226) (xy 67.216799 -244.227988) (xy 67.166366 -244.278421) (xy 67.110604 -244.32289)
			(xy 67.050213 -244.360836) (xy 66.985954 -244.391781) (xy 66.918634 -244.415338) (xy 66.849099 -244.431208)
			(xy 66.778225 -244.439194) (xy 66.706903 -244.439194) (xy 66.636029 -244.431208) (xy 66.566494 -244.415338)
			(xy 66.499174 -244.391781) (xy 66.434915 -244.360836) (xy 66.374524 -244.32289) (xy 66.318762 -244.278421)
			(xy 66.268329 -244.227988) (xy 66.22386 -244.172226) (xy 66.185914 -244.111835) (xy 66.154969 -244.047576)
			(xy 66.131412 -243.980256) (xy 66.115542 -243.910721) (xy 66.107556 -243.839847) (xy 16.954653 -243.839847)
			(xy 15.80896 -244.98554) (xy 9.070086 -244.98554) (xy 9.054965 -244.985995) (xy 9.025581 -244.993155)
			(xy 8.998705 -245.007023) (xy 8.975842 -245.026821) (xy 8.966708 -245.03888) (xy 8.945835 -245.06742)
			(xy 8.898728 -245.120153) (xy 8.846058 -245.167331) (xy 8.788477 -245.20837) (xy 8.726695 -245.242764)
			(xy 8.661478 -245.270087) (xy 8.59363 -245.290001) (xy 8.523991 -245.30226) (xy 8.453422 -245.306713)
			(xy 8.382794 -245.303304) (xy 8.312982 -245.292076) (xy 8.244847 -245.273167) (xy 8.179233 -245.246812)
			(xy 8.11695 -245.213335) (xy 8.058768 -245.173152) (xy 8.005406 -245.126758) (xy 7.957524 -245.074727)
			(xy 7.93623 -245.0465) (xy 7.922977 -245.029059) (xy 7.891411 -244.998691) (xy 7.855103 -244.974189)
			(xy 7.81513 -244.956279) (xy 7.772677 -244.945493) (xy 7.729002 -244.94215) (xy 7.685402 -244.94635)
			(xy 7.643169 -244.957968) (xy 7.603555 -244.976659) (xy 7.567735 -245.00187) (xy 7.551928 -245.017036)
			(xy 7.111492 -245.457472) (xy 7.101148 -245.468414) (xy 7.085468 -245.494112) (xy 7.076231 -245.522764)
			(xy 7.073948 -245.552781) (xy 7.075932 -245.567708) (xy 7.081207 -245.602899) (xy 7.08481 -245.673969)
			(xy 7.08045 -245.744997) (xy 7.068183 -245.815093) (xy 7.048163 -245.88338) (xy 7.020639 -245.949002)
			(xy 6.985956 -246.01114) (xy 6.94455 -246.069014) (xy 6.896937 -246.1219) (xy 6.843714 -246.169136)
			(xy 6.785547 -246.210131) (xy 6.723165 -246.244371) (xy 6.657348 -246.271429) (xy 6.588921 -246.290964)
			(xy 6.518739 -246.302733) (xy 6.447683 -246.306588) (xy 6.37664 -246.302481) (xy 6.306501 -246.290463)
			(xy 6.238143 -246.270686) (xy 6.172423 -246.243395) (xy 6.110162 -246.208934) (xy 6.052141 -246.167733)
			(xy 5.999086 -246.120309) (xy 5.951661 -246.067254) (xy 5.91046 -246.009234) (xy 5.875998 -245.946974)
			(xy 5.848707 -245.881253) (xy 5.828928 -245.812896) (xy 5.81691 -245.742757) (xy 5.812802 -245.671714)
			(xy 5.816656 -245.600657) (xy 5.828425 -245.530476) (xy 5.847959 -245.462048) (xy 5.875016 -245.396231)
			(xy 5.909255 -245.333849) (xy 5.950249 -245.275682) (xy 5.997485 -245.222458) (xy 6.050371 -245.174845)
			(xy 6.108244 -245.133437) (xy 6.170381 -245.098754) (xy 6.236004 -245.07123) (xy 6.304291 -245.051208)
			(xy 6.374387 -245.03894) (xy 6.445414 -245.03458) (xy 6.516484 -245.038182) (xy 6.551676 -245.043452)
			(xy 6.566605 -245.045471) (xy 6.59664 -245.043242) (xy 6.625304 -245.033998) (xy 6.650983 -245.01826)
			(xy 6.661912 -245.007892) (xy 8.102346 -243.567458) (xy 8.117497 -243.551648) (xy 8.142671 -243.515823)
			(xy 8.161332 -243.476212) (xy 8.172926 -243.433989) (xy 8.177112 -243.390404) (xy 8.173764 -243.346746)
			(xy 8.162983 -243.304308) (xy 8.145086 -243.264347) (xy 8.120605 -243.228044) (xy 8.090263 -243.196476)
			(xy 8.072882 -243.183156) (xy 8.047037 -243.163708) (xy 7.999033 -243.120353) (xy 7.95568 -243.072347)
			(xy 7.93623 -243.046504) (xy 7.922977 -243.029064) (xy 7.891411 -242.998695) (xy 7.855104 -242.974192)
			(xy 7.81513 -242.956282) (xy 7.772677 -242.945496) (xy 7.729002 -242.942153) (xy 7.685402 -242.946353)
			(xy 7.643168 -242.957971) (xy 7.603554 -242.976663) (xy 7.567735 -243.001874) (xy 7.551928 -243.01704)
			(xy 7.111492 -243.457476) (xy 7.101146 -243.468416) (xy 7.085466 -243.494115) (xy 7.076229 -243.522767)
			(xy 7.073948 -243.552785) (xy 7.075932 -243.567712) (xy 7.081204 -243.602903) (xy 7.084806 -243.673973)
			(xy 7.080446 -243.745) (xy 7.068179 -243.815095) (xy 7.048158 -243.883382) (xy 7.020634 -243.949004)
			(xy 6.985951 -244.011141) (xy 6.944544 -244.069014) (xy 6.896932 -244.1219) (xy 6.843709 -244.169135)
			(xy 6.785542 -244.210129) (xy 6.72316 -244.244369) (xy 6.657344 -244.271426) (xy 6.588917 -244.290961)
			(xy 6.518736 -244.302729) (xy 6.44768 -244.306584) (xy 6.376638 -244.302477) (xy 6.306499 -244.290459)
			(xy 6.238142 -244.270681) (xy 6.172422 -244.243391) (xy 6.110162 -244.208929) (xy 6.052142 -244.167729)
			(xy 5.999087 -244.120304) (xy 5.951663 -244.06725) (xy 5.910462 -244.00923) (xy 5.876 -243.94697)
			(xy 5.84871 -243.88125) (xy 5.828932 -243.812893) (xy 5.816914 -243.742755) (xy 5.812806 -243.671712)
			(xy 5.816661 -243.600656) (xy 5.828429 -243.530475) (xy 5.847963 -243.462048) (xy 5.87502 -243.396232)
			(xy 5.909259 -243.33385) (xy 5.950253 -243.275683) (xy 5.997489 -243.22246) (xy 6.050374 -243.174847)
			(xy 6.108247 -243.13344) (xy 6.170384 -243.098757) (xy 6.236006 -243.071233) (xy 6.304292 -243.051212)
			(xy 6.374388 -243.038944) (xy 6.445415 -243.034584) (xy 6.516485 -243.038186) (xy 6.551676 -243.043456)
			(xy 6.566606 -243.045473) (xy 6.59664 -243.043245) (xy 6.625304 -243.034002) (xy 6.650982 -243.018264)
			(xy 6.661912 -243.007896) (xy 7.107428 -242.56238) (xy 7.107428 -240.333276) (xy 7.238238 -240.202466)
			(xy 7.249589 -240.190311) (xy 7.266179 -240.161503) (xy 7.274761 -240.129386) (xy 7.274752 -240.096142)
			(xy 7.266152 -240.06403) (xy 7.249545 -240.035231) (xy 7.22606 -240.011702) (xy 7.197293 -239.995041)
			(xy 7.165197 -239.98638) (xy 7.148576 -239.985804) (xy 7.07009 -239.985804) (xy 7.054967 -239.986236)
			(xy 7.02558 -239.993399) (xy 6.998703 -240.007273) (xy 6.975843 -240.027081) (xy 6.966712 -240.039144)
			(xy 6.946052 -240.067338) (xy 6.89951 -240.119489) (xy 6.847527 -240.16622) (xy 6.790731 -240.206966)
			(xy 6.729807 -240.241234) (xy 6.665492 -240.268611) (xy 6.598561 -240.288766) (xy 6.529823 -240.301457)
			(xy 6.460107 -240.30653) (xy 6.390256 -240.303923) (xy 6.321113 -240.293668) (xy 6.253512 -240.275889)
			(xy 6.188269 -240.250801) (xy 6.126173 -240.218707) (xy 6.067973 -240.179993) (xy 6.014372 -240.135127)
			(xy 5.966017 -240.084652) (xy 5.923492 -240.029176) (xy 5.904992 -239.99952) (xy 5.892664 -239.980051)
			(xy 5.862113 -239.945557) (xy 5.825845 -239.917135) (xy 5.785047 -239.895717) (xy 5.741057 -239.882004)
			(xy 5.695315 -239.876445) (xy 5.649321 -239.879222) (xy 5.604581 -239.890245) (xy 5.56256 -239.909152)
			(xy 5.524636 -239.935324) (xy 5.50799 -239.95126) (xy 5.448808 -240.010442) (xy 5.448808 -240.620296)
			(xy 4.611624 -241.45748) (xy 4.601265 -241.468409) (xy 4.585592 -241.494113) (xy 4.57636 -241.522769)
			(xy 4.57408 -241.552788) (xy 4.576064 -241.567716) (xy 4.581339 -241.602943) (xy 4.584938 -241.674086)
			(xy 4.580559 -241.745184) (xy 4.568257 -241.815347) (xy 4.548186 -241.883694) (xy 4.520599 -241.949368)
			(xy 4.485841 -242.011546) (xy 4.444348 -242.069447) (xy 4.396641 -242.122345) (xy 4.343318 -242.169577)
			(xy 4.285048 -242.210549) (xy 4.222562 -242.244749) (xy 4.156644 -242.271748) (xy 4.08812 -242.291206)
			(xy 4.017849 -242.302879) (xy 3.946715 -242.306622) (xy 3.875607 -242.302386) (xy 3.80542 -242.290226)
			(xy 3.737032 -242.270294) (xy 3.671302 -242.24284) (xy 3.609054 -242.208208) (xy 3.55107 -242.166832)
			(xy 3.498075 -242.119232) (xy 3.450736 -242.066005) (xy 3.409645 -242.007818) (xy 3.375319 -241.945401)
			(xy 3.348187 -241.879537) (xy 3.328591 -241.811052) (xy 3.316776 -241.740806) (xy 3.312889 -241.669679)
			(xy 3.316981 -241.598563) (xy 3.328999 -241.528351) (xy 3.348793 -241.459923) (xy 3.376114 -241.394138)
			(xy 3.392932 -241.362738) (xy 3.403215 -241.343287) (xy 3.417574 -241.301701) (xy 3.42456 -241.258263)
			(xy 3.423965 -241.214271) (xy 3.415806 -241.171039) (xy 3.400327 -241.129856) (xy 3.37799 -241.091952)
			(xy 3.349463 -241.058459) (xy 3.315596 -241.030376) (xy 3.2774 -241.008542) (xy 3.236016 -240.993609)
			(xy 3.19268 -240.986022) (xy 3.170682 -240.985548) (xy 2.570226 -240.985548) (xy 2.555106 -240.986028)
			(xy 2.525724 -240.993179) (xy 2.498847 -241.00704) (xy 2.475983 -241.026832) (xy 2.466848 -241.038888)
			(xy 2.445835 -241.067601) (xy 2.398393 -241.120631) (xy 2.345323 -241.168029) (xy 2.28729 -241.209201)
			(xy 2.225021 -241.243633) (xy 2.159295 -241.270892) (xy 2.090935 -241.290638) (xy 2.020797 -241.302623)
			(xy 1.949759 -241.306697) (xy 1.878711 -241.30281) (xy 1.808541 -241.29101) (xy 1.74013 -241.271445)
			(xy 1.674332 -241.244359) (xy 1.611972 -241.210092) (xy 1.553831 -241.169073) (xy 1.500636 -241.121816)
			(xy 1.453054 -241.068911) (xy 1.41168 -241.011022) (xy 1.377032 -240.948873) (xy 1.349544 -240.883242)
			(xy 1.32956 -240.814951) (xy 1.317331 -240.744855) (xy 1.313009 -240.673832) (xy 1.316649 -240.602771)
			(xy 1.328205 -240.532561) (xy 1.347532 -240.464082) (xy 1.374389 -240.39819) (xy 1.408438 -240.335711)
			(xy 1.449255 -240.277427) (xy 1.496327 -240.224069) (xy 1.549066 -240.176302) (xy 1.60681 -240.134727)
			(xy 1.668839 -240.099863) (xy 1.734373 -240.072147) (xy 1.802594 -240.051926) (xy 1.872647 -240.039453)
			(xy 1.943654 -240.034884) (xy 2.014728 -240.038276) (xy 2.084978 -240.049588) (xy 2.153524 -240.068676)
			(xy 2.219509 -240.095303) (xy 2.282106 -240.129135) (xy 2.340531 -240.169749) (xy 2.394054 -240.216635)
			(xy 2.442003 -240.269207) (xy 2.463292 -240.297716) (xy 2.47247 -240.309576) (xy 2.495298 -240.329012)
			(xy 2.52202 -240.342606) (xy 2.551172 -240.349611) (xy 2.566162 -240.35004) (xy 4.130802 -240.35004)
			(xy 4.370832 -240.11001) (xy 4.370832 -239.67313) (xy 5.887212 -238.15675) (xy 5.898801 -238.144396)
			(xy 5.91556 -238.114973) (xy 5.923988 -238.082177) (xy 5.923492 -238.048319) (xy 5.914107 -238.015784)
			(xy 5.905754 -238.001048) (xy 5.905754 -238.000794) (xy 5.892568 -237.978596) (xy 5.869426 -237.932437)
			(xy 5.859526 -237.908592) (xy 5.849874 -237.884462) (xy 5.831586 -237.866174) (xy 5.819468 -237.854735)
			(xy 5.790629 -237.838059) (xy 5.758454 -237.829427) (xy 5.72514 -237.829427) (xy 5.692965 -237.838059)
			(xy 5.664126 -237.854735) (xy 5.652008 -237.866174) (xy 4.727194 -238.790988) (xy 3.85826 -238.790988)
			(xy 3.663442 -238.985552) (xy 2.570226 -238.985552) (xy 2.555106 -238.98603) (xy 2.525724 -238.993182)
			(xy 2.498847 -239.007043) (xy 2.475983 -239.026835) (xy 2.466848 -239.038892) (xy 2.445831 -239.067602)
			(xy 2.398389 -239.120632) (xy 2.345319 -239.168029) (xy 2.287286 -239.209201) (xy 2.225017 -239.243632)
			(xy 2.159291 -239.270891) (xy 2.090931 -239.290636) (xy 2.020793 -239.302621) (xy 1.949756 -239.306695)
			(xy 1.878708 -239.302808) (xy 1.808539 -239.291007) (xy 1.740127 -239.271442) (xy 1.67433 -239.244356)
			(xy 1.611971 -239.210089) (xy 1.55383 -239.169069) (xy 1.500635 -239.121812) (xy 1.453054 -239.068907)
			(xy 1.41168 -239.011018) (xy 1.377033 -238.948869) (xy 1.349545 -238.883238) (xy 1.329562 -238.814948)
			(xy 1.317333 -238.744852) (xy 1.313012 -238.673829) (xy 1.316652 -238.602768) (xy 1.328208 -238.532558)
			(xy 1.347535 -238.464079) (xy 1.374392 -238.398188) (xy 1.408442 -238.33571) (xy 1.449259 -238.277426)
			(xy 1.496331 -238.224068) (xy 1.54907 -238.176302) (xy 1.606814 -238.134727) (xy 1.668842 -238.099864)
			(xy 1.734377 -238.072148) (xy 1.802598 -238.051928) (xy 1.87265 -238.039455) (xy 1.943658 -238.034886)
			(xy 2.014731 -238.038279) (xy 2.08498 -238.049591) (xy 2.153526 -238.06868) (xy 2.219511 -238.095307)
			(xy 2.282107 -238.129139) (xy 2.340532 -238.169753) (xy 2.394054 -238.216639) (xy 2.442003 -238.269211)
			(xy 2.463292 -238.29772) (xy 2.472469 -238.309581) (xy 2.495297 -238.329017) (xy 2.52202 -238.34261)
			(xy 2.551172 -238.349616) (xy 2.566162 -238.350044) (xy 3.34772 -238.350044) (xy 3.364351 -238.349448)
			(xy 3.396466 -238.340773) (xy 3.42525 -238.324098) (xy 3.437382 -238.312706) (xy 3.475736 -238.274606)
			(xy 3.486839 -238.262824) (xy 3.503228 -238.234917) (xy 3.512059 -238.203782) (xy 3.512761 -238.171426)
			(xy 3.50529 -238.139936) (xy 3.490127 -238.111344) (xy 3.479546 -238.099092) (xy 3.455731 -238.072245)
			(xy 3.413644 -238.014111) (xy 3.378371 -237.951608) (xy 3.350363 -237.88553) (xy 3.329973 -237.816718)
			(xy 3.317463 -237.746048) (xy 3.312991 -237.674418) (xy 3.316614 -237.602741) (xy 3.328286 -237.531927)
			(xy 3.347859 -237.462879) (xy 3.375084 -237.396474) (xy 3.391916 -237.364778) (xy 3.402082 -237.34532)
			(xy 3.416248 -237.30377) (xy 3.423065 -237.260404) (xy 3.422331 -237.216511) (xy 3.414067 -237.173397)
			(xy 3.39852 -237.132344) (xy 3.376151 -237.094572) (xy 3.347625 -237.061205) (xy 3.313792 -237.033234)
			(xy 3.275656 -237.011491) (xy 3.234352 -236.996623) (xy 3.191107 -236.989071) (xy 3.169158 -236.988604)
			(xy 2.568448 -236.988604) (xy 2.553355 -236.989002) (xy 2.523999 -236.996025) (xy 2.497121 -237.009759)
			(xy 2.474229 -237.029433) (xy 2.46507 -237.041436) (xy 2.443911 -237.070044) (xy 2.396194 -237.122834)
			(xy 2.34288 -237.169963) (xy 2.284634 -237.210842) (xy 2.222187 -237.244959) (xy 2.15632 -237.271886)
			(xy 2.087857 -237.291288) (xy 2.017656 -237.302921) (xy 1.946594 -237.30664) (xy 1.875561 -237.302397)
			(xy 1.805447 -237.290246) (xy 1.73713 -237.27034) (xy 1.671463 -237.242927) (xy 1.609269 -237.20835)
			(xy 1.551327 -237.167043) (xy 1.498361 -237.119522) (xy 1.451036 -237.066382) (xy 1.409942 -237.008288)
			(xy 1.375595 -236.945967) (xy 1.348424 -236.8802) (xy 1.328769 -236.811809) (xy 1.316877 -236.741651)
			(xy 1.312896 -236.670603) (xy 1.316876 -236.599556) (xy 1.328768 -236.529397) (xy 1.348422 -236.461006)
			(xy 1.375592 -236.395239) (xy 1.409939 -236.332918) (xy 1.451032 -236.274823) (xy 1.498357 -236.221683)
			(xy 1.551322 -236.174161) (xy 1.609264 -236.132853) (xy 1.671457 -236.098276) (xy 1.737123 -236.070862)
			(xy 1.805441 -236.050955) (xy 1.875555 -236.038804) (xy 1.946587 -236.03456) (xy 2.017649 -236.038278)
			(xy 2.087851 -236.04991) (xy 2.156314 -236.069311) (xy 2.222181 -236.096239) (xy 2.284629 -236.130355)
			(xy 2.342875 -236.171233) (xy 2.39619 -236.218362) (xy 2.443907 -236.271151) (xy 2.46507 -236.299756)
			(xy 2.474231 -236.311756) (xy 2.497128 -236.33142) (xy 2.524005 -236.345154) (xy 2.553356 -236.352188)
			(xy 2.568448 -236.352588) (xy 3.169158 -236.352588) (xy 3.191111 -236.352133) (xy 3.234365 -236.344598)
			(xy 3.27568 -236.329742) (xy 3.313826 -236.308005) (xy 3.347669 -236.280034) (xy 3.376201 -236.246663)
			(xy 3.398572 -236.208885) (xy 3.414116 -236.167824) (xy 3.422372 -236.124702) (xy 3.423093 -236.080803)
			(xy 3.416257 -236.037433) (xy 3.402069 -235.995883) (xy 3.391916 -235.976414) (xy 3.374966 -235.944501)
			(xy 3.347593 -235.877623) (xy 3.327984 -235.808072) (xy 3.316391 -235.736745) (xy 3.312964 -235.664563)
			(xy 3.317747 -235.592459) (xy 3.330678 -235.521363) (xy 3.351591 -235.452192) (xy 3.380216 -235.38584)
			(xy 3.416182 -235.323164) (xy 3.459026 -235.264972) (xy 3.508195 -235.212015) (xy 3.563053 -235.164978)
			(xy 3.622893 -235.124468) (xy 3.686942 -235.091007) (xy 3.754373 -235.065028) (xy 3.824317 -235.046865)
			(xy 3.895869 -235.036754) (xy 3.968106 -235.034825) (xy 4.040095 -235.041102) (xy 4.110908 -235.055505)
			(xy 4.17963 -235.077848) (xy 4.245374 -235.107843) (xy 4.307291 -235.145101) (xy 4.364582 -235.189143)
			(xy 4.390898 -235.213906) (xy 4.406991 -235.228852) (xy 4.443313 -235.253535) (xy 4.483339 -235.271606)
			(xy 4.525875 -235.282527) (xy 4.569655 -235.285973) (xy 4.613376 -235.281841) (xy 4.655736 -235.270254)
			(xy 4.695473 -235.251558) (xy 4.731404 -235.226309) (xy 4.74726 -235.211112) (xy 5.73151 -234.226608)
			(xy 5.818632 -234.226608) (xy 5.833935 -234.226114) (xy 5.863652 -234.218786) (xy 5.890765 -234.204584)
			(xy 5.913711 -234.184328) (xy 5.931166 -234.159185) (xy 5.942123 -234.130607) (xy 5.94595 -234.10024)
			(xy 5.942427 -234.069836) (xy 5.931758 -234.041148) (xy 5.923534 -234.028234) (xy 5.903897 -233.998521)
			(xy 5.870647 -233.935534) (xy 5.844648 -233.869225) (xy 5.826227 -233.800424) (xy 5.815614 -233.729994)
			(xy 5.812944 -233.65882) (xy 5.818249 -233.587793) (xy 5.831463 -233.517805) (xy 5.85242 -233.449734)
			(xy 5.880857 -233.384433) (xy 5.916417 -233.322721) (xy 5.958655 -233.265372) (xy 6.007041 -233.213106)
			(xy 6.060968 -233.166578) (xy 6.119759 -233.126372) (xy 6.182677 -233.092993) (xy 6.248933 -233.066858)
			(xy 6.317696 -233.048295) (xy 6.388104 -233.037538) (xy 6.459273 -233.034721) (xy 6.53031 -233.03988)
			(xy 6.600325 -233.05295) (xy 6.668439 -233.073767) (xy 6.733799 -233.102069) (xy 6.795584 -233.137503)
			(xy 6.853019 -233.179623) (xy 6.905384 -233.227901) (xy 6.952023 -233.281732) (xy 6.99235 -233.340441)
			(xy 7.025859 -233.40329) (xy 7.05213 -233.469492) (xy 7.061962 -233.503724) (xy 7.068259 -233.524947)
			(xy 7.087137 -233.564984) (xy 7.112666 -233.601145) (xy 7.144074 -233.632336) (xy 7.180411 -233.657615)
			(xy 7.220577 -233.676215) (xy 7.263359 -233.687576) (xy 7.307462 -233.691354) (xy 7.351553 -233.687434)
			(xy 7.394297 -233.675934) (xy 7.434403 -233.657203) (xy 7.470658 -233.631808) (xy 7.48665 -233.6165)
			(xy 7.910576 -233.192574) (xy 7.920648 -233.181847) (xy 7.936131 -233.156836) (xy 7.945459 -233.12894)
			(xy 7.948133 -233.099646) (xy 7.944011 -233.070522) (xy 7.933313 -233.043121) (xy 7.925308 -233.030776)
			(xy 7.905331 -233.000842) (xy 7.871498 -232.937322) (xy 7.845058 -232.870385) (xy 7.826351 -232.800891)
			(xy 7.815616 -232.729727) (xy 7.81299 -232.657806) (xy 7.818507 -232.586049) (xy 7.832096 -232.515375)
			(xy 7.853584 -232.446689) (xy 7.882695 -232.380871) (xy 7.919056 -232.318763) (xy 7.962201 -232.261161)
			(xy 8.011579 -232.208803) (xy 8.066556 -232.16236) (xy 8.126429 -232.122425) (xy 8.190431 -232.089512)
			(xy 8.257741 -232.06404) (xy 8.327499 -232.046337) (xy 8.398809 -232.036629) (xy 8.470761 -232.03504)
			(xy 8.542431 -232.041592) (xy 8.612901 -232.056199) (xy 8.681271 -232.078675) (xy 8.746662 -232.108731)
			(xy 8.808239 -232.145984) (xy 8.865213 -232.189956) (xy 8.916853 -232.240084) (xy 8.962499 -232.295725)
			(xy 9.001566 -232.356167) (xy 9.033553 -232.420637) (xy 9.058052 -232.488307) (xy 9.074747 -232.558313)
			(xy 9.083426 -232.629756) (xy 9.083977 -232.701723) (xy 9.076393 -232.773291) (xy 9.06907 -232.808526)
			(xy 9.064729 -232.830855) (xy 9.062969 -232.876301) (xy 9.069317 -232.921336) (xy 9.083572 -232.964524)
			(xy 9.105279 -233.004489) (xy 9.133746 -233.039958) (xy 9.168066 -233.0698) (xy 9.207145 -233.093064)
			(xy 9.249739 -233.109009) (xy 9.294488 -233.117126) (xy 9.317228 -233.117644) (xy 19.001232 -233.117644)
			(xy 19.017846 -233.117064) (xy 19.049946 -233.10848) (xy 19.078743 -233.091903) (xy 19.090894 -233.08056)
			(xy 19.925792 -232.245408) (xy 19.925792 -220.335602) (xy 23.875492 -216.386156) (xy 23.886841 -216.374006)
			(xy 23.903444 -216.345215) (xy 23.912036 -216.313111) (xy 23.912576 -216.296494) (xy 23.912576 -215.926924)
			(xy 23.912003 -215.903864) (xy 23.903756 -215.85849) (xy 23.887457 -215.815349) (xy 23.863641 -215.775857)
			(xy 23.833089 -215.741312) (xy 23.796805 -215.712846) (xy 23.75598 -215.691396) (xy 23.711954 -215.677665)
			(xy 23.666173 -215.672104) (xy 23.62014 -215.674896) (xy 23.575367 -215.685949) (xy 23.533323 -215.7049)
			(xy 23.495389 -215.731126) (xy 23.478744 -215.747092) (xy 18.282666 -220.943424) (xy 18.267655 -220.959158)
			(xy 18.242607 -220.9947) (xy 18.223975 -221.033986) (xy 18.212302 -221.075871) (xy 18.20793 -221.119132)
			(xy 18.210985 -221.162506) (xy 18.22138 -221.204726) (xy 18.238809 -221.244561) (xy 18.262765 -221.280847)
			(xy 18.277332 -221.296992) (xy 18.296183 -221.317713) (xy 18.328224 -221.363662) (xy 18.3532 -221.413802)
			(xy 18.370575 -221.467056) (xy 18.379976 -221.522279) (xy 18.381199 -221.578282) (xy 18.374219 -221.633863)
			(xy 18.359186 -221.687825) (xy 18.336422 -221.739008) (xy 18.306418 -221.786312) (xy 18.269819 -221.828719)
			(xy 18.227412 -221.865319) (xy 18.180108 -221.895322) (xy 18.128925 -221.918086) (xy 18.074963 -221.933119)
			(xy 18.019382 -221.940099) (xy 17.963379 -221.938876) (xy 17.908156 -221.929475) (xy 17.854902 -221.9121)
			(xy 17.804761 -221.887124) (xy 17.758813 -221.855083) (xy 17.73809 -221.836234) (xy 17.721994 -221.821601)
			(xy 17.685705 -221.797611) (xy 17.64586 -221.780156) (xy 17.603623 -221.769746) (xy 17.56023 -221.766686)
			(xy 17.51695 -221.771065) (xy 17.475049 -221.782755) (xy 17.435753 -221.801415) (xy 17.400212 -221.826498)
			(xy 17.384522 -221.841568) (xy 16.196818 -223.029272) (xy 16.040354 -223.029272) (xy 12.994114 -226.075512)
			(xy 17.617947 -226.075512) (xy 17.624047 -226.020075) (xy 17.638153 -225.966118) (xy 17.659965 -225.914789)
			(xy 17.689019 -225.867183) (xy 17.724694 -225.824315) (xy 17.766231 -225.787098) (xy 17.812744 -225.756325)
			(xy 17.863241 -225.732653) (xy 17.916648 -225.716585) (xy 17.971824 -225.708465) (xy 17.99971 -225.707956)
			(xy 18.027596 -225.708465) (xy 18.082772 -225.716585) (xy 18.136179 -225.732653) (xy 18.186676 -225.756325)
			(xy 18.233189 -225.787098) (xy 18.274726 -225.824315) (xy 18.310401 -225.867183) (xy 18.339455 -225.914789)
			(xy 18.361267 -225.966118) (xy 18.375373 -226.020075) (xy 18.381473 -226.075512) (xy 18.379436 -226.131246)
			(xy 18.369306 -226.186089) (xy 18.351299 -226.238873) (xy 18.325798 -226.288473) (xy 18.293347 -226.333831)
			(xy 18.254638 -226.37398) (xy 18.210495 -226.408066) (xy 18.16186 -226.435362) (xy 18.109769 -226.455285)
			(xy 18.055332 -226.467411) (xy 17.99971 -226.471482) (xy 17.944088 -226.467411) (xy 17.889651 -226.455285)
			(xy 17.83756 -226.435362) (xy 17.788925 -226.408066) (xy 17.744782 -226.37398) (xy 17.706073 -226.333831)
			(xy 17.673622 -226.288473) (xy 17.648121 -226.238873) (xy 17.630114 -226.186089) (xy 17.619984 -226.131246)
			(xy 17.617947 -226.075512) (xy 12.994114 -226.075512) (xy 11.055078 -228.014548) (xy 17.617947 -228.014548)
			(xy 17.624047 -227.959111) (xy 17.638153 -227.905154) (xy 17.659965 -227.853825) (xy 17.689019 -227.806219)
			(xy 17.724694 -227.763351) (xy 17.766231 -227.726134) (xy 17.812744 -227.695361) (xy 17.863241 -227.671689)
			(xy 17.916648 -227.655621) (xy 17.971824 -227.647501) (xy 17.99971 -227.646992) (xy 18.027596 -227.647501)
			(xy 18.082772 -227.655621) (xy 18.136179 -227.671689) (xy 18.186676 -227.695361) (xy 18.233189 -227.726134)
			(xy 18.274726 -227.763351) (xy 18.310401 -227.806219) (xy 18.339455 -227.853825) (xy 18.361267 -227.905154)
			(xy 18.375373 -227.959111) (xy 18.381473 -228.014548) (xy 18.379436 -228.070282) (xy 18.369306 -228.125125)
			(xy 18.351299 -228.177909) (xy 18.325798 -228.227509) (xy 18.293347 -228.272867) (xy 18.254638 -228.313016)
			(xy 18.210495 -228.347102) (xy 18.16186 -228.374398) (xy 18.109769 -228.394321) (xy 18.055332 -228.406447)
			(xy 17.99971 -228.410518) (xy 17.944088 -228.406447) (xy 17.889651 -228.394321) (xy 17.83756 -228.374398)
			(xy 17.788925 -228.347102) (xy 17.744782 -228.313016) (xy 17.706073 -228.272867) (xy 17.673622 -228.227509)
			(xy 17.648121 -228.177909) (xy 17.630114 -228.125125) (xy 17.619984 -228.070282) (xy 17.617947 -228.014548)
			(xy 11.055078 -228.014548) (xy 10.081006 -228.98862) (xy 9.068308 -228.98862) (xy 9.053247 -228.989047)
			(xy 9.023963 -228.996097) (xy 8.997155 -229.009829) (xy 8.974321 -229.029473) (xy 8.965184 -229.041452)
			(xy 8.944213 -229.069814) (xy 8.896965 -229.122194) (xy 8.84421 -229.169021) (xy 8.786595 -229.20972)
			(xy 8.724829 -229.243792) (xy 8.659671 -229.270817) (xy 8.591922 -229.290464) (xy 8.522415 -229.30249)
			(xy 8.452003 -229.306748) (xy 8.381553 -229.303186) (xy 8.31193 -229.291847) (xy 8.24399 -229.272871)
			(xy 8.178568 -229.246491) (xy 8.116469 -229.213031) (xy 8.058455 -229.172902) (xy 8.005239 -229.126599)
			(xy 7.957476 -229.074689) (xy 7.93623 -229.046532) (xy 7.922976 -229.029092) (xy 7.891412 -228.998721)
			(xy 7.855104 -228.974216) (xy 7.815131 -228.956304) (xy 7.772677 -228.945516) (xy 7.729002 -228.942173)
			(xy 7.6854 -228.946374) (xy 7.643167 -228.957993) (xy 7.603553 -228.976687) (xy 7.567734 -229.0019)
			(xy 7.551928 -229.017068) (xy 7.111492 -229.457504) (xy 7.101188 -229.468481) (xy 7.085501 -229.494166)
			(xy 7.076253 -229.522807) (xy 7.073956 -229.552816) (xy 7.075932 -229.56774) (xy 7.08117 -229.602559)
			(xy 7.084791 -229.672883) (xy 7.080622 -229.743176) (xy 7.068713 -229.812578) (xy 7.049211 -229.88024)
			(xy 7.022354 -229.945334) (xy 7.005828 -229.976426) (xy 6.99562 -229.995864) (xy 6.98145 -230.037419)
			(xy 6.974631 -230.080791) (xy 6.975365 -230.124689) (xy 6.983631 -230.167809) (xy 6.999181 -230.208867)
			(xy 7.021555 -230.246643) (xy 7.050087 -230.280013) (xy 7.083928 -230.307984) (xy 7.122071 -230.329726)
			(xy 7.163383 -230.34459) (xy 7.206634 -230.352136) (xy 7.228586 -230.3526) (xy 7.829296 -230.3526)
			(xy 7.844391 -230.352231) (xy 7.873748 -230.345198) (xy 7.900626 -230.331455) (xy 7.923516 -230.311774)
			(xy 7.932674 -230.299768) (xy 7.953829 -230.271157) (xy 8.001546 -230.218368) (xy 8.05486 -230.171239)
			(xy 8.113105 -230.13036) (xy 8.175552 -230.096243) (xy 8.241419 -230.069315) (xy 8.309881 -230.049913)
			(xy 8.380083 -230.03828) (xy 8.451144 -230.034561) (xy 8.522177 -230.038804) (xy 8.59229 -230.050954)
			(xy 8.660608 -230.07086) (xy 8.726275 -230.098273) (xy 8.788469 -230.132849) (xy 8.846411 -230.174156)
			(xy 8.899376 -230.221677) (xy 8.946702 -230.274817) (xy 8.987796 -230.33291) (xy 9.022143 -230.395231)
			(xy 9.049314 -230.460998) (xy 9.068969 -230.529388) (xy 9.080862 -230.599546) (xy 9.084843 -230.670593)
			(xy 9.080863 -230.741641) (xy 9.068972 -230.811799) (xy 9.049319 -230.88019) (xy 9.022149 -230.945958)
			(xy 8.987803 -231.008279) (xy 8.94671 -231.066373) (xy 8.899385 -231.119514) (xy 8.846421 -231.167036)
			(xy 8.78848 -231.208344) (xy 8.726287 -231.242922) (xy 8.66062 -231.270336) (xy 8.592303 -231.290243)
			(xy 8.52219 -231.302395) (xy 8.451157 -231.306639) (xy 8.380096 -231.302921) (xy 8.309894 -231.29129)
			(xy 8.241431 -231.271889) (xy 8.175564 -231.244963) (xy 8.113116 -231.210847) (xy 8.05487 -231.16997)
			(xy 8.001555 -231.122842) (xy 7.953837 -231.070053) (xy 7.932674 -231.041448) (xy 7.923487 -231.02947)
			(xy 7.900598 -231.009803) (xy 7.87373 -230.996063) (xy 7.844385 -230.989021) (xy 7.829296 -230.988616)
			(xy 6.14426 -230.988616) (xy 5.360416 -230.204772) (xy 5.360416 -228.903022) (xy 6.018276 -228.245162)
			(xy 6.020054 -228.142546) (xy 5.984748 -228.104954) (xy 5.960572 -228.078392) (xy 5.917723 -228.020747)
			(xy 5.881646 -227.958638) (xy 5.852801 -227.892858) (xy 5.831556 -227.824246) (xy 5.818181 -227.753675)
			(xy 5.812847 -227.682047) (xy 5.815623 -227.610274) (xy 5.826472 -227.539272) (xy 5.845256 -227.469946)
			(xy 5.871736 -227.403179) (xy 5.905575 -227.339822) (xy 5.94634 -227.280685) (xy 5.993512 -227.22652)
			(xy 6.04649 -227.178019) (xy 6.104598 -227.135799) (xy 6.167095 -227.1004) (xy 6.233185 -227.072272)
			(xy 6.302024 -227.051773) (xy 6.372736 -227.039166) (xy 6.444417 -227.034612) (xy 6.516156 -227.038167)
			(xy 6.551676 -227.043488) (xy 6.566606 -227.045496) (xy 6.596639 -227.043268) (xy 6.625302 -227.034027)
			(xy 6.650981 -227.018294) (xy 6.661912 -227.007928) (xy 7.24789 -226.422204) (xy 7.263836 -226.405548)
			(xy 7.290028 -226.367602) (xy 7.308948 -226.325557) (xy 7.319978 -226.280788) (xy 7.322755 -226.234765)
			(xy 7.317189 -226.188996) (xy 7.303461 -226.14498) (xy 7.282023 -226.10416) (xy 7.253576 -226.067875)
			(xy 7.219053 -226.037314) (xy 7.179586 -226.013477) (xy 7.136468 -225.997148) (xy 7.091112 -225.98886)
			(xy 7.068058 -225.988372) (xy 7.037324 -225.988372) (xy 6.982968 -226.016312) (xy 6.964934 -226.041458)
			(xy 6.943437 -226.07051) (xy 6.894877 -226.124039) (xy 6.840557 -226.171714) (xy 6.78118 -226.212919)
			(xy 6.717512 -226.247122) (xy 6.650374 -226.273881) (xy 6.580634 -226.292851) (xy 6.509192 -226.303786)
			(xy 6.436971 -226.306546) (xy 6.364903 -226.301096) (xy 6.293919 -226.287504) (xy 6.224935 -226.265947)
			(xy 6.158841 -226.236704) (xy 6.096492 -226.200151) (xy 6.038693 -226.156761) (xy 5.986188 -226.107094)
			(xy 5.939658 -226.051792) (xy 5.899701 -225.991567) (xy 5.866835 -225.927199) (xy 5.841483 -225.859517)
			(xy 5.823974 -225.789396) (xy 5.814532 -225.717742) (xy 5.81328 -225.645479) (xy 5.820234 -225.57354)
			(xy 5.835304 -225.502855) (xy 5.846318 -225.468434) (xy 5.852896 -225.447541) (xy 5.859526 -225.404245)
			(xy 5.858637 -225.360453) (xy 5.850254 -225.317462) (xy 5.834626 -225.276545) (xy 5.812215 -225.238912)
			(xy 5.783686 -225.205677) (xy 5.749881 -225.177825) (xy 5.711803 -225.156179) (xy 5.670578 -225.141381)
			(xy 5.627426 -225.133868) (xy 5.605526 -225.133408) (xy 4.988052 -225.133408) (xy 4.971418 -225.133974)
			(xy 4.939301 -225.142659) (xy 4.910519 -225.159348) (xy 4.89839 -225.170746) (xy 4.611624 -225.457512)
			(xy 4.601272 -225.468411) (xy 4.585568 -225.494033) (xy 4.576325 -225.522629) (xy 4.574064 -225.552596)
			(xy 4.576064 -225.567494) (xy 4.576064 -225.567748) (xy 4.581324 -225.602743) (xy 4.584962 -225.673418)
			(xy 4.580726 -225.744061) (xy 4.56867 -225.813795) (xy 4.54894 -225.881758) (xy 4.521783 -225.94711)
			(xy 4.487534 -226.009039) (xy 4.446618 -226.066781) (xy 4.39954 -226.11962) (xy 4.346884 -226.166902)
			(xy 4.289301 -226.208041) (xy 4.227504 -226.24253) (xy 4.162259 -226.269939) (xy 4.094372 -226.289931)
			(xy 4.024685 -226.302258) (xy 3.954059 -226.306767) (xy 3.88337 -226.303402) (xy 3.813493 -226.292205)
			(xy 3.745291 -226.273315) (xy 3.67961 -226.246965) (xy 3.617263 -226.213482) (xy 3.559022 -226.17328)
			(xy 3.505607 -226.126857) (xy 3.45768 -226.074787) (xy 3.436366 -226.046538) (xy 3.42307 -226.029131)
			(xy 3.391513 -225.99876) (xy 3.355212 -225.974254) (xy 3.315244 -225.95634) (xy 3.272796 -225.945549)
			(xy 3.229125 -225.942203) (xy 3.185528 -225.946399) (xy 3.143298 -225.958013) (xy 3.103687 -225.976701)
			(xy 3.067869 -226.001909) (xy 3.052064 -226.017074) (xy 2.611628 -226.45751) (xy 2.601311 -226.468475)
			(xy 2.58563 -226.494166) (xy 2.576387 -226.52281) (xy 2.574092 -226.552821) (xy 2.576068 -226.567746)
			(xy 2.581338 -226.602938) (xy 2.584941 -226.674008) (xy 2.580581 -226.745035) (xy 2.568314 -226.815131)
			(xy 2.548293 -226.883418) (xy 2.520768 -226.94904) (xy 2.486086 -227.011178) (xy 2.444679 -227.069051)
			(xy 2.397066 -227.121937) (xy 2.343843 -227.169173) (xy 2.285676 -227.210168) (xy 2.223294 -227.244408)
			(xy 2.157477 -227.271464) (xy 2.08905 -227.290999) (xy 2.018868 -227.302768) (xy 1.947811 -227.306623)
			(xy 1.876769 -227.302515) (xy 1.80663 -227.290497) (xy 1.738272 -227.270719) (xy 1.672552 -227.243429)
			(xy 1.610292 -227.208967) (xy 1.552272 -227.167766) (xy 1.499217 -227.120341) (xy 1.451792 -227.067286)
			(xy 1.410591 -227.009266) (xy 1.376129 -226.947006) (xy 1.348839 -226.881286) (xy 1.329061 -226.812928)
			(xy 1.317043 -226.742789) (xy 1.312935 -226.671747) (xy 1.31679 -226.60069) (xy 1.328559 -226.530508)
			(xy 1.348094 -226.462081) (xy 1.37515 -226.396264) (xy 1.40939 -226.333882) (xy 1.450385 -226.275715)
			(xy 1.497621 -226.222492) (xy 1.550507 -226.174879) (xy 1.60838 -226.133472) (xy 1.670518 -226.09879)
			(xy 1.73614 -226.071265) (xy 1.804427 -226.051244) (xy 1.874523 -226.038977) (xy 1.94555 -226.034617)
			(xy 2.01662 -226.03822) (xy 2.051812 -226.04349) (xy 2.066737 -226.045553) (xy 2.096778 -226.043316)
			(xy 2.125445 -226.034059) (xy 2.151121 -226.018306) (xy 2.162048 -226.00793) (xy 3.602482 -224.567496)
			(xy 3.617625 -224.551679) (xy 3.6428 -224.515855) (xy 3.661461 -224.476245) (xy 3.673057 -224.434024)
			(xy 3.677243 -224.390439) (xy 3.673896 -224.346782) (xy 3.663116 -224.304345) (xy 3.64522 -224.264384)
			(xy 3.620739 -224.228082) (xy 3.590398 -224.196514) (xy 3.573018 -224.183194) (xy 3.544846 -224.161919)
			(xy 3.492908 -224.114101) (xy 3.446587 -224.060823) (xy 3.406454 -224.002741) (xy 3.373002 -223.94057)
			(xy 3.346645 -223.875076) (xy 3.327706 -223.807065) (xy 3.316418 -223.737375) (xy 3.312921 -223.666863)
			(xy 3.317257 -223.596397) (xy 3.329374 -223.526846) (xy 3.349121 -223.459066) (xy 3.376257 -223.39389)
			(xy 3.392932 -223.362774) (xy 3.40317 -223.3433) (xy 3.417532 -223.301719) (xy 3.424522 -223.258285)
			(xy 3.423931 -223.214297) (xy 3.415776 -223.171067) (xy 3.400302 -223.129887) (xy 3.377969 -223.091985)
			(xy 3.349446 -223.058493) (xy 3.315583 -223.030411) (xy 3.277391 -223.008577) (xy 3.236011 -222.993644)
			(xy 3.192678 -222.986058) (xy 3.170682 -222.985584) (xy 2.570226 -222.985584) (xy 2.555105 -222.986049)
			(xy 2.525721 -222.993203) (xy 2.498844 -223.007067) (xy 2.475981 -223.026865) (xy 2.466848 -223.038924)
			(xy 2.445829 -223.067633) (xy 2.398387 -223.120662) (xy 2.345317 -223.168059) (xy 2.287284 -223.209231)
			(xy 2.225015 -223.243662) (xy 2.159289 -223.27092) (xy 2.090929 -223.290665) (xy 2.020792 -223.30265)
			(xy 1.949754 -223.306724) (xy 1.878706 -223.302836) (xy 1.808537 -223.291036) (xy 1.740126 -223.27147)
			(xy 1.674329 -223.244384) (xy 1.61197 -223.210117) (xy 1.553829 -223.169097) (xy 1.500635 -223.12184)
			(xy 1.453053 -223.068935) (xy 1.41168 -223.011046) (xy 1.377033 -222.948897) (xy 1.349546 -222.883266)
			(xy 1.329563 -222.814976) (xy 1.317334 -222.74488) (xy 1.313013 -222.673857) (xy 1.316653 -222.602796)
			(xy 1.32821 -222.532587) (xy 1.347537 -222.464108) (xy 1.374394 -222.398217) (xy 1.408444 -222.335739)
			(xy 1.44926 -222.277456) (xy 1.496333 -222.224098) (xy 1.549072 -222.176332) (xy 1.606816 -222.134757)
			(xy 1.668844 -222.099894) (xy 1.734379 -222.072179) (xy 1.8026 -222.051958) (xy 1.872652 -222.039486)
			(xy 1.943659 -222.034917) (xy 2.014733 -222.03831) (xy 2.084982 -222.049622) (xy 2.153528 -222.068711)
			(xy 2.219512 -222.095339) (xy 2.282108 -222.129171) (xy 2.340533 -222.169784) (xy 2.394055 -222.216671)
			(xy 2.442003 -222.269243) (xy 2.463292 -222.297752) (xy 2.472461 -222.309619) (xy 2.495293 -222.329052)
			(xy 2.522018 -222.342644) (xy 2.551171 -222.349648) (xy 2.566162 -222.350076) (xy 3.167634 -222.350076)
			(xy 3.189573 -222.349641) (xy 3.232806 -222.342157) (xy 3.274111 -222.327357) (xy 3.31226 -222.305682)
			(xy 3.346119 -222.277777) (xy 3.374681 -222.24447) (xy 3.397097 -222.206752) (xy 3.412702 -222.165744)
			(xy 3.42103 -222.122666) (xy 3.421835 -222.078797) (xy 3.415092 -222.035442) (xy 3.401003 -221.993889)
			(xy 3.3909 -221.97441) (xy 3.374417 -221.943153) (xy 3.347704 -221.877731) (xy 3.328418 -221.809747)
			(xy 3.316798 -221.740043) (xy 3.312988 -221.669479) (xy 3.317034 -221.598929) (xy 3.328886 -221.529264)
			(xy 3.348399 -221.461345) (xy 3.37533 -221.396012) (xy 3.391916 -221.36481) (xy 3.402042 -221.345332)
			(xy 3.416211 -221.303786) (xy 3.423031 -221.260424) (xy 3.422301 -221.216534) (xy 3.414041 -221.173423)
			(xy 3.398497 -221.132372) (xy 3.376132 -221.094602) (xy 3.34761 -221.061235) (xy 3.31378 -221.033265)
			(xy 3.275647 -221.011523) (xy 3.234347 -220.996655) (xy 3.191106 -220.989104) (xy 3.169158 -220.988636)
			(xy 2.568448 -220.988636) (xy 2.553354 -220.989021) (xy 2.523996 -220.996046) (xy 2.497118 -221.009784)
			(xy 2.474228 -221.029463) (xy 2.46507 -221.041468) (xy 2.443909 -221.070075) (xy 2.396192 -221.122864)
			(xy 2.342878 -221.169993) (xy 2.284632 -221.210872) (xy 2.222185 -221.244988) (xy 2.156318 -221.271916)
			(xy 2.087855 -221.291317) (xy 2.017654 -221.30295) (xy 1.946592 -221.306668) (xy 1.87556 -221.302426)
			(xy 1.805446 -221.290275) (xy 1.737128 -221.270368) (xy 1.671462 -221.242955) (xy 1.609268 -221.208379)
			(xy 1.551326 -221.167071) (xy 1.498361 -221.11955) (xy 1.451036 -221.06641) (xy 1.409942 -221.008316)
			(xy 1.375595 -220.945995) (xy 1.348424 -220.880228) (xy 1.32877 -220.811837) (xy 1.316878 -220.741679)
			(xy 1.312897 -220.670632) (xy 1.316878 -220.599584) (xy 1.328769 -220.529426) (xy 1.348423 -220.461035)
			(xy 1.375594 -220.395268) (xy 1.40994 -220.332947) (xy 1.451034 -220.274853) (xy 1.498359 -220.221712)
			(xy 1.551324 -220.174191) (xy 1.609266 -220.132883) (xy 1.671459 -220.098306) (xy 1.737125 -220.070893)
			(xy 1.805443 -220.050986) (xy 1.875557 -220.038835) (xy 1.946589 -220.034592) (xy 2.017651 -220.038309)
			(xy 2.087852 -220.049942) (xy 2.156315 -220.069343) (xy 2.222182 -220.09627) (xy 2.28463 -220.130387)
			(xy 2.342875 -220.171265) (xy 2.39619 -220.218394) (xy 2.443907 -220.271183) (xy 2.46507 -220.299788)
			(xy 2.474223 -220.311795) (xy 2.497124 -220.331456) (xy 2.524003 -220.345188) (xy 2.553355 -220.352221)
			(xy 2.568448 -220.35262) (xy 3.951732 -220.35262) (xy 4.082288 -220.222064) (xy 5.610606 -220.222064)
			(xy 5.63268 -220.221571) (xy 5.676158 -220.213912) (xy 5.717659 -220.198854) (xy 5.755933 -220.176851)
			(xy 5.789829 -220.148565) (xy 5.818326 -220.114847) (xy 5.840568 -220.076711) (xy 5.855886 -220.035306)
			(xy 5.863817 -219.991876) (xy 5.864124 -219.947729) (xy 5.856797 -219.904194) (xy 5.849874 -219.883228)
			(xy 5.838454 -219.849612) (xy 5.822294 -219.780476) (xy 5.81394 -219.70997) (xy 5.813496 -219.638972)
			(xy 5.820968 -219.568367) (xy 5.836262 -219.499035) (xy 5.859188 -219.431839) (xy 5.889459 -219.367617)
			(xy 5.9267 -219.307169) (xy 5.970446 -219.251247) (xy 6.020152 -219.20055) (xy 6.075198 -219.155708)
			(xy 6.134899 -219.117281) (xy 6.198511 -219.085746) (xy 6.265241 -219.061498) (xy 6.334258 -219.044838)
			(xy 6.404701 -219.035973) (xy 6.475694 -219.035015) (xy 6.546351 -219.041974) (xy 6.615793 -219.056766)
			(xy 6.683153 -219.079204) (xy 6.747593 -219.10901) (xy 6.808309 -219.145812) (xy 6.864546 -219.189151)
			(xy 6.915602 -219.238488) (xy 6.960842 -219.293208) (xy 6.980682 -219.32265) (xy 6.99348 -219.341264)
			(xy 7.024484 -219.374109) (xy 7.060806 -219.400955) (xy 7.101301 -219.420957) (xy 7.144696 -219.433484)
			(xy 7.189621 -219.438142) (xy 7.234662 -219.434785) (xy 7.278401 -219.423517) (xy 7.319458 -219.404695)
			(xy 7.356541 -219.37891) (xy 7.372858 -219.36329) (xy 7.605522 -219.130626) (xy 7.627251 -219.128276)
			(xy 7.669502 -219.117106) (xy 7.709221 -219.098877) (xy 7.745239 -219.074127) (xy 7.776496 -219.043584)
			(xy 7.802072 -219.008147) (xy 7.821214 -218.96886) (xy 7.833358 -218.926879) (xy 7.838148 -218.88344)
			(xy 7.835441 -218.839822) (xy 7.83082 -218.81846) (xy 7.823064 -218.784247) (xy 7.814353 -218.714633)
			(xy 7.813363 -218.644483) (xy 7.820106 -218.574651) (xy 7.8345 -218.505986) (xy 7.85637 -218.439325)
			(xy 7.885449 -218.375478) (xy 7.921383 -218.315223) (xy 7.963736 -218.259292) (xy 8.011991 -218.208366)
			(xy 8.065562 -218.163066) (xy 8.123797 -218.123942) (xy 8.185987 -218.09147) (xy 8.251376 -218.066046)
			(xy 8.319166 -218.047979) (xy 8.388535 -218.037489) (xy 8.458636 -218.034703) (xy 8.528618 -218.039656)
			(xy 8.597629 -218.052286) (xy 8.664828 -218.072442) (xy 8.729399 -218.099876) (xy 8.760206 -218.116658)
			(xy 8.779668 -218.127077) (xy 8.821285 -218.141789) (xy 8.864817 -218.149086) (xy 8.908957 -218.148751)
			(xy 8.952373 -218.140792) (xy 8.993762 -218.12545) (xy 9.031875 -218.103185) (xy 9.065568 -218.074669)
			(xy 9.093825 -218.040759) (xy 9.115797 -218.002475) (xy 9.130822 -217.960971) (xy 9.138447 -217.917494)
			(xy 9.13892 -217.895424) (xy 9.13892 -215.445848) (xy 9.138422 -215.423781) (xy 9.130788 -215.380312)
			(xy 9.115758 -215.338815) (xy 9.093785 -215.300539) (xy 9.065529 -215.266635) (xy 9.031841 -215.238123)
			(xy 8.993733 -215.21586) (xy 8.952351 -215.200517) (xy 8.908941 -215.192553) (xy 8.864808 -215.192209)
			(xy 8.821279 -215.199496) (xy 8.779664 -215.214193) (xy 8.760206 -215.224614) (xy 8.728772 -215.241724)
			(xy 8.662837 -215.269563) (xy 8.594192 -215.289819) (xy 8.523705 -215.302233) (xy 8.45227 -215.30665)
			(xy 8.380792 -215.303013) (xy 8.310174 -215.291368) (xy 8.241312 -215.271863) (xy 8.175077 -215.244745)
			(xy 8.112308 -215.210357) (xy 8.053801 -215.169134) (xy 8.000295 -215.121599) (xy 7.952469 -215.068353)
			(xy 7.910927 -215.010072) (xy 7.876197 -214.947492) (xy 7.848718 -214.881406) (xy 7.828837 -214.812651)
			(xy 7.816807 -214.742098) (xy 7.81278 -214.67064) (xy 7.816807 -214.599182) (xy 7.828837 -214.528629)
			(xy 7.848718 -214.459874) (xy 7.876197 -214.393788) (xy 7.910927 -214.331208) (xy 7.952469 -214.272927)
			(xy 8.000295 -214.219681) (xy 8.053801 -214.172146) (xy 8.112308 -214.130923) (xy 8.175077 -214.096535)
			(xy 8.241312 -214.069417) (xy 8.310174 -214.049912) (xy 8.380792 -214.038267) (xy 8.45227 -214.03463)
			(xy 8.523705 -214.039047) (xy 8.594192 -214.051461) (xy 8.662837 -214.071717) (xy 8.728772 -214.099556)
			(xy 8.760206 -214.116666) (xy 8.779667 -214.127087) (xy 8.821284 -214.141799) (xy 8.864817 -214.149096)
			(xy 8.908956 -214.148761) (xy 8.952374 -214.140802) (xy 8.993762 -214.12546) (xy 9.031876 -214.103195)
			(xy 9.065569 -214.074678) (xy 9.093826 -214.040768) (xy 9.115797 -214.002484) (xy 9.130822 -213.960979)
			(xy 9.138448 -213.917502) (xy 9.13892 -213.895432) (xy 9.13892 -213.445852) (xy 9.138419 -213.423785)
			(xy 9.130785 -213.380316) (xy 9.115756 -213.338819) (xy 9.093783 -213.300543) (xy 9.065528 -213.266639)
			(xy 9.03184 -213.238127) (xy 8.993732 -213.215864) (xy 8.952351 -213.20052) (xy 8.90894 -213.192556)
			(xy 8.864807 -213.192213) (xy 8.821279 -213.199499) (xy 8.779663 -213.214197) (xy 8.760206 -213.224618)
			(xy 8.728769 -213.241721) (xy 8.662834 -213.269561) (xy 8.594189 -213.289816) (xy 8.523703 -213.30223)
			(xy 8.452268 -213.306647) (xy 8.38079 -213.303009) (xy 8.310173 -213.291364) (xy 8.241311 -213.271859)
			(xy 8.175077 -213.244741) (xy 8.112309 -213.210353) (xy 8.053801 -213.16913) (xy 8.000296 -213.121595)
			(xy 7.95247 -213.06835) (xy 7.910929 -213.010068) (xy 7.876199 -212.947488) (xy 7.84872 -212.881403)
			(xy 7.82884 -212.812648) (xy 7.816811 -212.742096) (xy 7.812784 -212.670638) (xy 7.816811 -212.599181)
			(xy 7.828841 -212.528628) (xy 7.848722 -212.459874) (xy 7.876201 -212.393788) (xy 7.910931 -212.331209)
			(xy 7.952473 -212.272927) (xy 8.000299 -212.219682) (xy 8.053804 -212.172147) (xy 8.112312 -212.130925)
			(xy 8.17508 -212.096537) (xy 8.241315 -212.069419) (xy 8.310177 -212.049915) (xy 8.380794 -212.03827)
			(xy 8.452272 -212.034633) (xy 8.523707 -212.03905) (xy 8.594193 -212.051465) (xy 8.662838 -212.071721)
			(xy 8.728772 -212.09956) (xy 8.760206 -212.11667) (xy 8.779665 -212.127096) (xy 8.821282 -212.141808)
			(xy 8.864816 -212.149106) (xy 8.908956 -212.148771) (xy 8.952374 -212.140812) (xy 8.993763 -212.125469)
			(xy 9.031878 -212.103204) (xy 9.06557 -212.074686) (xy 9.093828 -212.040775) (xy 9.115799 -212.00249)
			(xy 9.130823 -211.960985) (xy 9.138448 -211.917507) (xy 9.13892 -211.895436) (xy 9.13892 -211.445856)
			(xy 9.138416 -211.423789) (xy 9.130783 -211.38032) (xy 9.115754 -211.338823) (xy 9.093782 -211.300547)
			(xy 9.065527 -211.266643) (xy 9.031839 -211.23813) (xy 8.993731 -211.215867) (xy 8.95235 -211.200523)
			(xy 8.90894 -211.19256) (xy 8.864807 -211.192216) (xy 8.821278 -211.199503) (xy 8.779663 -211.214201)
			(xy 8.760206 -211.224622) (xy 8.728773 -211.241735) (xy 8.662838 -211.269575) (xy 8.594193 -211.28983)
			(xy 8.523706 -211.302245) (xy 8.452271 -211.306662) (xy 8.380792 -211.303025) (xy 8.310175 -211.29138)
			(xy 8.241312 -211.271875) (xy 8.175077 -211.244757) (xy 8.112308 -211.210369) (xy 8.0538 -211.169146)
			(xy 8.000294 -211.121611) (xy 7.952468 -211.068365) (xy 7.910926 -211.010083) (xy 7.876196 -210.947503)
			(xy 7.848716 -210.881417) (xy 7.828836 -210.812662) (xy 7.816806 -210.742109) (xy 7.812779 -210.670651)
			(xy 7.816806 -210.599193) (xy 7.828835 -210.52864) (xy 7.848716 -210.459885) (xy 7.876195 -210.393799)
			(xy 7.910925 -210.331218) (xy 7.952467 -210.272936) (xy 8.000293 -210.21969) (xy 8.053799 -210.172155)
			(xy 8.112307 -210.130932) (xy 8.175075 -210.096544) (xy 8.24131 -210.069425) (xy 8.310173 -210.04992)
			(xy 8.38079 -210.038275) (xy 8.452269 -210.034638) (xy 8.523705 -210.039055) (xy 8.594191 -210.05147)
			(xy 8.662837 -210.071725) (xy 8.728772 -210.099564) (xy 8.760206 -210.116674) (xy 8.779666 -210.127097)
			(xy 8.821283 -210.141808) (xy 8.864817 -210.149106) (xy 8.908956 -210.148771) (xy 8.952374 -210.140812)
			(xy 8.993762 -210.125469) (xy 9.031876 -210.103205) (xy 9.065569 -210.074688) (xy 9.093827 -210.040777)
			(xy 9.115798 -210.002493) (xy 9.130823 -209.960988) (xy 9.138448 -209.91751) (xy 9.13892 -209.89544)
			(xy 9.13892 -209.44586) (xy 9.138413 -209.423793) (xy 9.13078 -209.380324) (xy 9.115752 -209.338827)
			(xy 9.09378 -209.300551) (xy 9.065526 -209.266647) (xy 9.031838 -209.238134) (xy 8.99373 -209.215871)
			(xy 8.952349 -209.200527) (xy 8.908939 -209.192563) (xy 8.864807 -209.19222) (xy 8.821278 -209.199507)
			(xy 8.779663 -209.214205) (xy 8.760206 -209.224626) (xy 8.72877 -209.241733) (xy 8.662835 -209.269572)
			(xy 8.59419 -209.289827) (xy 8.523704 -209.302242) (xy 8.452269 -209.306658) (xy 8.380791 -209.303021)
			(xy 8.310173 -209.291376) (xy 8.241311 -209.271871) (xy 8.175077 -209.244753) (xy 8.112308 -209.210365)
			(xy 8.053801 -209.169142) (xy 8.000295 -209.121607) (xy 7.952469 -209.068362) (xy 7.910928 -209.01008)
			(xy 7.876198 -208.9475) (xy 7.848719 -208.881414) (xy 7.828839 -208.81266) (xy 7.816809 -208.742107)
			(xy 7.812782 -208.670649) (xy 7.816809 -208.599191) (xy 7.828839 -208.528638) (xy 7.84872 -208.459884)
			(xy 7.876199 -208.393798) (xy 7.910929 -208.331219) (xy 7.952471 -208.272937) (xy 8.000297 -208.219692)
			(xy 8.053803 -208.172157) (xy 8.11231 -208.130934) (xy 8.175079 -208.096546) (xy 8.241313 -208.069428)
			(xy 8.310175 -208.049923) (xy 8.380793 -208.038279) (xy 8.452271 -208.034642) (xy 8.523706 -208.039059)
			(xy 8.594192 -208.051473) (xy 8.662837 -208.071729) (xy 8.728772 -208.099568) (xy 8.760206 -208.116678)
			(xy 8.779668 -208.127097) (xy 8.821285 -208.141809) (xy 8.864817 -208.149106) (xy 8.908957 -208.148771)
			(xy 8.952373 -208.140812) (xy 8.993762 -208.12547) (xy 9.031875 -208.103205) (xy 9.065568 -208.074689)
			(xy 9.093825 -208.040779) (xy 9.115797 -208.002495) (xy 9.130822 -207.960991) (xy 9.138447 -207.917514)
			(xy 9.13892 -207.895444) (xy 9.13892 -207.445864) (xy 9.13841 -207.423797) (xy 9.130778 -207.380328)
			(xy 9.11575 -207.338831) (xy 9.093779 -207.300555) (xy 9.065524 -207.26665) (xy 9.031837 -207.238138)
			(xy 8.993729 -207.215874) (xy 8.952349 -207.20053) (xy 8.908939 -207.192567) (xy 8.864806 -207.192223)
			(xy 8.821278 -207.19951) (xy 8.779663 -207.214209) (xy 8.760206 -207.22463) (xy 8.728775 -207.241746)
			(xy 8.66284 -207.269586) (xy 8.594194 -207.289841) (xy 8.523708 -207.302256) (xy 8.452272 -207.306674)
			(xy 8.380793 -207.303037) (xy 8.310175 -207.291392) (xy 8.241312 -207.271887) (xy 8.175077 -207.244769)
			(xy 8.112308 -207.210381) (xy 8.0538 -207.169158) (xy 8.000294 -207.121623) (xy 7.952467 -207.068377)
			(xy 7.910925 -207.010095) (xy 7.876195 -206.947515) (xy 7.848715 -206.881429) (xy 7.828834 -206.812674)
			(xy 7.816804 -206.74212) (xy 7.812777 -206.670662) (xy 7.816804 -206.599204) (xy 7.828834 -206.52865)
			(xy 7.848714 -206.459895) (xy 7.876193 -206.393809) (xy 7.910923 -206.331228) (xy 7.952465 -206.272946)
			(xy 8.000291 -206.2197) (xy 8.053797 -206.172164) (xy 8.112305 -206.130941) (xy 8.175074 -206.096553)
			(xy 8.241309 -206.069434) (xy 8.310171 -206.049929) (xy 8.380789 -206.038284) (xy 8.452268 -206.034646)
			(xy 8.523704 -206.039063) (xy 8.594191 -206.051478) (xy 8.662836 -206.071733) (xy 8.728772 -206.099572)
			(xy 8.760206 -206.116682) (xy 8.77968 -206.127081) (xy 8.821294 -206.1418) (xy 8.864827 -206.149104)
			(xy 8.908966 -206.148774) (xy 8.952384 -206.140819) (xy 8.993774 -206.125479) (xy 9.031889 -206.103215)
			(xy 9.065582 -206.074699) (xy 9.093838 -206.040788) (xy 9.115808 -206.002503) (xy 9.130829 -205.960996)
			(xy 9.13845 -205.917518) (xy 9.13892 -205.895448) (xy 9.13892 -205.445868) (xy 9.138406 -205.423801)
			(xy 9.130775 -205.380332) (xy 9.115748 -205.338835) (xy 9.093777 -205.300558) (xy 9.065523 -205.266654)
			(xy 9.031836 -205.238141) (xy 8.993729 -205.215878) (xy 8.952348 -205.200534) (xy 8.908938 -205.19257)
			(xy 8.864806 -205.192227) (xy 8.821277 -205.199514) (xy 8.779663 -205.214213) (xy 8.760206 -205.224634)
			(xy 8.728772 -205.241744) (xy 8.662837 -205.269583) (xy 8.594192 -205.289839) (xy 8.523705 -205.302253)
			(xy 8.45227 -205.30667) (xy 8.380792 -205.303033) (xy 8.310174 -205.291388) (xy 8.241312 -205.271883)
			(xy 8.175077 -205.244765) (xy 8.112308 -205.210377) (xy 8.053801 -205.169154) (xy 8.000295 -205.121619)
			(xy 7.952469 -205.068373) (xy 7.910927 -205.010092) (xy 7.876197 -204.947512) (xy 7.848718 -204.881426)
			(xy 7.828837 -204.812671) (xy 7.816807 -204.742118) (xy 7.81278 -204.67066) (xy 7.816807 -204.599202)
			(xy 7.828837 -204.528649) (xy 7.848718 -204.459894) (xy 7.876197 -204.393808) (xy 7.910927 -204.331228)
			(xy 7.952469 -204.272947) (xy 8.000295 -204.219701) (xy 8.053801 -204.172166) (xy 8.112308 -204.130943)
			(xy 8.175077 -204.096555) (xy 8.241312 -204.069437) (xy 8.310174 -204.049932) (xy 8.380792 -204.038287)
			(xy 8.45227 -204.03465) (xy 8.523705 -204.039067) (xy 8.594192 -204.051481) (xy 8.662837 -204.071737)
			(xy 8.728772 -204.099576) (xy 8.760206 -204.116686) (xy 8.779681 -204.127081) (xy 8.821296 -204.1418)
			(xy 8.864827 -204.149104) (xy 8.908966 -204.148774) (xy 8.952384 -204.140819) (xy 8.993773 -204.125479)
			(xy 9.031888 -204.103216) (xy 9.06558 -204.0747) (xy 9.093837 -204.040789) (xy 9.115807 -204.002505)
			(xy 9.130829 -203.961) (xy 9.13845 -203.917522) (xy 9.13892 -203.895452) (xy 9.13892 -203.445618)
			(xy 9.138446 -203.42355) (xy 9.130807 -203.380081) (xy 9.115773 -203.338585) (xy 9.093797 -203.30031)
			(xy 9.065538 -203.266408) (xy 9.031848 -203.237896) (xy 8.993739 -203.215634) (xy 8.952356 -203.200291)
			(xy 8.908945 -203.192327) (xy 8.864811 -203.191983) (xy 8.821281 -203.199268) (xy 8.779665 -203.213964)
			(xy 8.760206 -203.224384) (xy 8.729072 -203.241325) (xy 8.663802 -203.26897) (xy 8.595861 -203.28918)
			(xy 8.526093 -203.301702) (xy 8.455364 -203.306382) (xy 8.384554 -203.303161) (xy 8.314543 -203.292079)
			(xy 8.2462 -203.273275) (xy 8.180374 -203.246981) (xy 8.117883 -203.213525) (xy 8.059504 -203.173321)
			(xy 8.005962 -203.126871) (xy 7.957922 -203.07475) (xy 7.915982 -203.017606) (xy 7.880662 -202.95615)
			(xy 7.8524 -202.891144) (xy 7.831549 -202.823397) (xy 7.818367 -202.753751) (xy 7.813019 -202.68307)
			(xy 7.81557 -202.612233) (xy 7.825988 -202.54212) (xy 7.844145 -202.473601) (xy 7.869815 -202.40753)
			(xy 7.902679 -202.344725) (xy 7.942328 -202.285969) (xy 7.98827 -202.23199) (xy 8.039934 -202.183459)
			(xy 8.096678 -202.14098) (xy 8.157798 -202.105079) (xy 8.222533 -202.076204) (xy 8.29008 -202.054713)
			(xy 8.359598 -202.040873) (xy 8.430226 -202.034856) (xy 8.501084 -202.036737) (xy 8.571292 -202.046492)
			(xy 8.639979 -202.064) (xy 8.706291 -202.089043) (xy 8.769403 -202.121311) (xy 8.828532 -202.160403)
			(xy 8.882944 -202.205832) (xy 8.931961 -202.257035) (xy 8.974975 -202.313375) (xy 8.993632 -202.343512)
			(xy 9.005948 -202.363048) (xy 9.036455 -202.397714) (xy 9.072725 -202.426294) (xy 9.113563 -202.447847)
			(xy 9.157625 -202.461663) (xy 9.203459 -202.467287) (xy 9.249554 -202.464534) (xy 9.294392 -202.453494)
			(xy 9.336496 -202.434531) (xy 9.374479 -202.40827) (xy 9.391142 -202.39228) (xy 14.678152 -197.105524)
			(xy 14.68951 -197.093381) (xy 14.706111 -197.064588) (xy 14.714699 -197.03248) (xy 14.715236 -197.015862)
			(xy 14.715236 -195.46697) (xy 14.714764 -195.443907) (xy 14.706508 -195.398527) (xy 14.690199 -195.355382)
			(xy 14.666373 -195.315888) (xy 14.635811 -195.281341) (xy 14.599518 -195.252876) (xy 14.558685 -195.231426)
			(xy 14.514651 -195.217697) (xy 14.468863 -195.212137) (xy 14.422823 -195.214931) (xy 14.378043 -195.225987)
			(xy 14.335992 -195.24494) (xy 14.298052 -195.271171) (xy 14.281404 -195.287138) (xy 9.111488 -200.457308)
			(xy 9.101181 -200.468282) (xy 9.085495 -200.493969) (xy 9.076248 -200.52261) (xy 9.073952 -200.55262)
			(xy 9.075928 -200.567544) (xy 9.081207 -200.602733) (xy 9.084811 -200.673799) (xy 9.080454 -200.744823)
			(xy 9.068191 -200.814917) (xy 9.048175 -200.883201) (xy 9.020657 -200.948823) (xy 8.985982 -201.01096)
			(xy 8.944582 -201.068835) (xy 8.896977 -201.121724) (xy 8.843762 -201.168963) (xy 8.785603 -201.209963)
			(xy 8.723229 -201.244211) (xy 8.657419 -201.271276) (xy 8.588998 -201.290821) (xy 8.518822 -201.302601)
			(xy 8.44777 -201.306469) (xy 8.37673 -201.302376) (xy 8.306592 -201.290373) (xy 8.238233 -201.27061)
			(xy 8.17251 -201.243336) (xy 8.110245 -201.208891) (xy 8.052216 -201.167706) (xy 7.999152 -201.120298)
			(xy 7.951715 -201.067258) (xy 7.910499 -201.009252) (xy 7.876021 -200.947005) (xy 7.848712 -200.881296)
			(xy 7.828913 -200.812948) (xy 7.816873 -200.742817) (xy 7.812742 -200.671779) (xy 7.816572 -200.600724)
			(xy 7.828314 -200.530542) (xy 7.847823 -200.46211) (xy 7.874853 -200.396287) (xy 7.891526 -200.364852)
			(xy 7.901692 -200.345381) (xy 7.915934 -200.303834) (xy 7.922819 -200.260458) (xy 7.922144 -200.216543)
			(xy 7.913927 -200.173399) (xy 7.898414 -200.13231) (xy 7.876066 -200.094501) (xy 7.84755 -200.061098)
			(xy 7.813714 -200.033096) (xy 7.775568 -200.011329) (xy 7.734247 -199.996446) (xy 7.690982 -199.98889)
			(xy 7.669022 -199.988424) (xy 7.068312 -199.988424) (xy 7.053251 -199.988852) (xy 7.023967 -199.995902)
			(xy 6.997159 -200.009633) (xy 6.974325 -200.029277) (xy 6.965188 -200.041256) (xy 6.94435 -200.06948)
			(xy 6.897405 -200.12162) (xy 6.845004 -200.168273) (xy 6.787784 -200.208873) (xy 6.726442 -200.242925)
			(xy 6.661724 -200.270016) (xy 6.594416 -200.289815) (xy 6.525337 -200.302083) (xy 6.455327 -200.30667)
			(xy 6.385238 -200.303521) (xy 6.350508 -200.298558) (xy 6.328776 -200.295601) (xy 6.284926 -200.296388)
			(xy 6.241863 -200.304691) (xy 6.200864 -200.320265) (xy 6.163149 -200.342647) (xy 6.129836 -200.371171)
			(xy 6.101915 -200.404992) (xy 6.080215 -200.443104) (xy 6.065381 -200.484376) (xy 6.057853 -200.527582)
			(xy 6.057392 -200.54951) (xy 6.057392 -202.791822) (xy 6.05786 -202.813748) (xy 6.065393 -202.856948)
			(xy 6.080229 -202.898214) (xy 6.10193 -202.936321) (xy 6.12985 -202.970136) (xy 6.163161 -202.998656)
			(xy 6.200874 -203.021033) (xy 6.241868 -203.036605) (xy 6.284927 -203.044907) (xy 6.328772 -203.045694)
			(xy 6.350508 -203.042774) (xy 6.385553 -203.037774) (xy 6.456278 -203.034665) (xy 6.526911 -203.039434)
			(xy 6.596576 -203.052024) (xy 6.66441 -203.072277) (xy 6.729573 -203.099943) (xy 6.791259 -203.13468)
			(xy 6.848701 -203.176057) (xy 6.90119 -203.223561) (xy 6.948074 -203.276603) (xy 6.988774 -203.334528)
			(xy 7.022784 -203.396617) (xy 7.049683 -203.462101) (xy 7.069139 -203.530168) (xy 7.080909 -203.599976)
			(xy 7.084849 -203.67066) (xy 7.080909 -203.741343) (xy 7.069139 -203.811151) (xy 7.049683 -203.879219)
			(xy 7.022784 -203.944703) (xy 6.988774 -204.006791) (xy 6.948075 -204.064716) (xy 6.90119 -204.117759)
			(xy 6.848702 -204.165263) (xy 6.791259 -204.20664) (xy 6.729574 -204.241376) (xy 6.664411 -204.269043)
			(xy 6.596576 -204.289296) (xy 6.526911 -204.301886) (xy 6.456279 -204.306655) (xy 6.385554 -204.303546)
			(xy 6.350508 -204.29855) (xy 6.328775 -204.295601) (xy 6.284926 -204.296388) (xy 6.241864 -204.304691)
			(xy 6.200866 -204.320264) (xy 6.163151 -204.342645) (xy 6.129838 -204.371169) (xy 6.101917 -204.404988)
			(xy 6.080217 -204.443099) (xy 6.065382 -204.484369) (xy 6.057853 -204.527574) (xy 6.057392 -204.549502)
			(xy 6.057392 -204.791818) (xy 6.057864 -204.813744) (xy 6.065395 -204.856944) (xy 6.080232 -204.89821)
			(xy 6.101932 -204.936317) (xy 6.129852 -204.970132) (xy 6.163162 -204.998652) (xy 6.200875 -205.021029)
			(xy 6.241869 -205.036601) (xy 6.284928 -205.044903) (xy 6.328772 -205.04569) (xy 6.350508 -205.04277)
			(xy 6.385554 -205.037778) (xy 6.456279 -205.034669) (xy 6.526911 -205.039438) (xy 6.596575 -205.052028)
			(xy 6.664409 -205.072281) (xy 6.729572 -205.099947) (xy 6.791257 -205.134684) (xy 6.848699 -205.17606)
			(xy 6.901188 -205.223564) (xy 6.948072 -205.276606) (xy 6.988771 -205.334531) (xy 7.022781 -205.396619)
			(xy 7.04968 -205.462103) (xy 7.069135 -205.53017) (xy 7.080905 -205.599977) (xy 7.084845 -205.67066)
			(xy 7.080905 -205.741343) (xy 7.069135 -205.811151) (xy 7.049679 -205.879218) (xy 7.02278 -205.944701)
			(xy 6.98877 -206.00679) (xy 6.948071 -206.064714) (xy 6.901187 -206.117757) (xy 6.848699 -206.16526)
			(xy 6.791256 -206.206637) (xy 6.729572 -206.241373) (xy 6.664409 -206.269039) (xy 6.596575 -206.289292)
			(xy 6.52691 -206.301882) (xy 6.456278 -206.306651) (xy 6.385554 -206.303542) (xy 6.350508 -206.298546)
			(xy 6.328775 -206.295601) (xy 6.284926 -206.296388) (xy 6.241864 -206.304691) (xy 6.200867 -206.320264)
			(xy 6.163152 -206.342644) (xy 6.12984 -206.371167) (xy 6.101919 -206.404986) (xy 6.080218 -206.443096)
			(xy 6.065383 -206.484366) (xy 6.057854 -206.52757) (xy 6.057392 -206.549498) (xy 6.057392 -206.791814)
			(xy 6.057868 -206.81374) (xy 6.065398 -206.85694) (xy 6.080234 -206.898206) (xy 6.101934 -206.936312)
			(xy 6.129853 -206.970128) (xy 6.163163 -206.998648) (xy 6.200875 -207.021025) (xy 6.241869 -207.036597)
			(xy 6.284928 -207.044899) (xy 6.328773 -207.045686) (xy 6.350508 -207.042766) (xy 6.385425 -207.03783)
			(xy 6.455877 -207.034704) (xy 6.526242 -207.039397) (xy 6.595655 -207.051851) (xy 6.663262 -207.071913)
			(xy 6.728233 -207.099335) (xy 6.789769 -207.133782) (xy 6.847113 -207.17483) (xy 6.89956 -207.221973)
			(xy 6.946466 -207.274633) (xy 6.987254 -207.332162) (xy 7.021422 -207.393853) (xy 7.048551 -207.458948)
			(xy 7.068307 -207.526645) (xy 7.080447 -207.596114) (xy 7.084821 -207.666499) (xy 7.081377 -207.736936)
			(xy 7.070156 -207.806559) (xy 7.051296 -207.874511) (xy 7.02503 -207.939958) (xy 6.991679 -208.002095)
			(xy 6.951655 -208.060158) (xy 6.905449 -208.113433) (xy 6.853629 -208.161265) (xy 6.796832 -208.203067)
			(xy 6.735757 -208.238323) (xy 6.671154 -208.266602) (xy 6.603817 -208.287555) (xy 6.534575 -208.300925)
			(xy 6.464278 -208.306547) (xy 6.393791 -208.304352) (xy 6.32398 -208.294367) (xy 6.255704 -208.276715)
			(xy 6.189802 -208.251613) (xy 6.127083 -208.21937) (xy 6.06832 -208.180382) (xy 6.014234 -208.135127)
			(xy 5.96549 -208.084164) (xy 5.922688 -208.028117) (xy 5.886354 -207.967676) (xy 5.87121 -207.93583)
			(xy 5.861509 -207.915799) (xy 5.83618 -207.879206) (xy 5.804865 -207.847584) (xy 5.768521 -207.8219)
			(xy 5.728259 -207.802938) (xy 5.68531 -207.791278) (xy 5.640987 -207.787276) (xy 5.596644 -207.791056)
			(xy 5.553637 -207.802501) (xy 5.51328 -207.821261) (xy 5.476808 -207.846764) (xy 5.460746 -207.86217)
			(xy 4.334256 -208.98866) (xy 2.568448 -208.98866) (xy 2.553356 -208.989076) (xy 2.524003 -208.996096)
			(xy 2.497125 -209.009826) (xy 2.474232 -209.029493) (xy 2.46507 -209.041492) (xy 2.443905 -209.070096)
			(xy 2.396188 -209.122885) (xy 2.342874 -209.170013) (xy 2.284628 -209.210891) (xy 2.222181 -209.245008)
			(xy 2.156314 -209.271935) (xy 2.087852 -209.291336) (xy 2.01765 -209.302968) (xy 1.946589 -209.306686)
			(xy 1.875557 -209.302443) (xy 1.805443 -209.290292) (xy 1.737126 -209.270385) (xy 1.67146 -209.242972)
			(xy 1.609267 -209.208395) (xy 1.551325 -209.167087) (xy 1.49836 -209.119566) (xy 1.451035 -209.066426)
			(xy 1.409942 -209.008332) (xy 1.375596 -208.946011) (xy 1.348425 -208.880244) (xy 1.328771 -208.811853)
			(xy 1.31688 -208.741696) (xy 1.3129 -208.670648) (xy 1.31688 -208.599601) (xy 1.328772 -208.529443)
			(xy 1.348426 -208.461053) (xy 1.375597 -208.395286) (xy 1.409944 -208.332965) (xy 1.451037 -208.274872)
			(xy 1.498363 -208.221732) (xy 1.551328 -208.174211) (xy 1.60927 -208.132903) (xy 1.671463 -208.098327)
			(xy 1.737129 -208.070914) (xy 1.805447 -208.051007) (xy 1.87556 -208.038857) (xy 1.946592 -208.034614)
			(xy 2.017654 -208.038332) (xy 2.087855 -208.049965) (xy 2.156317 -208.069366) (xy 2.222184 -208.096294)
			(xy 2.284631 -208.13041) (xy 2.342876 -208.171289) (xy 2.396191 -208.218418) (xy 2.443907 -208.271207)
			(xy 2.46507 -208.299812) (xy 2.474216 -208.311823) (xy 2.497121 -208.331483) (xy 2.524001 -208.345213)
			(xy 2.553355 -208.352245) (xy 2.568448 -208.352644) (xy 3.169158 -208.352644) (xy 3.191111 -208.352195)
			(xy 3.234366 -208.34466) (xy 3.275681 -208.329803) (xy 3.313828 -208.308066) (xy 3.347672 -208.280095)
			(xy 3.376203 -208.246723) (xy 3.398574 -208.208944) (xy 3.414119 -208.167882) (xy 3.422374 -208.12476)
			(xy 3.423094 -208.08086) (xy 3.416258 -208.037489) (xy 3.402069 -207.995939) (xy 3.391916 -207.97647)
			(xy 3.375282 -207.94515) (xy 3.348286 -207.87957) (xy 3.328759 -207.811391) (xy 3.316944 -207.741463)
			(xy 3.312989 -207.670654) (xy 3.316943 -207.599844) (xy 3.328757 -207.529916) (xy 3.348283 -207.461737)
			(xy 3.375279 -207.396157) (xy 3.391916 -207.364838) (xy 3.402007 -207.345342) (xy 3.416178 -207.3038)
			(xy 3.423002 -207.260441) (xy 3.422275 -207.216555) (xy 3.414018 -207.173446) (xy 3.398477 -207.132396)
			(xy 3.376115 -207.094627) (xy 3.347597 -207.061262) (xy 3.31377 -207.033292) (xy 3.27564 -207.01155)
			(xy 3.234342 -206.996683) (xy 3.191104 -206.989132) (xy 3.169158 -206.988664) (xy 2.568448 -206.988664)
			(xy 2.553356 -206.989078) (xy 2.524002 -206.996099) (xy 2.497125 -207.009829) (xy 2.474231 -207.029497)
			(xy 2.46507 -207.041496) (xy 2.443911 -207.070104) (xy 2.396194 -207.122894) (xy 2.34288 -207.170023)
			(xy 2.284634 -207.210902) (xy 2.222187 -207.245019) (xy 2.15632 -207.271946) (xy 2.087857 -207.291348)
			(xy 2.017656 -207.302981) (xy 1.946594 -207.3067) (xy 1.875561 -207.302457) (xy 1.805447 -207.290306)
			(xy 1.73713 -207.2704) (xy 1.671463 -207.242987) (xy 1.609269 -207.20841) (xy 1.551327 -207.167103)
			(xy 1.498361 -207.119582) (xy 1.451036 -207.066442) (xy 1.409942 -207.008348) (xy 1.375595 -206.946027)
			(xy 1.348424 -206.88026) (xy 1.328769 -206.811869) (xy 1.316877 -206.741711) (xy 1.312896 -206.670663)
			(xy 1.316876 -206.599616) (xy 1.328768 -206.529457) (xy 1.348422 -206.461066) (xy 1.375592 -206.395299)
			(xy 1.409939 -206.332978) (xy 1.451032 -206.274883) (xy 1.498357 -206.221743) (xy 1.551322 -206.174221)
			(xy 1.609264 -206.132913) (xy 1.671457 -206.098336) (xy 1.737123 -206.070922) (xy 1.805441 -206.051015)
			(xy 1.875555 -206.038864) (xy 1.946587 -206.03462) (xy 2.017649 -206.038338) (xy 2.087851 -206.04997)
			(xy 2.156314 -206.069371) (xy 2.222181 -206.096299) (xy 2.284629 -206.130415) (xy 2.342875 -206.171293)
			(xy 2.39619 -206.218422) (xy 2.443907 -206.271211) (xy 2.46507 -206.299816) (xy 2.474215 -206.311828)
			(xy 2.49712 -206.331487) (xy 2.524001 -206.345217) (xy 2.553355 -206.352249) (xy 2.568448 -206.352648)
			(xy 3.169158 -206.352648) (xy 3.191111 -206.352193) (xy 3.234365 -206.344658) (xy 3.27568 -206.329802)
			(xy 3.313826 -206.308065) (xy 3.347669 -206.280094) (xy 3.376201 -206.246723) (xy 3.398572 -206.208945)
			(xy 3.414116 -206.167884) (xy 3.422372 -206.124762) (xy 3.423093 -206.080863) (xy 3.416257 -206.037493)
			(xy 3.402069 -205.995943) (xy 3.391916 -205.976474) (xy 3.375376 -205.945388) (xy 3.348498 -205.880299)
			(xy 3.328986 -205.812637) (xy 3.31708 -205.743231) (xy 3.312927 -205.672934) (xy 3.316577 -205.60261)
			(xy 3.321812 -205.567788) (xy 3.321812 -205.567534) (xy 3.323728 -205.552637) (xy 3.321406 -205.5227)
			(xy 3.312176 -205.494127) (xy 3.296544 -205.46849) (xy 3.286252 -205.457552) (xy 2.929128 -205.100174)
			(xy 2.929128 -204.266038) (xy 2.438908 -204.266038) (xy 2.460992 -204.293537) (xy 2.499605 -204.35256)
			(xy 2.531446 -204.415496) (xy 2.556121 -204.48157) (xy 2.573329 -204.549971) (xy 2.582856 -204.619856)
			(xy 2.584586 -204.690366) (xy 2.578498 -204.760635) (xy 2.564667 -204.829797) (xy 2.543262 -204.897002)
			(xy 2.514547 -204.961424) (xy 2.478875 -205.02227) (xy 2.436685 -205.078791) (xy 2.388496 -205.130294)
			(xy 2.3349 -205.176143) (xy 2.276557 -205.215776) (xy 2.214184 -205.248705) (xy 2.148548 -205.274525)
			(xy 2.080457 -205.292917) (xy 2.010748 -205.303657) (xy 1.940278 -205.306612) (xy 1.869915 -205.301746)
			(xy 1.800523 -205.289118) (xy 1.732956 -205.268884) (xy 1.668045 -205.241292) (xy 1.606589 -205.206682)
			(xy 1.549343 -205.16548) (xy 1.497011 -205.118193) (xy 1.450237 -205.065402) (xy 1.409597 -205.007756)
			(xy 1.37559 -204.945964) (xy 1.348634 -204.880786) (xy 1.329061 -204.813025) (xy 1.317112 -204.743513)
			(xy 1.312934 -204.673105) (xy 1.316577 -204.602668) (xy 1.321816 -204.56779) (xy 1.323871 -204.552864)
			(xy 1.321634 -204.522825) (xy 1.31238 -204.494159) (xy 1.29663 -204.468481) (xy 1.286256 -204.457554)
			(xy 0.898652 -204.069696) (xy 0.509016 -204.069696) (xy 0.509016 -210.706309) (xy 1.313934 -210.706309)
			(xy 1.313934 -210.634987) (xy 1.32192 -210.564113) (xy 1.33779 -210.494578) (xy 1.361347 -210.427258)
			(xy 1.392292 -210.362999) (xy 1.430238 -210.302608) (xy 1.474707 -210.246846) (xy 1.52514 -210.196413)
			(xy 1.580902 -210.151944) (xy 1.641293 -210.113998) (xy 1.705552 -210.083053) (xy 1.772872 -210.059496)
			(xy 1.842407 -210.043626) (xy 1.913281 -210.03564) (xy 1.948942 -210.03514) (xy 1.984603 -210.03564)
			(xy 2.055477 -210.043626) (xy 2.125012 -210.059496) (xy 2.192332 -210.083053) (xy 2.256591 -210.113998)
			(xy 2.316982 -210.151944) (xy 2.372744 -210.196413) (xy 2.423177 -210.246846) (xy 2.467646 -210.302608)
			(xy 2.505592 -210.362999) (xy 2.536537 -210.427258) (xy 2.560094 -210.494578) (xy 2.575964 -210.564113)
			(xy 2.58395 -210.634987) (xy 2.58395 -210.706309) (xy 2.575964 -210.777183) (xy 2.560094 -210.846718)
			(xy 2.536537 -210.914038) (xy 2.505592 -210.978297) (xy 2.467646 -211.038688) (xy 2.423177 -211.09445)
			(xy 2.372744 -211.144883) (xy 2.316982 -211.189352) (xy 2.256591 -211.227298) (xy 2.192332 -211.258243)
			(xy 2.125012 -211.2818) (xy 2.055477 -211.29767) (xy 1.984603 -211.305656) (xy 1.913281 -211.305656)
			(xy 1.842407 -211.29767) (xy 1.772872 -211.2818) (xy 1.705552 -211.258243) (xy 1.641293 -211.227298)
			(xy 1.580902 -211.189352) (xy 1.52514 -211.144883) (xy 1.474707 -211.09445) (xy 1.430238 -211.038688)
			(xy 1.392292 -210.978297) (xy 1.361347 -210.914038) (xy 1.33779 -210.846718) (xy 1.32192 -210.777183)
			(xy 1.313934 -210.706309) (xy 0.509016 -210.706309) (xy 0.509016 -211.706307) (xy 3.31393 -211.706307)
			(xy 3.31393 -211.634985) (xy 3.321916 -211.564111) (xy 3.337786 -211.494576) (xy 3.361343 -211.427256)
			(xy 3.392288 -211.362997) (xy 3.430234 -211.302606) (xy 3.474703 -211.246844) (xy 3.525136 -211.196411)
			(xy 3.580898 -211.151942) (xy 3.641289 -211.113996) (xy 3.705548 -211.083051) (xy 3.772868 -211.059494)
			(xy 3.842403 -211.043624) (xy 3.913277 -211.035638) (xy 3.948938 -211.035138) (xy 3.984599 -211.035638)
			(xy 4.055473 -211.043624) (xy 4.125008 -211.059494) (xy 4.192328 -211.083051) (xy 4.256587 -211.113996)
			(xy 4.316978 -211.151942) (xy 4.37274 -211.196411) (xy 4.423173 -211.246844) (xy 4.467642 -211.302606)
			(xy 4.505588 -211.362997) (xy 4.536533 -211.427256) (xy 4.56009 -211.494576) (xy 4.57596 -211.564111)
			(xy 4.583946 -211.634985) (xy 4.583946 -211.706307) (xy 5.813798 -211.706307) (xy 5.813798 -211.634985)
			(xy 5.821784 -211.564111) (xy 5.837654 -211.494576) (xy 5.861211 -211.427256) (xy 5.892156 -211.362997)
			(xy 5.930102 -211.302606) (xy 5.974571 -211.246844) (xy 6.025004 -211.196411) (xy 6.080766 -211.151942)
			(xy 6.141157 -211.113996) (xy 6.205416 -211.083051) (xy 6.272736 -211.059494) (xy 6.342271 -211.043624)
			(xy 6.413145 -211.035638) (xy 6.448806 -211.035138) (xy 6.484467 -211.035638) (xy 6.555341 -211.043624)
			(xy 6.624876 -211.059494) (xy 6.692196 -211.083051) (xy 6.756455 -211.113996) (xy 6.816846 -211.151942)
			(xy 6.872608 -211.196411) (xy 6.923041 -211.246844) (xy 6.96751 -211.302606) (xy 7.005456 -211.362997)
			(xy 7.036401 -211.427256) (xy 7.059958 -211.494576) (xy 7.075828 -211.564111) (xy 7.083814 -211.634985)
			(xy 7.083814 -211.706307) (xy 7.075828 -211.777181) (xy 7.059958 -211.846716) (xy 7.036401 -211.914036)
			(xy 7.005456 -211.978295) (xy 6.96751 -212.038686) (xy 6.923041 -212.094448) (xy 6.872608 -212.144881)
			(xy 6.816846 -212.18935) (xy 6.756455 -212.227296) (xy 6.692196 -212.258241) (xy 6.624876 -212.281798)
			(xy 6.555341 -212.297668) (xy 6.484467 -212.305654) (xy 6.413145 -212.305654) (xy 6.342271 -212.297668)
			(xy 6.272736 -212.281798) (xy 6.205416 -212.258241) (xy 6.141157 -212.227296) (xy 6.080766 -212.18935)
			(xy 6.025004 -212.144881) (xy 5.974571 -212.094448) (xy 5.930102 -212.038686) (xy 5.892156 -211.978295)
			(xy 5.861211 -211.914036) (xy 5.837654 -211.846716) (xy 5.821784 -211.777181) (xy 5.813798 -211.706307)
			(xy 4.583946 -211.706307) (xy 4.57596 -211.777181) (xy 4.56009 -211.846716) (xy 4.536533 -211.914036)
			(xy 4.505588 -211.978295) (xy 4.467642 -212.038686) (xy 4.423173 -212.094448) (xy 4.37274 -212.144881)
			(xy 4.316978 -212.18935) (xy 4.256587 -212.227296) (xy 4.192328 -212.258241) (xy 4.125008 -212.281798)
			(xy 4.055473 -212.297668) (xy 3.984599 -212.305654) (xy 3.913277 -212.305654) (xy 3.842403 -212.297668)
			(xy 3.772868 -212.281798) (xy 3.705548 -212.258241) (xy 3.641289 -212.227296) (xy 3.580898 -212.18935)
			(xy 3.525136 -212.144881) (xy 3.474703 -212.094448) (xy 3.430234 -212.038686) (xy 3.392288 -211.978295)
			(xy 3.361343 -211.914036) (xy 3.337786 -211.846716) (xy 3.321916 -211.777181) (xy 3.31393 -211.706307)
			(xy 0.509016 -211.706307) (xy 0.509016 -212.706305) (xy 1.313934 -212.706305) (xy 1.313934 -212.634983)
			(xy 1.32192 -212.564109) (xy 1.33779 -212.494574) (xy 1.361347 -212.427254) (xy 1.392292 -212.362995)
			(xy 1.430238 -212.302604) (xy 1.474707 -212.246842) (xy 1.52514 -212.196409) (xy 1.580902 -212.15194)
			(xy 1.641293 -212.113994) (xy 1.705552 -212.083049) (xy 1.772872 -212.059492) (xy 1.842407 -212.043622)
			(xy 1.913281 -212.035636) (xy 1.948942 -212.035136) (xy 1.984603 -212.035636) (xy 2.055477 -212.043622)
			(xy 2.125012 -212.059492) (xy 2.192332 -212.083049) (xy 2.256591 -212.113994) (xy 2.316982 -212.15194)
			(xy 2.372744 -212.196409) (xy 2.423177 -212.246842) (xy 2.467646 -212.302604) (xy 2.505592 -212.362995)
			(xy 2.536537 -212.427254) (xy 2.560094 -212.494574) (xy 2.575964 -212.564109) (xy 2.58395 -212.634983)
			(xy 2.58395 -212.706305) (xy 2.575964 -212.777179) (xy 2.560094 -212.846714) (xy 2.536537 -212.914034)
			(xy 2.505592 -212.978293) (xy 2.467646 -213.038684) (xy 2.423177 -213.094446) (xy 2.372744 -213.144879)
			(xy 2.316982 -213.189348) (xy 2.256591 -213.227294) (xy 2.192332 -213.258239) (xy 2.125012 -213.281796)
			(xy 2.055477 -213.297666) (xy 1.984603 -213.305652) (xy 1.913281 -213.305652) (xy 1.842407 -213.297666)
			(xy 1.772872 -213.281796) (xy 1.705552 -213.258239) (xy 1.641293 -213.227294) (xy 1.580902 -213.189348)
			(xy 1.52514 -213.144879) (xy 1.474707 -213.094446) (xy 1.430238 -213.038684) (xy 1.392292 -212.978293)
			(xy 1.361347 -212.914034) (xy 1.33779 -212.846714) (xy 1.32192 -212.777179) (xy 1.313934 -212.706305)
			(xy 0.509016 -212.706305) (xy 0.509016 -213.706303) (xy 3.31393 -213.706303) (xy 3.31393 -213.634981)
			(xy 3.321916 -213.564107) (xy 3.337786 -213.494572) (xy 3.361343 -213.427252) (xy 3.392288 -213.362993)
			(xy 3.430234 -213.302602) (xy 3.474703 -213.24684) (xy 3.525136 -213.196407) (xy 3.580898 -213.151938)
			(xy 3.641289 -213.113992) (xy 3.705548 -213.083047) (xy 3.772868 -213.05949) (xy 3.842403 -213.04362)
			(xy 3.913277 -213.035634) (xy 3.948938 -213.035134) (xy 3.984599 -213.035634) (xy 4.055473 -213.04362)
			(xy 4.125008 -213.05949) (xy 4.192328 -213.083047) (xy 4.256587 -213.113992) (xy 4.316978 -213.151938)
			(xy 4.37274 -213.196407) (xy 4.423173 -213.24684) (xy 4.467642 -213.302602) (xy 4.505588 -213.362993)
			(xy 4.536533 -213.427252) (xy 4.56009 -213.494572) (xy 4.57596 -213.564107) (xy 4.583946 -213.634981)
			(xy 4.583946 -213.706303) (xy 5.813798 -213.706303) (xy 5.813798 -213.634981) (xy 5.821784 -213.564107)
			(xy 5.837654 -213.494572) (xy 5.861211 -213.427252) (xy 5.892156 -213.362993) (xy 5.930102 -213.302602)
			(xy 5.974571 -213.24684) (xy 6.025004 -213.196407) (xy 6.080766 -213.151938) (xy 6.141157 -213.113992)
			(xy 6.205416 -213.083047) (xy 6.272736 -213.05949) (xy 6.342271 -213.04362) (xy 6.413145 -213.035634)
			(xy 6.448806 -213.035134) (xy 6.484467 -213.035634) (xy 6.555341 -213.04362) (xy 6.624876 -213.05949)
			(xy 6.692196 -213.083047) (xy 6.756455 -213.113992) (xy 6.816846 -213.151938) (xy 6.872608 -213.196407)
			(xy 6.923041 -213.24684) (xy 6.96751 -213.302602) (xy 7.005456 -213.362993) (xy 7.036401 -213.427252)
			(xy 7.059958 -213.494572) (xy 7.075828 -213.564107) (xy 7.083814 -213.634981) (xy 7.083814 -213.706303)
			(xy 7.075828 -213.777177) (xy 7.059958 -213.846712) (xy 7.036401 -213.914032) (xy 7.005456 -213.978291)
			(xy 6.96751 -214.038682) (xy 6.923041 -214.094444) (xy 6.872608 -214.144877) (xy 6.816846 -214.189346)
			(xy 6.756455 -214.227292) (xy 6.692196 -214.258237) (xy 6.624876 -214.281794) (xy 6.555341 -214.297664)
			(xy 6.484467 -214.30565) (xy 6.413145 -214.30565) (xy 6.342271 -214.297664) (xy 6.272736 -214.281794)
			(xy 6.205416 -214.258237) (xy 6.141157 -214.227292) (xy 6.080766 -214.189346) (xy 6.025004 -214.144877)
			(xy 5.974571 -214.094444) (xy 5.930102 -214.038682) (xy 5.892156 -213.978291) (xy 5.861211 -213.914032)
			(xy 5.837654 -213.846712) (xy 5.821784 -213.777177) (xy 5.813798 -213.706303) (xy 4.583946 -213.706303)
			(xy 4.57596 -213.777177) (xy 4.56009 -213.846712) (xy 4.536533 -213.914032) (xy 4.505588 -213.978291)
			(xy 4.467642 -214.038682) (xy 4.423173 -214.094444) (xy 4.37274 -214.144877) (xy 4.316978 -214.189346)
			(xy 4.256587 -214.227292) (xy 4.192328 -214.258237) (xy 4.125008 -214.281794) (xy 4.055473 -214.297664)
			(xy 3.984599 -214.30565) (xy 3.913277 -214.30565) (xy 3.842403 -214.297664) (xy 3.772868 -214.281794)
			(xy 3.705548 -214.258237) (xy 3.641289 -214.227292) (xy 3.580898 -214.189346) (xy 3.525136 -214.144877)
			(xy 3.474703 -214.094444) (xy 3.430234 -214.038682) (xy 3.392288 -213.978291) (xy 3.361343 -213.914032)
			(xy 3.337786 -213.846712) (xy 3.321916 -213.777177) (xy 3.31393 -213.706303) (xy 0.509016 -213.706303)
			(xy 0.509016 -214.706301) (xy 1.313934 -214.706301) (xy 1.313934 -214.634979) (xy 1.32192 -214.564105)
			(xy 1.33779 -214.49457) (xy 1.361347 -214.42725) (xy 1.392292 -214.362991) (xy 1.430238 -214.3026)
			(xy 1.474707 -214.246838) (xy 1.52514 -214.196405) (xy 1.580902 -214.151936) (xy 1.641293 -214.11399)
			(xy 1.705552 -214.083045) (xy 1.772872 -214.059488) (xy 1.842407 -214.043618) (xy 1.913281 -214.035632)
			(xy 1.948942 -214.035132) (xy 1.984603 -214.035632) (xy 2.055477 -214.043618) (xy 2.125012 -214.059488)
			(xy 2.192332 -214.083045) (xy 2.256591 -214.11399) (xy 2.316982 -214.151936) (xy 2.372744 -214.196405)
			(xy 2.423177 -214.246838) (xy 2.467646 -214.3026) (xy 2.505592 -214.362991) (xy 2.536537 -214.42725)
			(xy 2.560094 -214.49457) (xy 2.575964 -214.564105) (xy 2.58395 -214.634979) (xy 2.58395 -214.706301)
			(xy 2.575964 -214.777175) (xy 2.560094 -214.84671) (xy 2.536537 -214.91403) (xy 2.505592 -214.978289)
			(xy 2.467646 -215.03868) (xy 2.423177 -215.094442) (xy 2.372744 -215.144875) (xy 2.316982 -215.189344)
			(xy 2.256591 -215.22729) (xy 2.192332 -215.258235) (xy 2.125012 -215.281792) (xy 2.055477 -215.297662)
			(xy 1.984603 -215.305648) (xy 1.913281 -215.305648) (xy 1.842407 -215.297662) (xy 1.772872 -215.281792)
			(xy 1.705552 -215.258235) (xy 1.641293 -215.22729) (xy 1.580902 -215.189344) (xy 1.52514 -215.144875)
			(xy 1.474707 -215.094442) (xy 1.430238 -215.03868) (xy 1.392292 -214.978289) (xy 1.361347 -214.91403)
			(xy 1.33779 -214.84671) (xy 1.32192 -214.777175) (xy 1.313934 -214.706301) (xy 0.509016 -214.706301)
			(xy 0.509016 -215.706299) (xy 3.31393 -215.706299) (xy 3.31393 -215.634977) (xy 3.321916 -215.564103)
			(xy 3.337786 -215.494568) (xy 3.361343 -215.427248) (xy 3.392288 -215.362989) (xy 3.430234 -215.302598)
			(xy 3.474703 -215.246836) (xy 3.525136 -215.196403) (xy 3.580898 -215.151934) (xy 3.641289 -215.113988)
			(xy 3.705548 -215.083043) (xy 3.772868 -215.059486) (xy 3.842403 -215.043616) (xy 3.913277 -215.03563)
			(xy 3.948938 -215.03513) (xy 3.984599 -215.03563) (xy 4.055473 -215.043616) (xy 4.125008 -215.059486)
			(xy 4.192328 -215.083043) (xy 4.256587 -215.113988) (xy 4.316978 -215.151934) (xy 4.37274 -215.196403)
			(xy 4.423173 -215.246836) (xy 4.467642 -215.302598) (xy 4.505588 -215.362989) (xy 4.536533 -215.427248)
			(xy 4.56009 -215.494568) (xy 4.57596 -215.564103) (xy 4.583946 -215.634977) (xy 4.583946 -215.706299)
			(xy 5.813798 -215.706299) (xy 5.813798 -215.634977) (xy 5.821784 -215.564103) (xy 5.837654 -215.494568)
			(xy 5.861211 -215.427248) (xy 5.892156 -215.362989) (xy 5.930102 -215.302598) (xy 5.974571 -215.246836)
			(xy 6.025004 -215.196403) (xy 6.080766 -215.151934) (xy 6.141157 -215.113988) (xy 6.205416 -215.083043)
			(xy 6.272736 -215.059486) (xy 6.342271 -215.043616) (xy 6.413145 -215.03563) (xy 6.448806 -215.03513)
			(xy 6.484467 -215.03563) (xy 6.555341 -215.043616) (xy 6.624876 -215.059486) (xy 6.692196 -215.083043)
			(xy 6.756455 -215.113988) (xy 6.816846 -215.151934) (xy 6.872608 -215.196403) (xy 6.923041 -215.246836)
			(xy 6.96751 -215.302598) (xy 7.005456 -215.362989) (xy 7.036401 -215.427248) (xy 7.059958 -215.494568)
			(xy 7.075828 -215.564103) (xy 7.083814 -215.634977) (xy 7.083814 -215.706299) (xy 7.075828 -215.777173)
			(xy 7.059958 -215.846708) (xy 7.036401 -215.914028) (xy 7.005456 -215.978287) (xy 6.96751 -216.038678)
			(xy 6.923041 -216.09444) (xy 6.872608 -216.144873) (xy 6.816846 -216.189342) (xy 6.756455 -216.227288)
			(xy 6.692196 -216.258233) (xy 6.624876 -216.28179) (xy 6.555341 -216.29766) (xy 6.484467 -216.305646)
			(xy 6.413145 -216.305646) (xy 6.342271 -216.29766) (xy 6.272736 -216.28179) (xy 6.205416 -216.258233)
			(xy 6.141157 -216.227288) (xy 6.080766 -216.189342) (xy 6.025004 -216.144873) (xy 5.974571 -216.09444)
			(xy 5.930102 -216.038678) (xy 5.892156 -215.978287) (xy 5.861211 -215.914028) (xy 5.837654 -215.846708)
			(xy 5.821784 -215.777173) (xy 5.813798 -215.706299) (xy 4.583946 -215.706299) (xy 4.57596 -215.777173)
			(xy 4.56009 -215.846708) (xy 4.536533 -215.914028) (xy 4.505588 -215.978287) (xy 4.467642 -216.038678)
			(xy 4.423173 -216.09444) (xy 4.37274 -216.144873) (xy 4.316978 -216.189342) (xy 4.256587 -216.227288)
			(xy 4.192328 -216.258233) (xy 4.125008 -216.28179) (xy 4.055473 -216.29766) (xy 3.984599 -216.305646)
			(xy 3.913277 -216.305646) (xy 3.842403 -216.29766) (xy 3.772868 -216.28179) (xy 3.705548 -216.258233)
			(xy 3.641289 -216.227288) (xy 3.580898 -216.189342) (xy 3.525136 -216.144873) (xy 3.474703 -216.09444)
			(xy 3.430234 -216.038678) (xy 3.392288 -215.978287) (xy 3.361343 -215.914028) (xy 3.337786 -215.846708)
			(xy 3.321916 -215.777173) (xy 3.31393 -215.706299) (xy 0.509016 -215.706299) (xy 0.509016 -217.706295)
			(xy 3.31393 -217.706295) (xy 3.31393 -217.634973) (xy 3.321916 -217.564099) (xy 3.337786 -217.494564)
			(xy 3.361343 -217.427244) (xy 3.392288 -217.362985) (xy 3.430234 -217.302594) (xy 3.474703 -217.246832)
			(xy 3.525136 -217.196399) (xy 3.580898 -217.15193) (xy 3.641289 -217.113984) (xy 3.705548 -217.083039)
			(xy 3.772868 -217.059482) (xy 3.842403 -217.043612) (xy 3.913277 -217.035626) (xy 3.948938 -217.035126)
			(xy 3.984599 -217.035626) (xy 4.055473 -217.043612) (xy 4.125008 -217.059482) (xy 4.192328 -217.083039)
			(xy 4.256587 -217.113984) (xy 4.316978 -217.15193) (xy 4.37274 -217.196399) (xy 4.423173 -217.246832)
			(xy 4.467642 -217.302594) (xy 4.505588 -217.362985) (xy 4.536533 -217.427244) (xy 4.56009 -217.494564)
			(xy 4.57596 -217.564099) (xy 4.583946 -217.634973) (xy 4.583946 -217.706295) (xy 5.813798 -217.706295)
			(xy 5.813798 -217.634973) (xy 5.821784 -217.564099) (xy 5.837654 -217.494564) (xy 5.861211 -217.427244)
			(xy 5.892156 -217.362985) (xy 5.930102 -217.302594) (xy 5.974571 -217.246832) (xy 6.025004 -217.196399)
			(xy 6.080766 -217.15193) (xy 6.141157 -217.113984) (xy 6.205416 -217.083039) (xy 6.272736 -217.059482)
			(xy 6.342271 -217.043612) (xy 6.413145 -217.035626) (xy 6.448806 -217.035126) (xy 6.484467 -217.035626)
			(xy 6.555341 -217.043612) (xy 6.624876 -217.059482) (xy 6.692196 -217.083039) (xy 6.756455 -217.113984)
			(xy 6.816846 -217.15193) (xy 6.872608 -217.196399) (xy 6.923041 -217.246832) (xy 6.96751 -217.302594)
			(xy 7.005456 -217.362985) (xy 7.036401 -217.427244) (xy 7.059958 -217.494564) (xy 7.075828 -217.564099)
			(xy 7.083814 -217.634973) (xy 7.083814 -217.706295) (xy 7.075828 -217.777169) (xy 7.059958 -217.846704)
			(xy 7.036401 -217.914024) (xy 7.005456 -217.978283) (xy 6.96751 -218.038674) (xy 6.923041 -218.094436)
			(xy 6.872608 -218.144869) (xy 6.816846 -218.189338) (xy 6.756455 -218.227284) (xy 6.692196 -218.258229)
			(xy 6.624876 -218.281786) (xy 6.555341 -218.297656) (xy 6.484467 -218.305642) (xy 6.413145 -218.305642)
			(xy 6.342271 -218.297656) (xy 6.272736 -218.281786) (xy 6.205416 -218.258229) (xy 6.141157 -218.227284)
			(xy 6.080766 -218.189338) (xy 6.025004 -218.144869) (xy 5.974571 -218.094436) (xy 5.930102 -218.038674)
			(xy 5.892156 -217.978283) (xy 5.861211 -217.914024) (xy 5.837654 -217.846704) (xy 5.821784 -217.777169)
			(xy 5.813798 -217.706295) (xy 4.583946 -217.706295) (xy 4.57596 -217.777169) (xy 4.56009 -217.846704)
			(xy 4.536533 -217.914024) (xy 4.505588 -217.978283) (xy 4.467642 -218.038674) (xy 4.423173 -218.094436)
			(xy 4.37274 -218.144869) (xy 4.316978 -218.189338) (xy 4.256587 -218.227284) (xy 4.192328 -218.258229)
			(xy 4.125008 -218.281786) (xy 4.055473 -218.297656) (xy 3.984599 -218.305642) (xy 3.913277 -218.305642)
			(xy 3.842403 -218.297656) (xy 3.772868 -218.281786) (xy 3.705548 -218.258229) (xy 3.641289 -218.227284)
			(xy 3.580898 -218.189338) (xy 3.525136 -218.144869) (xy 3.474703 -218.094436) (xy 3.430234 -218.038674)
			(xy 3.392288 -217.978283) (xy 3.361343 -217.914024) (xy 3.337786 -217.846704) (xy 3.321916 -217.777169)
			(xy 3.31393 -217.706295) (xy 0.509016 -217.706295) (xy 0.509016 -218.706293) (xy 1.313934 -218.706293)
			(xy 1.313934 -218.634971) (xy 1.32192 -218.564097) (xy 1.33779 -218.494562) (xy 1.361347 -218.427242)
			(xy 1.392292 -218.362983) (xy 1.430238 -218.302592) (xy 1.474707 -218.24683) (xy 1.52514 -218.196397)
			(xy 1.580902 -218.151928) (xy 1.641293 -218.113982) (xy 1.705552 -218.083037) (xy 1.772872 -218.05948)
			(xy 1.842407 -218.04361) (xy 1.913281 -218.035624) (xy 1.948942 -218.035124) (xy 1.984603 -218.035624)
			(xy 2.055477 -218.04361) (xy 2.125012 -218.05948) (xy 2.192332 -218.083037) (xy 2.256591 -218.113982)
			(xy 2.316982 -218.151928) (xy 2.372744 -218.196397) (xy 2.423177 -218.24683) (xy 2.467646 -218.302592)
			(xy 2.505592 -218.362983) (xy 2.536537 -218.427242) (xy 2.560094 -218.494562) (xy 2.575964 -218.564097)
			(xy 2.58395 -218.634971) (xy 2.58395 -218.706293) (xy 2.575964 -218.777167) (xy 2.560094 -218.846702)
			(xy 2.536537 -218.914022) (xy 2.505592 -218.978281) (xy 2.467646 -219.038672) (xy 2.423177 -219.094434)
			(xy 2.372744 -219.144867) (xy 2.316982 -219.189336) (xy 2.256591 -219.227282) (xy 2.192332 -219.258227)
			(xy 2.125012 -219.281784) (xy 2.055477 -219.297654) (xy 1.984603 -219.30564) (xy 1.913281 -219.30564)
			(xy 1.842407 -219.297654) (xy 1.772872 -219.281784) (xy 1.705552 -219.258227) (xy 1.641293 -219.227282)
			(xy 1.580902 -219.189336) (xy 1.52514 -219.144867) (xy 1.474707 -219.094434) (xy 1.430238 -219.038672)
			(xy 1.392292 -218.978281) (xy 1.361347 -218.914022) (xy 1.33779 -218.846702) (xy 1.32192 -218.777167)
			(xy 1.313934 -218.706293) (xy 0.509016 -218.706293) (xy 0.509016 -227.706275) (xy 3.31393 -227.706275)
			(xy 3.31393 -227.634953) (xy 3.321916 -227.564079) (xy 3.337786 -227.494544) (xy 3.361343 -227.427224)
			(xy 3.392288 -227.362965) (xy 3.430234 -227.302574) (xy 3.474703 -227.246812) (xy 3.525136 -227.196379)
			(xy 3.580898 -227.15191) (xy 3.641289 -227.113964) (xy 3.705548 -227.083019) (xy 3.772868 -227.059462)
			(xy 3.842403 -227.043592) (xy 3.913277 -227.035606) (xy 3.948938 -227.035106) (xy 3.984599 -227.035606)
			(xy 4.055473 -227.043592) (xy 4.125008 -227.059462) (xy 4.192328 -227.083019) (xy 4.256587 -227.113964)
			(xy 4.316978 -227.15191) (xy 4.37274 -227.196379) (xy 4.423173 -227.246812) (xy 4.467642 -227.302574)
			(xy 4.505588 -227.362965) (xy 4.536533 -227.427224) (xy 4.56009 -227.494544) (xy 4.57596 -227.564079)
			(xy 4.583946 -227.634953) (xy 4.583946 -227.706275) (xy 4.57596 -227.777149) (xy 4.56009 -227.846684)
			(xy 4.536533 -227.914004) (xy 4.505588 -227.978263) (xy 4.467642 -228.038654) (xy 4.423173 -228.094416)
			(xy 4.37274 -228.144849) (xy 4.316978 -228.189318) (xy 4.256587 -228.227264) (xy 4.192328 -228.258209)
			(xy 4.125008 -228.281766) (xy 4.055473 -228.297636) (xy 3.984599 -228.305622) (xy 3.913277 -228.305622)
			(xy 3.842403 -228.297636) (xy 3.772868 -228.281766) (xy 3.705548 -228.258209) (xy 3.641289 -228.227264)
			(xy 3.580898 -228.189318) (xy 3.525136 -228.144849) (xy 3.474703 -228.094416) (xy 3.430234 -228.038654)
			(xy 3.392288 -227.978263) (xy 3.361343 -227.914004) (xy 3.337786 -227.846684) (xy 3.321916 -227.777149)
			(xy 3.31393 -227.706275) (xy 0.509016 -227.706275) (xy 0.509016 -228.706273) (xy 1.313934 -228.706273)
			(xy 1.313934 -228.634951) (xy 1.32192 -228.564077) (xy 1.33779 -228.494542) (xy 1.361347 -228.427222)
			(xy 1.392292 -228.362963) (xy 1.430238 -228.302572) (xy 1.474707 -228.24681) (xy 1.52514 -228.196377)
			(xy 1.580902 -228.151908) (xy 1.641293 -228.113962) (xy 1.705552 -228.083017) (xy 1.772872 -228.05946)
			(xy 1.842407 -228.04359) (xy 1.913281 -228.035604) (xy 1.948942 -228.035104) (xy 1.984603 -228.035604)
			(xy 2.055477 -228.04359) (xy 2.125012 -228.05946) (xy 2.192332 -228.083017) (xy 2.256591 -228.113962)
			(xy 2.316982 -228.151908) (xy 2.372744 -228.196377) (xy 2.423177 -228.24681) (xy 2.467646 -228.302572)
			(xy 2.505592 -228.362963) (xy 2.536537 -228.427222) (xy 2.560094 -228.494542) (xy 2.575964 -228.564077)
			(xy 2.58395 -228.634951) (xy 2.58395 -228.706273) (xy 2.575964 -228.777147) (xy 2.560094 -228.846682)
			(xy 2.536537 -228.914002) (xy 2.505592 -228.978261) (xy 2.467646 -229.038652) (xy 2.423177 -229.094414)
			(xy 2.372744 -229.144847) (xy 2.316982 -229.189316) (xy 2.256591 -229.227262) (xy 2.192332 -229.258207)
			(xy 2.125012 -229.281764) (xy 2.055477 -229.297634) (xy 1.984603 -229.30562) (xy 1.913281 -229.30562)
			(xy 1.842407 -229.297634) (xy 1.772872 -229.281764) (xy 1.705552 -229.258207) (xy 1.641293 -229.227262)
			(xy 1.580902 -229.189316) (xy 1.52514 -229.144847) (xy 1.474707 -229.094414) (xy 1.430238 -229.038652)
			(xy 1.392292 -228.978261) (xy 1.361347 -228.914002) (xy 1.33779 -228.846682) (xy 1.32192 -228.777147)
			(xy 1.313934 -228.706273) (xy 0.509016 -228.706273) (xy 0.509016 -230.706269) (xy 1.313934 -230.706269)
			(xy 1.313934 -230.634947) (xy 1.32192 -230.564073) (xy 1.33779 -230.494538) (xy 1.361347 -230.427218)
			(xy 1.392292 -230.362959) (xy 1.430238 -230.302568) (xy 1.474707 -230.246806) (xy 1.52514 -230.196373)
			(xy 1.580902 -230.151904) (xy 1.641293 -230.113958) (xy 1.705552 -230.083013) (xy 1.772872 -230.059456)
			(xy 1.842407 -230.043586) (xy 1.913281 -230.0356) (xy 1.948942 -230.0351) (xy 1.984603 -230.0356)
			(xy 2.055477 -230.043586) (xy 2.125012 -230.059456) (xy 2.192332 -230.083013) (xy 2.256591 -230.113958)
			(xy 2.316982 -230.151904) (xy 2.372744 -230.196373) (xy 2.423177 -230.246806) (xy 2.467646 -230.302568)
			(xy 2.505592 -230.362959) (xy 2.536537 -230.427218) (xy 2.560094 -230.494538) (xy 2.575964 -230.564073)
			(xy 2.58395 -230.634947) (xy 2.58395 -230.706269) (xy 2.575964 -230.777143) (xy 2.560094 -230.846678)
			(xy 2.536537 -230.913998) (xy 2.505592 -230.978257) (xy 2.467646 -231.038648) (xy 2.423177 -231.09441)
			(xy 2.372744 -231.144843) (xy 2.316982 -231.189312) (xy 2.256591 -231.227258) (xy 2.192332 -231.258203)
			(xy 2.125012 -231.28176) (xy 2.055477 -231.29763) (xy 1.984603 -231.305616) (xy 1.913281 -231.305616)
			(xy 1.842407 -231.29763) (xy 1.772872 -231.28176) (xy 1.705552 -231.258203) (xy 1.641293 -231.227258)
			(xy 1.580902 -231.189312) (xy 1.52514 -231.144843) (xy 1.474707 -231.09441) (xy 1.430238 -231.038648)
			(xy 1.392292 -230.978257) (xy 1.361347 -230.913998) (xy 1.33779 -230.846678) (xy 1.32192 -230.777143)
			(xy 1.313934 -230.706269) (xy 0.509016 -230.706269) (xy 0.509016 -231.706267) (xy 3.31393 -231.706267)
			(xy 3.31393 -231.634945) (xy 3.321916 -231.564071) (xy 3.337786 -231.494536) (xy 3.361343 -231.427216)
			(xy 3.392288 -231.362957) (xy 3.430234 -231.302566) (xy 3.474703 -231.246804) (xy 3.525136 -231.196371)
			(xy 3.580898 -231.151902) (xy 3.641289 -231.113956) (xy 3.705548 -231.083011) (xy 3.772868 -231.059454)
			(xy 3.842403 -231.043584) (xy 3.913277 -231.035598) (xy 3.948938 -231.035098) (xy 3.984599 -231.035598)
			(xy 4.055473 -231.043584) (xy 4.125008 -231.059454) (xy 4.192328 -231.083011) (xy 4.256587 -231.113956)
			(xy 4.316978 -231.151902) (xy 4.37274 -231.196371) (xy 4.423173 -231.246804) (xy 4.467642 -231.302566)
			(xy 4.505588 -231.362957) (xy 4.536533 -231.427216) (xy 4.56009 -231.494536) (xy 4.57596 -231.564071)
			(xy 4.583946 -231.634945) (xy 4.583946 -231.706267) (xy 4.57596 -231.777141) (xy 4.56009 -231.846676)
			(xy 4.536533 -231.913996) (xy 4.505588 -231.978255) (xy 4.467642 -232.038646) (xy 4.423173 -232.094408)
			(xy 4.37274 -232.144841) (xy 4.316978 -232.18931) (xy 4.256587 -232.227256) (xy 4.192328 -232.258201)
			(xy 4.125008 -232.281758) (xy 4.055473 -232.297628) (xy 3.984599 -232.305614) (xy 3.913277 -232.305614)
			(xy 3.842403 -232.297628) (xy 3.772868 -232.281758) (xy 3.705548 -232.258201) (xy 3.641289 -232.227256)
			(xy 3.580898 -232.18931) (xy 3.525136 -232.144841) (xy 3.474703 -232.094408) (xy 3.430234 -232.038646)
			(xy 3.392288 -231.978255) (xy 3.361343 -231.913996) (xy 3.337786 -231.846676) (xy 3.321916 -231.777141)
			(xy 3.31393 -231.706267) (xy 0.509016 -231.706267) (xy 0.509016 -232.706265) (xy 1.313934 -232.706265)
			(xy 1.313934 -232.634943) (xy 1.32192 -232.564069) (xy 1.33779 -232.494534) (xy 1.361347 -232.427214)
			(xy 1.392292 -232.362955) (xy 1.430238 -232.302564) (xy 1.474707 -232.246802) (xy 1.52514 -232.196369)
			(xy 1.580902 -232.1519) (xy 1.641293 -232.113954) (xy 1.705552 -232.083009) (xy 1.772872 -232.059452)
			(xy 1.842407 -232.043582) (xy 1.913281 -232.035596) (xy 1.948942 -232.035096) (xy 1.984603 -232.035596)
			(xy 2.055477 -232.043582) (xy 2.125012 -232.059452) (xy 2.192332 -232.083009) (xy 2.256591 -232.113954)
			(xy 2.316982 -232.1519) (xy 2.372744 -232.196369) (xy 2.423177 -232.246802) (xy 2.467646 -232.302564)
			(xy 2.505592 -232.362955) (xy 2.536537 -232.427214) (xy 2.560094 -232.494534) (xy 2.575964 -232.564069)
			(xy 2.58395 -232.634943) (xy 2.58395 -232.706265) (xy 2.575964 -232.777139) (xy 2.560094 -232.846674)
			(xy 2.536537 -232.913994) (xy 2.505592 -232.978253) (xy 2.467646 -233.038644) (xy 2.423177 -233.094406)
			(xy 2.372744 -233.144839) (xy 2.316982 -233.189308) (xy 2.256591 -233.227254) (xy 2.192332 -233.258199)
			(xy 2.125012 -233.281756) (xy 2.055477 -233.297626) (xy 1.984603 -233.305612) (xy 1.913281 -233.305612)
			(xy 1.842407 -233.297626) (xy 1.772872 -233.281756) (xy 1.705552 -233.258199) (xy 1.641293 -233.227254)
			(xy 1.580902 -233.189308) (xy 1.52514 -233.144839) (xy 1.474707 -233.094406) (xy 1.430238 -233.038644)
			(xy 1.392292 -232.978253) (xy 1.361347 -232.913994) (xy 1.33779 -232.846674) (xy 1.32192 -232.777139)
			(xy 1.313934 -232.706265) (xy 0.509016 -232.706265) (xy 0.509016 -233.706263) (xy 3.31393 -233.706263)
			(xy 3.31393 -233.634941) (xy 3.321916 -233.564067) (xy 3.337786 -233.494532) (xy 3.361343 -233.427212)
			(xy 3.392288 -233.362953) (xy 3.430234 -233.302562) (xy 3.474703 -233.2468) (xy 3.525136 -233.196367)
			(xy 3.580898 -233.151898) (xy 3.641289 -233.113952) (xy 3.705548 -233.083007) (xy 3.772868 -233.05945)
			(xy 3.842403 -233.04358) (xy 3.913277 -233.035594) (xy 3.948938 -233.035094) (xy 3.984599 -233.035594)
			(xy 4.055473 -233.04358) (xy 4.125008 -233.05945) (xy 4.192328 -233.083007) (xy 4.256587 -233.113952)
			(xy 4.316978 -233.151898) (xy 4.37274 -233.196367) (xy 4.423173 -233.2468) (xy 4.467642 -233.302562)
			(xy 4.505588 -233.362953) (xy 4.536533 -233.427212) (xy 4.56009 -233.494532) (xy 4.57596 -233.564067)
			(xy 4.583946 -233.634941) (xy 4.583946 -233.706263) (xy 4.57596 -233.777137) (xy 4.56009 -233.846672)
			(xy 4.536533 -233.913992) (xy 4.505588 -233.978251) (xy 4.467642 -234.038642) (xy 4.423173 -234.094404)
			(xy 4.37274 -234.144837) (xy 4.316978 -234.189306) (xy 4.256587 -234.227252) (xy 4.192328 -234.258197)
			(xy 4.125008 -234.281754) (xy 4.055473 -234.297624) (xy 3.984599 -234.30561) (xy 3.913277 -234.30561)
			(xy 3.842403 -234.297624) (xy 3.772868 -234.281754) (xy 3.705548 -234.258197) (xy 3.641289 -234.227252)
			(xy 3.580898 -234.189306) (xy 3.525136 -234.144837) (xy 3.474703 -234.094404) (xy 3.430234 -234.038642)
			(xy 3.392288 -233.978251) (xy 3.361343 -233.913992) (xy 3.337786 -233.846672) (xy 3.321916 -233.777137)
			(xy 3.31393 -233.706263) (xy 0.509016 -233.706263) (xy 0.509016 -242.706245) (xy 1.313934 -242.706245)
			(xy 1.313934 -242.634923) (xy 1.32192 -242.564049) (xy 1.33779 -242.494514) (xy 1.361347 -242.427194)
			(xy 1.392292 -242.362935) (xy 1.430238 -242.302544) (xy 1.474707 -242.246782) (xy 1.52514 -242.196349)
			(xy 1.580902 -242.15188) (xy 1.641293 -242.113934) (xy 1.705552 -242.082989) (xy 1.772872 -242.059432)
			(xy 1.842407 -242.043562) (xy 1.913281 -242.035576) (xy 1.948942 -242.035076) (xy 1.984603 -242.035576)
			(xy 2.055477 -242.043562) (xy 2.125012 -242.059432) (xy 2.192332 -242.082989) (xy 2.256591 -242.113934)
			(xy 2.316982 -242.15188) (xy 2.372744 -242.196349) (xy 2.423177 -242.246782) (xy 2.467646 -242.302544)
			(xy 2.505592 -242.362935) (xy 2.536537 -242.427194) (xy 2.560094 -242.494514) (xy 2.575964 -242.564049)
			(xy 2.58395 -242.634923) (xy 2.58395 -242.706245) (xy 2.575964 -242.777119) (xy 2.560094 -242.846654)
			(xy 2.536537 -242.913974) (xy 2.505592 -242.978233) (xy 2.467646 -243.038624) (xy 2.423177 -243.094386)
			(xy 2.372744 -243.144819) (xy 2.316982 -243.189288) (xy 2.256591 -243.227234) (xy 2.192332 -243.258179)
			(xy 2.125012 -243.281736) (xy 2.055477 -243.297606) (xy 1.984603 -243.305592) (xy 1.913281 -243.305592)
			(xy 1.842407 -243.297606) (xy 1.772872 -243.281736) (xy 1.705552 -243.258179) (xy 1.641293 -243.227234)
			(xy 1.580902 -243.189288) (xy 1.52514 -243.144819) (xy 1.474707 -243.094386) (xy 1.430238 -243.038624)
			(xy 1.392292 -242.978233) (xy 1.361347 -242.913974) (xy 1.33779 -242.846654) (xy 1.32192 -242.777119)
			(xy 1.313934 -242.706245) (xy 0.509016 -242.706245) (xy 0.509016 -243.706243) (xy 3.31393 -243.706243)
			(xy 3.31393 -243.634921) (xy 3.321916 -243.564047) (xy 3.337786 -243.494512) (xy 3.361343 -243.427192)
			(xy 3.392288 -243.362933) (xy 3.430234 -243.302542) (xy 3.474703 -243.24678) (xy 3.525136 -243.196347)
			(xy 3.580898 -243.151878) (xy 3.641289 -243.113932) (xy 3.705548 -243.082987) (xy 3.772868 -243.05943)
			(xy 3.842403 -243.04356) (xy 3.913277 -243.035574) (xy 3.948938 -243.035074) (xy 3.984599 -243.035574)
			(xy 4.055473 -243.04356) (xy 4.125008 -243.05943) (xy 4.192328 -243.082987) (xy 4.256587 -243.113932)
			(xy 4.316978 -243.151878) (xy 4.37274 -243.196347) (xy 4.423173 -243.24678) (xy 4.467642 -243.302542)
			(xy 4.505588 -243.362933) (xy 4.536533 -243.427192) (xy 4.56009 -243.494512) (xy 4.57596 -243.564047)
			(xy 4.583946 -243.634921) (xy 4.583946 -243.706243) (xy 4.57596 -243.777117) (xy 4.56009 -243.846652)
			(xy 4.536533 -243.913972) (xy 4.505588 -243.978231) (xy 4.467642 -244.038622) (xy 4.423173 -244.094384)
			(xy 4.37274 -244.144817) (xy 4.316978 -244.189286) (xy 4.256587 -244.227232) (xy 4.192328 -244.258177)
			(xy 4.125008 -244.281734) (xy 4.055473 -244.297604) (xy 3.984599 -244.30559) (xy 3.913277 -244.30559)
			(xy 3.842403 -244.297604) (xy 3.772868 -244.281734) (xy 3.705548 -244.258177) (xy 3.641289 -244.227232)
			(xy 3.580898 -244.189286) (xy 3.525136 -244.144817) (xy 3.474703 -244.094384) (xy 3.430234 -244.038622)
			(xy 3.392288 -243.978231) (xy 3.361343 -243.913972) (xy 3.337786 -243.846652) (xy 3.321916 -243.777117)
			(xy 3.31393 -243.706243) (xy 0.509016 -243.706243) (xy 0.509016 -245.706239) (xy 3.31393 -245.706239)
			(xy 3.31393 -245.634917) (xy 3.321916 -245.564043) (xy 3.337786 -245.494508) (xy 3.361343 -245.427188)
			(xy 3.392288 -245.362929) (xy 3.430234 -245.302538) (xy 3.474703 -245.246776) (xy 3.525136 -245.196343)
			(xy 3.580898 -245.151874) (xy 3.641289 -245.113928) (xy 3.705548 -245.082983) (xy 3.772868 -245.059426)
			(xy 3.842403 -245.043556) (xy 3.913277 -245.03557) (xy 3.948938 -245.03507) (xy 3.984599 -245.03557)
			(xy 4.055473 -245.043556) (xy 4.125008 -245.059426) (xy 4.192328 -245.082983) (xy 4.256587 -245.113928)
			(xy 4.316978 -245.151874) (xy 4.37274 -245.196343) (xy 4.423173 -245.246776) (xy 4.467642 -245.302538)
			(xy 4.505588 -245.362929) (xy 4.536533 -245.427188) (xy 4.56009 -245.494508) (xy 4.57596 -245.564043)
			(xy 4.583946 -245.634917) (xy 4.583946 -245.706239) (xy 4.57596 -245.777113) (xy 4.56009 -245.846648)
			(xy 4.536533 -245.913968) (xy 4.505588 -245.978227) (xy 4.467642 -246.038618) (xy 4.423173 -246.09438)
			(xy 4.37274 -246.144813) (xy 4.316978 -246.189282) (xy 4.256587 -246.227228) (xy 4.192328 -246.258173)
			(xy 4.125008 -246.28173) (xy 4.055473 -246.2976) (xy 3.984599 -246.305586) (xy 3.913277 -246.305586)
			(xy 3.842403 -246.2976) (xy 3.772868 -246.28173) (xy 3.705548 -246.258173) (xy 3.641289 -246.227228)
			(xy 3.580898 -246.189282) (xy 3.525136 -246.144813) (xy 3.474703 -246.09438) (xy 3.430234 -246.038618)
			(xy 3.392288 -245.978227) (xy 3.361343 -245.913968) (xy 3.337786 -245.846648) (xy 3.321916 -245.777113)
			(xy 3.31393 -245.706239) (xy 0.509016 -245.706239) (xy 0.509016 -246.706237) (xy 1.313934 -246.706237)
			(xy 1.313934 -246.634915) (xy 1.32192 -246.564041) (xy 1.33779 -246.494506) (xy 1.361347 -246.427186)
			(xy 1.392292 -246.362927) (xy 1.430238 -246.302536) (xy 1.474707 -246.246774) (xy 1.52514 -246.196341)
			(xy 1.580902 -246.151872) (xy 1.641293 -246.113926) (xy 1.705552 -246.082981) (xy 1.772872 -246.059424)
			(xy 1.842407 -246.043554) (xy 1.913281 -246.035568) (xy 1.948942 -246.035068) (xy 1.984603 -246.035568)
			(xy 2.055477 -246.043554) (xy 2.125012 -246.059424) (xy 2.192332 -246.082981) (xy 2.256591 -246.113926)
			(xy 2.316982 -246.151872) (xy 2.372744 -246.196341) (xy 2.423177 -246.246774) (xy 2.467646 -246.302536)
			(xy 2.505592 -246.362927) (xy 2.536537 -246.427186) (xy 2.560094 -246.494506) (xy 2.575964 -246.564041)
			(xy 2.58395 -246.634915) (xy 2.58395 -246.706237) (xy 2.575964 -246.777111) (xy 2.560094 -246.846646)
			(xy 2.536537 -246.913966) (xy 2.505592 -246.978225) (xy 2.467646 -247.038616) (xy 2.423177 -247.094378)
			(xy 2.372744 -247.144811) (xy 2.316982 -247.18928) (xy 2.256591 -247.227226) (xy 2.192332 -247.258171)
			(xy 2.125012 -247.281728) (xy 2.055477 -247.297598) (xy 1.984603 -247.305584) (xy 1.913281 -247.305584)
			(xy 1.842407 -247.297598) (xy 1.772872 -247.281728) (xy 1.705552 -247.258171) (xy 1.641293 -247.227226)
			(xy 1.580902 -247.18928) (xy 1.52514 -247.144811) (xy 1.474707 -247.094378) (xy 1.430238 -247.038616)
			(xy 1.392292 -246.978225) (xy 1.361347 -246.913966) (xy 1.33779 -246.846646) (xy 1.32192 -246.777111)
			(xy 1.313934 -246.706237) (xy 0.509016 -246.706237) (xy 0.509016 -247.706235) (xy 3.31393 -247.706235)
			(xy 3.31393 -247.634913) (xy 3.321916 -247.564039) (xy 3.337786 -247.494504) (xy 3.361343 -247.427184)
			(xy 3.392288 -247.362925) (xy 3.430234 -247.302534) (xy 3.474703 -247.246772) (xy 3.525136 -247.196339)
			(xy 3.580898 -247.15187) (xy 3.641289 -247.113924) (xy 3.705548 -247.082979) (xy 3.772868 -247.059422)
			(xy 3.842403 -247.043552) (xy 3.913277 -247.035566) (xy 3.948938 -247.035066) (xy 3.984599 -247.035566)
			(xy 4.055473 -247.043552) (xy 4.125008 -247.059422) (xy 4.192328 -247.082979) (xy 4.256587 -247.113924)
			(xy 4.316978 -247.15187) (xy 4.37274 -247.196339) (xy 4.423173 -247.246772) (xy 4.467642 -247.302534)
			(xy 4.505588 -247.362925) (xy 4.536533 -247.427184) (xy 4.56009 -247.494504) (xy 4.57596 -247.564039)
			(xy 4.583946 -247.634913) (xy 4.583946 -247.706235) (xy 5.813798 -247.706235) (xy 5.813798 -247.634913)
			(xy 5.821784 -247.564039) (xy 5.837654 -247.494504) (xy 5.861211 -247.427184) (xy 5.892156 -247.362925)
			(xy 5.930102 -247.302534) (xy 5.974571 -247.246772) (xy 6.025004 -247.196339) (xy 6.080766 -247.15187)
			(xy 6.141157 -247.113924) (xy 6.205416 -247.082979) (xy 6.272736 -247.059422) (xy 6.342271 -247.043552)
			(xy 6.413145 -247.035566) (xy 6.448806 -247.035066) (xy 6.484467 -247.035566) (xy 6.555341 -247.043552)
			(xy 6.624876 -247.059422) (xy 6.692196 -247.082979) (xy 6.756455 -247.113924) (xy 6.816846 -247.15187)
			(xy 6.872608 -247.196339) (xy 6.923041 -247.246772) (xy 6.96751 -247.302534) (xy 7.005456 -247.362925)
			(xy 7.036401 -247.427184) (xy 7.059958 -247.494504) (xy 7.075828 -247.564039) (xy 7.083814 -247.634913)
			(xy 7.083814 -247.706235) (xy 7.075828 -247.777109) (xy 7.059958 -247.846644) (xy 7.036401 -247.913964)
			(xy 7.005456 -247.978223) (xy 6.96751 -248.038614) (xy 6.923041 -248.094376) (xy 6.872608 -248.144809)
			(xy 6.816846 -248.189278) (xy 6.756455 -248.227224) (xy 6.692196 -248.258169) (xy 6.624876 -248.281726)
			(xy 6.555341 -248.297596) (xy 6.484467 -248.305582) (xy 6.413145 -248.305582) (xy 6.342271 -248.297596)
			(xy 6.272736 -248.281726) (xy 6.205416 -248.258169) (xy 6.141157 -248.227224) (xy 6.080766 -248.189278)
			(xy 6.025004 -248.144809) (xy 5.974571 -248.094376) (xy 5.930102 -248.038614) (xy 5.892156 -247.978223)
			(xy 5.861211 -247.913964) (xy 5.837654 -247.846644) (xy 5.821784 -247.777109) (xy 5.813798 -247.706235)
			(xy 4.583946 -247.706235) (xy 4.57596 -247.777109) (xy 4.56009 -247.846644) (xy 4.536533 -247.913964)
			(xy 4.505588 -247.978223) (xy 4.467642 -248.038614) (xy 4.423173 -248.094376) (xy 4.37274 -248.144809)
			(xy 4.316978 -248.189278) (xy 4.256587 -248.227224) (xy 4.192328 -248.258169) (xy 4.125008 -248.281726)
			(xy 4.055473 -248.297596) (xy 3.984599 -248.305582) (xy 3.913277 -248.305582) (xy 3.842403 -248.297596)
			(xy 3.772868 -248.281726) (xy 3.705548 -248.258169) (xy 3.641289 -248.227224) (xy 3.580898 -248.189278)
			(xy 3.525136 -248.144809) (xy 3.474703 -248.094376) (xy 3.430234 -248.038614) (xy 3.392288 -247.978223)
			(xy 3.361343 -247.913964) (xy 3.337786 -247.846644) (xy 3.321916 -247.777109) (xy 3.31393 -247.706235)
			(xy 0.509016 -247.706235) (xy 0.509016 -248.706233) (xy 1.313934 -248.706233) (xy 1.313934 -248.634911)
			(xy 1.32192 -248.564037) (xy 1.33779 -248.494502) (xy 1.361347 -248.427182) (xy 1.392292 -248.362923)
			(xy 1.430238 -248.302532) (xy 1.474707 -248.24677) (xy 1.52514 -248.196337) (xy 1.580902 -248.151868)
			(xy 1.641293 -248.113922) (xy 1.705552 -248.082977) (xy 1.772872 -248.05942) (xy 1.842407 -248.04355)
			(xy 1.913281 -248.035564) (xy 1.948942 -248.035064) (xy 1.984603 -248.035564) (xy 2.055477 -248.04355)
			(xy 2.125012 -248.05942) (xy 2.192332 -248.082977) (xy 2.256591 -248.113922) (xy 2.316982 -248.151868)
			(xy 2.372744 -248.196337) (xy 2.423177 -248.24677) (xy 2.467646 -248.302532) (xy 2.505592 -248.362923)
			(xy 2.536537 -248.427182) (xy 2.560094 -248.494502) (xy 2.575964 -248.564037) (xy 2.58395 -248.634911)
			(xy 2.58395 -248.706233) (xy 2.575964 -248.777107) (xy 2.560094 -248.846642) (xy 2.536537 -248.913962)
			(xy 2.505592 -248.978221) (xy 2.467646 -249.038612) (xy 2.423177 -249.094374) (xy 2.372744 -249.144807)
			(xy 2.316982 -249.189276) (xy 2.256591 -249.227222) (xy 2.192332 -249.258167) (xy 2.125012 -249.281724)
			(xy 2.055477 -249.297594) (xy 1.984603 -249.30558) (xy 1.913281 -249.30558) (xy 1.842407 -249.297594)
			(xy 1.772872 -249.281724) (xy 1.705552 -249.258167) (xy 1.641293 -249.227222) (xy 1.580902 -249.189276)
			(xy 1.52514 -249.144807) (xy 1.474707 -249.094374) (xy 1.430238 -249.038612) (xy 1.392292 -248.978221)
			(xy 1.361347 -248.913962) (xy 1.33779 -248.846642) (xy 1.32192 -248.777107) (xy 1.313934 -248.706233)
			(xy 0.509016 -248.706233) (xy 0.509016 -252.706225) (xy 1.313934 -252.706225) (xy 1.313934 -252.634903)
			(xy 1.32192 -252.564029) (xy 1.33779 -252.494494) (xy 1.361347 -252.427174) (xy 1.392292 -252.362915)
			(xy 1.430238 -252.302524) (xy 1.474707 -252.246762) (xy 1.52514 -252.196329) (xy 1.580902 -252.15186)
			(xy 1.641293 -252.113914) (xy 1.705552 -252.082969) (xy 1.772872 -252.059412) (xy 1.842407 -252.043542)
			(xy 1.913281 -252.035556) (xy 1.948942 -252.035056) (xy 1.984603 -252.035556) (xy 2.055477 -252.043542)
			(xy 2.125012 -252.059412) (xy 2.192332 -252.082969) (xy 2.256591 -252.113914) (xy 2.316982 -252.15186)
			(xy 2.372744 -252.196329) (xy 2.423177 -252.246762) (xy 2.467646 -252.302524) (xy 2.505592 -252.362915)
			(xy 2.536537 -252.427174) (xy 2.560094 -252.494494) (xy 2.575964 -252.564029) (xy 2.58395 -252.634903)
			(xy 2.58395 -252.706225) (xy 2.575964 -252.777099) (xy 2.560094 -252.846634) (xy 2.536537 -252.913954)
			(xy 2.505592 -252.978213) (xy 2.467646 -253.038604) (xy 2.423177 -253.094366) (xy 2.372744 -253.144799)
			(xy 2.316982 -253.189268) (xy 2.256591 -253.227214) (xy 2.192332 -253.258159) (xy 2.125012 -253.281716)
			(xy 2.055477 -253.297586) (xy 1.984603 -253.305572) (xy 1.913281 -253.305572) (xy 1.842407 -253.297586)
			(xy 1.772872 -253.281716) (xy 1.705552 -253.258159) (xy 1.641293 -253.227214) (xy 1.580902 -253.189268)
			(xy 1.52514 -253.144799) (xy 1.474707 -253.094366) (xy 1.430238 -253.038604) (xy 1.392292 -252.978213)
			(xy 1.361347 -252.913954) (xy 1.33779 -252.846634) (xy 1.32192 -252.777099) (xy 1.313934 -252.706225)
			(xy 0.509016 -252.706225) (xy 0.509016 -256.670563) (xy 1.312896 -256.670563) (xy 1.316876 -256.599516)
			(xy 1.328768 -256.529357) (xy 1.348422 -256.460966) (xy 1.375592 -256.395199) (xy 1.409939 -256.332878)
			(xy 1.451032 -256.274783) (xy 1.498357 -256.221643) (xy 1.551322 -256.174121) (xy 1.609264 -256.132813)
			(xy 1.671457 -256.098236) (xy 1.737123 -256.070822) (xy 1.805441 -256.050915) (xy 1.875555 -256.038764)
			(xy 1.946587 -256.03452) (xy 2.017649 -256.038238) (xy 2.087851 -256.04987) (xy 2.156314 -256.069271)
			(xy 2.222181 -256.096199) (xy 2.284629 -256.130315) (xy 2.342875 -256.171193) (xy 2.39619 -256.218322)
			(xy 2.443907 -256.271111) (xy 2.46507 -256.299716) (xy 2.474215 -256.311728) (xy 2.49712 -256.331387)
			(xy 2.524001 -256.345117) (xy 2.553355 -256.352149) (xy 2.568448 -256.352548) (xy 3.169158 -256.352548)
			(xy 3.191111 -256.352093) (xy 3.234365 -256.344558) (xy 3.27568 -256.329702) (xy 3.313826 -256.307965)
			(xy 3.347669 -256.279994) (xy 3.376201 -256.246623) (xy 3.398572 -256.208845) (xy 3.414116 -256.167784)
			(xy 3.422372 -256.124662) (xy 3.423093 -256.080763) (xy 3.416257 -256.037393) (xy 3.402069 -255.995843)
			(xy 3.391916 -255.976374) (xy 3.375278 -255.945056) (xy 3.348281 -255.879476) (xy 3.328755 -255.811297)
			(xy 3.316941 -255.741368) (xy 3.312987 -255.670558) (xy 3.316941 -255.599749) (xy 3.328755 -255.52982)
			(xy 3.348282 -255.461641) (xy 3.375279 -255.396061) (xy 3.391916 -255.364742) (xy 3.402002 -255.345244)
			(xy 3.416174 -255.303702) (xy 3.422998 -255.260344) (xy 3.422271 -255.216458) (xy 3.414015 -255.173349)
			(xy 3.398475 -255.1323) (xy 3.376113 -255.094531) (xy 3.347595 -255.061166) (xy 3.313768 -255.033196)
			(xy 3.275639 -255.011454) (xy 3.234342 -254.996587) (xy 3.191104 -254.989036) (xy 3.169158 -254.988568)
			(xy 2.568448 -254.988568) (xy 2.553356 -254.988981) (xy 2.524002 -254.996002) (xy 2.497124 -255.009732)
			(xy 2.474231 -255.0294) (xy 2.46507 -255.0414) (xy 2.443907 -255.070005) (xy 2.39619 -255.122794)
			(xy 2.342876 -255.169923) (xy 2.28463 -255.210801) (xy 2.222183 -255.244918) (xy 2.156316 -255.271845)
			(xy 2.087854 -255.291247) (xy 2.017652 -255.302879) (xy 1.946591 -255.306597) (xy 1.875558 -255.302354)
			(xy 1.805445 -255.290203) (xy 1.737127 -255.270297) (xy 1.671461 -255.242884) (xy 1.609268 -255.208307)
			(xy 1.551326 -255.166999) (xy 1.498361 -255.119478) (xy 1.451035 -255.066338) (xy 1.409942 -255.008244)
			(xy 1.375595 -254.945923) (xy 1.348425 -254.880156) (xy 1.328771 -254.811765) (xy 1.316879 -254.741607)
			(xy 1.312898 -254.67056) (xy 1.316879 -254.599513) (xy 1.328771 -254.529355) (xy 1.348425 -254.460964)
			(xy 1.375595 -254.395197) (xy 1.409942 -254.332876) (xy 1.451035 -254.274782) (xy 1.498361 -254.221642)
			(xy 1.551326 -254.174121) (xy 1.609268 -254.132813) (xy 1.671461 -254.098236) (xy 1.737127 -254.070823)
			(xy 1.805445 -254.050917) (xy 1.875558 -254.038766) (xy 1.946591 -254.034523) (xy 2.017652 -254.038241)
			(xy 2.087854 -254.049873) (xy 2.156316 -254.069275) (xy 2.222183 -254.096202) (xy 2.28463 -254.130319)
			(xy 2.342876 -254.171197) (xy 2.39619 -254.218326) (xy 2.443907 -254.271115) (xy 2.46507 -254.29972)
			(xy 2.474214 -254.311733) (xy 2.497119 -254.331392) (xy 2.524001 -254.345121) (xy 2.553355 -254.352153)
			(xy 2.568448 -254.352552) (xy 3.963416 -254.352552) (xy 4.547362 -253.768606) (xy 4.558762 -253.756479)
			(xy 4.575453 -253.727698) (xy 4.584125 -253.695578) (xy 4.5847 -253.678944) (xy 4.5847 -253.086362)
			(xy 5.479288 -252.19152) (xy 5.600446 -252.19152) (xy 5.622103 -252.191059) (xy 5.664784 -252.183674)
			(xy 5.705594 -252.169157) (xy 5.743351 -252.147929) (xy 5.776961 -252.120606) (xy 5.805451 -252.087978)
			(xy 5.827994 -252.050992) (xy 5.843938 -252.010718) (xy 5.852821 -251.968324) (xy 5.854386 -251.925037)
			(xy 5.848587 -251.882111) (xy 5.842508 -251.86132) (xy 5.837912 -251.846258) (xy 5.830033 -251.815764)
			(xy 5.82676 -251.80036) (xy 5.821807 -251.778751) (xy 5.805353 -251.737588) (xy 5.782007 -251.699904)
			(xy 5.752477 -251.666841) (xy 5.71766 -251.639402) (xy 5.67861 -251.618419) (xy 5.636512 -251.604529)
			(xy 5.592643 -251.598152) (xy 5.548333 -251.599483) (xy 5.526532 -251.60351) (xy 5.472591 -251.614244)
			(xy 5.36362 -251.629213) (xy 5.253883 -251.636735) (xy 5.143889 -251.636775) (xy 5.034146 -251.629333)
			(xy 4.925164 -251.614443) (xy 4.871212 -251.603764) (xy 4.849427 -251.599696) (xy 4.805133 -251.598335)
			(xy 4.761275 -251.604683) (xy 4.719185 -251.618545) (xy 4.680139 -251.639502) (xy 4.645323 -251.666917)
			(xy 4.615793 -251.699959) (xy 4.592445 -251.737624) (xy 4.575989 -251.77877) (xy 4.570984 -251.80036)
			(xy 4.563244 -251.835059) (xy 4.541045 -251.902602) (xy 4.511446 -251.967244) (xy 4.474817 -252.028179)
			(xy 4.431616 -252.084646) (xy 4.382382 -252.135937) (xy 4.327731 -252.181413) (xy 4.268345 -252.220505)
			(xy 4.204968 -252.252724) (xy 4.138391 -252.277668) (xy 4.069445 -252.295026) (xy 3.998993 -252.304579)
			(xy 3.927914 -252.30621) (xy 3.857098 -252.299897) (xy 3.787429 -252.285719) (xy 3.719778 -252.263855)
			(xy 3.65499 -252.234575) (xy 3.593874 -252.198248) (xy 3.537195 -252.155326) (xy 3.485661 -252.106346)
			(xy 3.439916 -252.051921) (xy 3.400531 -251.99273) (xy 3.367999 -251.929512) (xy 3.342726 -251.863059)
			(xy 3.325028 -251.7942) (xy 3.315126 -251.723796) (xy 3.313144 -251.652726) (xy 3.319107 -251.58188)
			(xy 3.33294 -251.512142) (xy 3.35447 -251.444383) (xy 3.383429 -251.379451) (xy 3.419454 -251.318157)
			(xy 3.462095 -251.261266) (xy 3.510819 -251.209491) (xy 3.565018 -251.163477) (xy 3.624014 -251.1238)
			(xy 3.655314 -251.10694) (xy 3.674734 -251.096276) (xy 3.709879 -251.069308) (xy 3.739815 -251.036654)
			(xy 3.763636 -250.999303) (xy 3.780619 -250.958389) (xy 3.790251 -250.915149) (xy 3.79224 -250.870894)
			(xy 3.786524 -250.826964) (xy 3.773279 -250.784691) (xy 3.763518 -250.764802) (xy 3.738506 -250.715541)
			(xy 3.694475 -250.614203) (xy 3.657468 -250.510095) (xy 3.627656 -250.403703) (xy 3.605179 -250.295523)
			(xy 3.590142 -250.186061) (xy 3.582615 -250.075827) (xy 3.582162 -250.020582) (xy 3.582667 -249.963207)
			(xy 3.590809 -249.848747) (xy 3.607047 -249.735153) (xy 3.6313 -249.622996) (xy 3.663446 -249.512841)
			(xy 3.703323 -249.405244) (xy 3.75073 -249.300745) (xy 3.805428 -249.199871) (xy 3.867141 -249.10313)
			(xy 3.93556 -249.011009) (xy 4.01034 -248.923972) (xy 4.091103 -248.842458) (xy 4.177444 -248.766876)
			(xy 4.268927 -248.697607) (xy 4.365092 -248.635) (xy 4.465455 -248.57937) (xy 4.569511 -248.530998)
			(xy 4.676734 -248.490126) (xy 4.786587 -248.456962) (xy 4.898514 -248.431671) (xy 5.011953 -248.414381)
			(xy 5.126333 -248.40518) (xy 5.241077 -248.404113) (xy 5.355608 -248.411186) (xy 5.46935 -248.426363)
			(xy 5.581728 -248.449568) (xy 5.692178 -248.480683) (xy 5.800143 -248.519554) (xy 5.90508 -248.565982)
			(xy 6.00646 -248.619736) (xy 6.103773 -248.680544) (xy 6.139045 -248.706233) (xy 7.813794 -248.706233)
			(xy 7.813794 -248.634911) (xy 7.82178 -248.564037) (xy 7.83765 -248.494502) (xy 7.861207 -248.427182)
			(xy 7.892152 -248.362923) (xy 7.930098 -248.302532) (xy 7.974567 -248.24677) (xy 8.025 -248.196337)
			(xy 8.080762 -248.151868) (xy 8.141153 -248.113922) (xy 8.205412 -248.082977) (xy 8.272732 -248.05942)
			(xy 8.342267 -248.04355) (xy 8.413141 -248.035564) (xy 8.448802 -248.035064) (xy 8.484463 -248.035564)
			(xy 8.555337 -248.04355) (xy 8.624872 -248.05942) (xy 8.692192 -248.082977) (xy 8.756451 -248.113922)
			(xy 8.816842 -248.151868) (xy 8.872604 -248.196337) (xy 8.923037 -248.24677) (xy 8.967506 -248.302532)
			(xy 9.005452 -248.362923) (xy 9.036397 -248.427182) (xy 9.059954 -248.494502) (xy 9.075824 -248.564037)
			(xy 9.08381 -248.634911) (xy 9.08381 -248.706233) (xy 9.075824 -248.777107) (xy 9.059954 -248.846642)
			(xy 9.036397 -248.913962) (xy 9.005452 -248.978221) (xy 8.967506 -249.038612) (xy 8.923037 -249.094374)
			(xy 8.872604 -249.144807) (xy 8.816842 -249.189276) (xy 8.756451 -249.227222) (xy 8.692192 -249.258167)
			(xy 8.624872 -249.281724) (xy 8.555337 -249.297594) (xy 8.484463 -249.30558) (xy 8.413141 -249.30558)
			(xy 8.342267 -249.297594) (xy 8.272732 -249.281724) (xy 8.205412 -249.258167) (xy 8.141153 -249.227222)
			(xy 8.080762 -249.189276) (xy 8.025 -249.144807) (xy 7.974567 -249.094374) (xy 7.930098 -249.038612)
			(xy 7.892152 -248.978221) (xy 7.861207 -248.913962) (xy 7.83765 -248.846642) (xy 7.82178 -248.777107)
			(xy 7.813794 -248.706233) (xy 6.139045 -248.706233) (xy 6.196529 -248.748099) (xy 6.284261 -248.822063)
			(xy 6.366526 -248.902061) (xy 6.442911 -248.987693) (xy 6.513031 -249.078525) (xy 6.576533 -249.174102)
			(xy 6.633098 -249.273941) (xy 6.68244 -249.37754) (xy 6.72431 -249.484377) (xy 6.758499 -249.593915)
			(xy 6.784834 -249.705601) (xy 6.803182 -249.818874) (xy 6.813452 -249.933163) (xy 6.81559 -250.047892)
			(xy 6.809587 -250.162485) (xy 6.795473 -250.276362) (xy 6.773318 -250.388953) (xy 6.743235 -250.499688)
			(xy 6.705375 -250.608012) (xy 6.659928 -250.713378) (xy 6.633972 -250.764548) (xy 6.624195 -250.784446)
			(xy 6.610935 -250.826745) (xy 6.605209 -250.870704) (xy 6.607191 -250.914989) (xy 6.616821 -250.95826)
			(xy 6.633807 -250.999206) (xy 6.657635 -251.036587) (xy 6.687583 -251.069271) (xy 6.722744 -251.096268)
			(xy 6.742176 -251.10694) (xy 6.771363 -251.122616) (xy 6.826636 -251.15915) (xy 6.877812 -251.201231)
			(xy 6.924338 -251.248402) (xy 6.96571 -251.300153) (xy 7.001479 -251.355923) (xy 7.01675 -251.385324)
			(xy 7.027021 -251.404606) (xy 7.053034 -251.439698) (xy 7.084663 -251.469826) (xy 7.120976 -251.494105)
			(xy 7.160905 -251.511818) (xy 7.203275 -251.522445) (xy 7.246837 -251.525673) (xy 7.29031 -251.521407)
			(xy 7.332414 -251.509772) (xy 7.37191 -251.491111) (xy 7.407633 -251.465973) (xy 7.423404 -251.450856)
			(xy 7.759954 -251.11456) (xy 9.17829 -251.11456) (xy 11.327892 -253.264162) (xy 11.327892 -255.015492)
			(xy 14.530324 -258.217924) (xy 14.546916 -258.233943) (xy 14.58487 -258.260144) (xy 14.626926 -258.279072)
			(xy 14.671705 -258.290105) (xy 14.717741 -258.292883) (xy 14.763522 -258.287314) (xy 14.807549 -258.27358)
			(xy 14.848377 -258.252132) (xy 14.884669 -258.223673) (xy 14.915233 -258.189137) (xy 14.939069 -258.149655)
			(xy 14.955394 -258.106522) (xy 14.963673 -258.061152) (xy 14.964156 -258.038092) (xy 14.964156 -255.546606)
			(xy 18.483072 -252.027436) (xy 24.295608 -252.027436) (xy 24.319348 -252.026889) (xy 24.366002 -252.018072)
			(xy 24.410207 -252.000745) (xy 24.450427 -251.975512) (xy 24.485262 -251.94325) (xy 24.513501 -251.905081)
			(xy 24.534161 -251.862332) (xy 24.546526 -251.816491) (xy 24.550163 -251.769151) (xy 24.548084 -251.745496)
			(xy 24.545501 -251.717715) (xy 24.547515 -251.661957) (xy 24.557627 -251.607087) (xy 24.575623 -251.554275)
			(xy 24.601119 -251.504648) (xy 24.633571 -251.459262) (xy 24.672287 -251.419087) (xy 24.716441 -251.384979)
			(xy 24.765092 -251.357665) (xy 24.817203 -251.337729) (xy 24.871661 -251.325594) (xy 24.927306 -251.32152)
			(xy 24.982951 -251.325594) (xy 25.037409 -251.337729) (xy 25.08952 -251.357665) (xy 25.138171 -251.384979)
			(xy 25.182325 -251.419087) (xy 25.221041 -251.459262) (xy 25.253493 -251.504648) (xy 25.278989 -251.554275)
			(xy 25.296985 -251.607087) (xy 25.307097 -251.661957) (xy 25.309111 -251.717715) (xy 25.306528 -251.745496)
			(xy 25.304421 -251.76915) (xy 25.308059 -251.816494) (xy 25.320425 -251.86234) (xy 25.341088 -251.905092)
			(xy 25.369331 -251.943264) (xy 25.40417 -251.975528) (xy 25.444394 -252.000762) (xy 25.488604 -252.018089)
			(xy 25.535262 -252.026905) (xy 25.559004 -252.027436) (xy 27.94762 -252.027436) (xy 29.29382 -250.681236)
			(xy 29.356304 -250.681236) (xy 29.378975 -250.680653) (xy 29.423598 -250.672605) (xy 29.466083 -250.656765)
			(xy 29.505084 -250.633636) (xy 29.53936 -250.603953) (xy 29.567823 -250.568658) (xy 29.589571 -250.528871)
			(xy 29.603912 -250.485856) (xy 29.610392 -250.440979) (xy 29.608803 -250.395664) (xy 29.599198 -250.351351)
			(xy 29.591 -250.330208) (xy 29.574781 -250.289759) (xy 29.549008 -250.206505) (xy 29.531046 -250.121223)
			(xy 29.52105 -250.034646) (xy 29.519105 -249.947515) (xy 29.525228 -249.860577) (xy 29.539367 -249.774579)
			(xy 29.5614 -249.690258) (xy 29.591138 -249.608336) (xy 29.609288 -249.568716) (xy 29.618724 -249.547477)
			(xy 29.630598 -249.50255) (xy 29.634099 -249.456212) (xy 29.62911 -249.410011) (xy 29.615799 -249.365489)
			(xy 29.594609 -249.324132) (xy 29.566247 -249.28732) (xy 29.531662 -249.256284) (xy 29.492006 -249.232058)
			(xy 29.448605 -249.215452) (xy 29.402907 -249.20702) (xy 29.379672 -249.206512) (xy 27.026362 -249.206512)
			(xy 25.58034 -247.760236) (xy 25.58034 -246.94388) (xy 25.580769 -246.913674) (xy 25.588294 -246.853732)
			(xy 25.603238 -246.795197) (xy 25.625367 -246.738983) (xy 25.654335 -246.685969) (xy 25.689689 -246.636982)
			(xy 25.730878 -246.592787) (xy 25.777258 -246.554076) (xy 25.828104 -246.521452) (xy 25.882623 -246.495426)
			(xy 25.939962 -246.476403) (xy 25.999227 -246.464681) (xy 26.05949 -246.460443) (xy 26.119812 -246.463755)
			(xy 26.179249 -246.474566) (xy 26.236874 -246.492707) (xy 26.291785 -246.517893) (xy 26.317702 -246.533416)
			(xy 26.33136 -246.541319) (xy 26.361416 -246.550892) (xy 26.392902 -246.552796) (xy 26.423893 -246.546915)
			(xy 26.452493 -246.533609) (xy 26.465022 -246.524018) (xy 26.490965 -246.503496) (xy 26.54742 -246.469022)
			(xy 26.608054 -246.442579) (xy 26.67173 -246.424662) (xy 26.737256 -246.415607) (xy 26.77033 -246.415052)
			(xy 28.552394 -246.415052) (xy 29.25953 -245.707916) (xy 29.40685 -245.707916) (xy 29.428695 -245.707488)
			(xy 29.471743 -245.700025) (xy 29.512881 -245.685309) (xy 29.550895 -245.663775) (xy 29.584667 -245.636057)
			(xy 29.613201 -245.602971) (xy 29.635656 -245.565493) (xy 29.65137 -245.524726) (xy 29.659881 -245.481873)
			(xy 29.660938 -245.438196) (xy 29.65451 -245.394981) (xy 29.640786 -245.353503) (xy 29.630878 -245.334028)
			(xy 29.610952 -245.295803) (xy 29.577371 -245.216404) (xy 29.551199 -245.134265) (xy 29.532656 -245.050075)
			(xy 29.521898 -244.964541) (xy 29.519015 -244.878381) (xy 29.524032 -244.792319) (xy 29.536906 -244.707077)
			(xy 29.557529 -244.623373) (xy 29.585728 -244.541907) (xy 29.621266 -244.463365) (xy 29.663845 -244.388406)
			(xy 29.713107 -244.317659) (xy 29.768639 -244.251719) (xy 29.829974 -244.19114) (xy 29.896597 -244.136429)
			(xy 29.967948 -244.088047) (xy 30.043429 -244.0464) (xy 30.122405 -244.011838) (xy 30.204214 -243.98465)
			(xy 30.288168 -243.965066) (xy 30.373562 -243.953249) (xy 30.45968 -243.949299) (xy 30.545798 -243.953249)
			(xy 30.631192 -243.965066) (xy 30.715146 -243.98465) (xy 30.796955 -244.011838) (xy 30.875931 -244.0464)
			(xy 30.951412 -244.088047) (xy 31.022763 -244.136429) (xy 31.089386 -244.19114) (xy 31.150721 -244.251719)
			(xy 31.206253 -244.317659) (xy 31.255515 -244.388406) (xy 31.298094 -244.463365) (xy 31.333632 -244.541907)
			(xy 31.361831 -244.623373) (xy 31.382454 -244.707077) (xy 31.395328 -244.792319) (xy 31.400345 -244.878381)
			(xy 31.397462 -244.964541) (xy 31.386704 -245.050075) (xy 31.368161 -245.134265) (xy 31.341989 -245.216404)
			(xy 31.308408 -245.295803) (xy 31.288482 -245.334028) (xy 31.278628 -245.353536) (xy 31.264859 -245.395009)
			(xy 31.258395 -245.438227) (xy 31.259424 -245.481914) (xy 31.267918 -245.524779) (xy 31.283625 -245.565557)
			(xy 31.306082 -245.603044) (xy 31.334624 -245.636133) (xy 31.368411 -245.663847) (xy 31.406443 -245.685367)
			(xy 31.447598 -245.700059) (xy 31.49066 -245.707487) (xy 31.51251 -245.707916) (xy 34.48685 -245.707916)
			(xy 34.508695 -245.707488) (xy 34.551743 -245.700025) (xy 34.592881 -245.685309) (xy 34.630895 -245.663775)
			(xy 34.664667 -245.636057) (xy 34.693201 -245.602971) (xy 34.715656 -245.565493) (xy 34.73137 -245.524726)
			(xy 34.739881 -245.481873) (xy 34.740938 -245.438196) (xy 34.73451 -245.394981) (xy 34.720786 -245.353503)
			(xy 34.710878 -245.334028) (xy 34.690952 -245.295803) (xy 34.657371 -245.216404) (xy 34.631199 -245.134265)
			(xy 34.612656 -245.050075) (xy 34.601898 -244.964541) (xy 34.599015 -244.878381) (xy 34.604032 -244.792319)
			(xy 34.616906 -244.707077) (xy 34.637529 -244.623373) (xy 34.665728 -244.541907) (xy 34.701266 -244.463365)
			(xy 34.743845 -244.388406) (xy 34.793107 -244.317659) (xy 34.848639 -244.251719) (xy 34.909974 -244.19114)
			(xy 34.976597 -244.136429) (xy 35.047948 -244.088047) (xy 35.123429 -244.0464) (xy 35.202405 -244.011838)
			(xy 35.284214 -243.98465) (xy 35.368168 -243.965066) (xy 35.453562 -243.953249) (xy 35.53968 -243.949299)
			(xy 35.625798 -243.953249) (xy 35.711192 -243.965066) (xy 35.795146 -243.98465) (xy 35.876955 -244.011838)
			(xy 35.955931 -244.0464) (xy 36.031412 -244.088047) (xy 36.102763 -244.136429) (xy 36.169386 -244.19114)
			(xy 36.230721 -244.251719) (xy 36.286253 -244.317659) (xy 36.335515 -244.388406) (xy 36.378094 -244.463365)
			(xy 36.413632 -244.541907) (xy 36.441831 -244.623373) (xy 36.462454 -244.707077) (xy 36.463121 -244.711492)
			(xy 44.159423 -244.711492) (xy 44.165523 -244.656055) (xy 44.179629 -244.602098) (xy 44.201441 -244.550769)
			(xy 44.230495 -244.503163) (xy 44.26617 -244.460295) (xy 44.307707 -244.423078) (xy 44.35422 -244.392305)
			(xy 44.404717 -244.368633) (xy 44.458124 -244.352565) (xy 44.5133 -244.344445) (xy 44.541186 -244.343936)
			(xy 44.569072 -244.344445) (xy 44.624248 -244.352565) (xy 44.677655 -244.368633) (xy 44.728152 -244.392305)
			(xy 44.774665 -244.423078) (xy 44.816202 -244.460295) (xy 44.851877 -244.503163) (xy 44.880931 -244.550769)
			(xy 44.902743 -244.602098) (xy 44.916849 -244.656055) (xy 44.922949 -244.711492) (xy 44.920912 -244.767226)
			(xy 44.910782 -244.822069) (xy 44.892775 -244.874853) (xy 44.867274 -244.924453) (xy 44.834823 -244.969811)
			(xy 44.796114 -245.00996) (xy 44.751971 -245.044046) (xy 44.703336 -245.071342) (xy 44.651245 -245.091265)
			(xy 44.596808 -245.103391) (xy 44.541186 -245.107462) (xy 44.485564 -245.103391) (xy 44.431127 -245.091265)
			(xy 44.379036 -245.071342) (xy 44.330401 -245.044046) (xy 44.286258 -245.00996) (xy 44.247549 -244.969811)
			(xy 44.215098 -244.924453) (xy 44.189597 -244.874853) (xy 44.17159 -244.822069) (xy 44.16146 -244.767226)
			(xy 44.159423 -244.711492) (xy 36.463121 -244.711492) (xy 36.475328 -244.792319) (xy 36.480345 -244.878381)
			(xy 36.477462 -244.964541) (xy 36.466704 -245.050075) (xy 36.448161 -245.134265) (xy 36.421989 -245.216404)
			(xy 36.388408 -245.295803) (xy 36.368482 -245.334028) (xy 36.358628 -245.353536) (xy 36.344859 -245.395009)
			(xy 36.338395 -245.438227) (xy 36.339424 -245.481914) (xy 36.347918 -245.524779) (xy 36.363625 -245.565557)
			(xy 36.386082 -245.603044) (xy 36.414624 -245.636133) (xy 36.448411 -245.663847) (xy 36.477992 -245.680585)
			(xy 66.107556 -245.680585) (xy 66.107556 -245.609263) (xy 66.115542 -245.538389) (xy 66.131412 -245.468854)
			(xy 66.154969 -245.401534) (xy 66.185914 -245.337275) (xy 66.22386 -245.276884) (xy 66.268329 -245.221122)
			(xy 66.318762 -245.170689) (xy 66.374524 -245.12622) (xy 66.434915 -245.088274) (xy 66.499174 -245.057329)
			(xy 66.566494 -245.033772) (xy 66.636029 -245.017902) (xy 66.706903 -245.009916) (xy 66.742564 -245.009416)
			(xy 66.778225 -245.009916) (xy 66.849099 -245.017902) (xy 66.918634 -245.033772) (xy 66.985954 -245.057329)
			(xy 67.050213 -245.088274) (xy 67.110604 -245.12622) (xy 67.166366 -245.170689) (xy 67.216799 -245.221122)
			(xy 67.261268 -245.276884) (xy 67.299214 -245.337275) (xy 67.330159 -245.401534) (xy 67.353716 -245.468854)
			(xy 67.369586 -245.538389) (xy 67.377572 -245.609263) (xy 67.377572 -245.680585) (xy 69.099168 -245.680585)
			(xy 69.099168 -245.609263) (xy 69.107154 -245.538389) (xy 69.123024 -245.468854) (xy 69.146581 -245.401534)
			(xy 69.177526 -245.337275) (xy 69.215472 -245.276884) (xy 69.259941 -245.221122) (xy 69.310374 -245.170689)
			(xy 69.366136 -245.12622) (xy 69.426527 -245.088274) (xy 69.490786 -245.057329) (xy 69.558106 -245.033772)
			(xy 69.627641 -245.017902) (xy 69.698515 -245.009916) (xy 69.734176 -245.009416) (xy 69.769837 -245.009916)
			(xy 69.840711 -245.017902) (xy 69.910246 -245.033772) (xy 69.977566 -245.057329) (xy 70.041825 -245.088274)
			(xy 70.102216 -245.12622) (xy 70.157978 -245.170689) (xy 70.208411 -245.221122) (xy 70.25288 -245.276884)
			(xy 70.290826 -245.337275) (xy 70.321771 -245.401534) (xy 70.345328 -245.468854) (xy 70.361198 -245.538389)
			(xy 70.369184 -245.609263) (xy 70.369184 -245.680585) (xy 70.361198 -245.751459) (xy 70.345328 -245.820994)
			(xy 70.321771 -245.888314) (xy 70.290826 -245.952573) (xy 70.25288 -246.012964) (xy 70.208411 -246.068726)
			(xy 70.157978 -246.119159) (xy 70.102216 -246.163628) (xy 70.041825 -246.201574) (xy 69.977566 -246.232519)
			(xy 69.910246 -246.256076) (xy 69.840711 -246.271946) (xy 69.769837 -246.279932) (xy 69.698515 -246.279932)
			(xy 69.627641 -246.271946) (xy 69.558106 -246.256076) (xy 69.490786 -246.232519) (xy 69.426527 -246.201574)
			(xy 69.366136 -246.163628) (xy 69.310374 -246.119159) (xy 69.259941 -246.068726) (xy 69.215472 -246.012964)
			(xy 69.177526 -245.952573) (xy 69.146581 -245.888314) (xy 69.123024 -245.820994) (xy 69.107154 -245.751459)
			(xy 69.099168 -245.680585) (xy 67.377572 -245.680585) (xy 67.369586 -245.751459) (xy 67.353716 -245.820994)
			(xy 67.330159 -245.888314) (xy 67.299214 -245.952573) (xy 67.261268 -246.012964) (xy 67.216799 -246.068726)
			(xy 67.166366 -246.119159) (xy 67.110604 -246.163628) (xy 67.050213 -246.201574) (xy 66.985954 -246.232519)
			(xy 66.918634 -246.256076) (xy 66.849099 -246.271946) (xy 66.778225 -246.279932) (xy 66.706903 -246.279932)
			(xy 66.636029 -246.271946) (xy 66.566494 -246.256076) (xy 66.499174 -246.232519) (xy 66.434915 -246.201574)
			(xy 66.374524 -246.163628) (xy 66.318762 -246.119159) (xy 66.268329 -246.068726) (xy 66.22386 -246.012964)
			(xy 66.185914 -245.952573) (xy 66.154969 -245.888314) (xy 66.131412 -245.820994) (xy 66.115542 -245.751459)
			(xy 66.107556 -245.680585) (xy 36.477992 -245.680585) (xy 36.486443 -245.685367) (xy 36.527598 -245.700059)
			(xy 36.57066 -245.707487) (xy 36.59251 -245.707916) (xy 43.863006 -245.707916) (xy 44.82592 -246.67083)
			(xy 44.847922 -246.693563) (xy 44.886435 -246.743755) (xy 44.918068 -246.798544) (xy 44.942279 -246.856994)
			(xy 44.958653 -246.918103) (xy 44.966911 -246.980827) (xy 44.966911 -247.044093) (xy 44.958653 -247.106817)
			(xy 44.942279 -247.167926) (xy 44.918068 -247.226376) (xy 44.886435 -247.281165) (xy 44.847922 -247.331357)
			(xy 44.803187 -247.376092) (xy 44.752995 -247.414605) (xy 44.698206 -247.446238) (xy 44.639756 -247.470449)
			(xy 44.578647 -247.486823) (xy 44.515923 -247.495081) (xy 44.452657 -247.495081) (xy 44.389933 -247.486823)
			(xy 44.328824 -247.470449) (xy 44.270374 -247.446238) (xy 44.215585 -247.414605) (xy 44.165393 -247.376092)
			(xy 44.14266 -247.35409) (xy 43.462702 -246.674132) (xy 43.209464 -246.674132) (xy 43.186707 -246.674644)
			(xy 43.141919 -246.68274) (xy 43.099289 -246.698686) (xy 43.060182 -246.721971) (xy 43.025849 -246.75185)
			(xy 42.997387 -246.787368) (xy 42.975708 -246.827387) (xy 42.961505 -246.870628) (xy 42.955232 -246.915708)
			(xy 42.95709 -246.961185) (xy 42.96156 -246.983504) (xy 42.968871 -247.018336) (xy 42.976604 -247.089088)
			(xy 42.976382 -247.160262) (xy 42.968208 -247.230966) (xy 42.952185 -247.300313) (xy 42.928513 -247.367435)
			(xy 42.897489 -247.431492) (xy 42.859502 -247.491681) (xy 42.829067 -247.529705) (xy 66.070726 -247.529705)
			(xy 66.070726 -247.458383) (xy 66.078712 -247.387509) (xy 66.094582 -247.317974) (xy 66.118139 -247.250654)
			(xy 66.149084 -247.186395) (xy 66.18703 -247.126004) (xy 66.231499 -247.070242) (xy 66.281932 -247.019809)
			(xy 66.337694 -246.97534) (xy 66.398085 -246.937394) (xy 66.462344 -246.906449) (xy 66.529664 -246.882892)
			(xy 66.599199 -246.867022) (xy 66.670073 -246.859036) (xy 66.705734 -246.858536) (xy 66.741395 -246.859036)
			(xy 66.812269 -246.867022) (xy 66.881804 -246.882892) (xy 66.949124 -246.906449) (xy 67.013383 -246.937394)
			(xy 67.073774 -246.97534) (xy 67.129536 -247.019809) (xy 67.179969 -247.070242) (xy 67.224438 -247.126004)
			(xy 67.262384 -247.186395) (xy 67.293329 -247.250654) (xy 67.316886 -247.317974) (xy 67.332756 -247.387509)
			(xy 67.340742 -247.458383) (xy 67.340742 -247.529705) (xy 69.062338 -247.529705) (xy 69.062338 -247.458383)
			(xy 69.070324 -247.387509) (xy 69.086194 -247.317974) (xy 69.109751 -247.250654) (xy 69.140696 -247.186395)
			(xy 69.178642 -247.126004) (xy 69.223111 -247.070242) (xy 69.273544 -247.019809) (xy 69.329306 -246.97534)
			(xy 69.389697 -246.937394) (xy 69.453956 -246.906449) (xy 69.521276 -246.882892) (xy 69.590811 -246.867022)
			(xy 69.661685 -246.859036) (xy 69.697346 -246.858536) (xy 69.733007 -246.859036) (xy 69.803881 -246.867022)
			(xy 69.873416 -246.882892) (xy 69.940736 -246.906449) (xy 70.004995 -246.937394) (xy 70.065386 -246.97534)
			(xy 70.121148 -247.019809) (xy 70.171581 -247.070242) (xy 70.21605 -247.126004) (xy 70.253996 -247.186395)
			(xy 70.284941 -247.250654) (xy 70.308498 -247.317974) (xy 70.324368 -247.387509) (xy 70.332354 -247.458383)
			(xy 70.332354 -247.529705) (xy 70.324368 -247.600579) (xy 70.308498 -247.670114) (xy 70.284941 -247.737434)
			(xy 70.253996 -247.801693) (xy 70.21605 -247.862084) (xy 70.171581 -247.917846) (xy 70.121148 -247.968279)
			(xy 70.065386 -248.012748) (xy 70.004995 -248.050694) (xy 69.940736 -248.081639) (xy 69.873416 -248.105196)
			(xy 69.803881 -248.121066) (xy 69.733007 -248.129052) (xy 69.661685 -248.129052) (xy 69.590811 -248.121066)
			(xy 69.521276 -248.105196) (xy 69.453956 -248.081639) (xy 69.389697 -248.050694) (xy 69.329306 -248.012748)
			(xy 69.273544 -247.968279) (xy 69.223111 -247.917846) (xy 69.178642 -247.862084) (xy 69.140696 -247.801693)
			(xy 69.109751 -247.737434) (xy 69.086194 -247.670114) (xy 69.070324 -247.600579) (xy 69.062338 -247.529705)
			(xy 67.340742 -247.529705) (xy 67.332756 -247.600579) (xy 67.316886 -247.670114) (xy 67.293329 -247.737434)
			(xy 67.262384 -247.801693) (xy 67.224438 -247.862084) (xy 67.179969 -247.917846) (xy 67.129536 -247.968279)
			(xy 67.073774 -248.012748) (xy 67.013383 -248.050694) (xy 66.949124 -248.081639) (xy 66.881804 -248.105196)
			(xy 66.812269 -248.121066) (xy 66.741395 -248.129052) (xy 66.670073 -248.129052) (xy 66.599199 -248.121066)
			(xy 66.529664 -248.105196) (xy 66.462344 -248.081639) (xy 66.398085 -248.050694) (xy 66.337694 -248.012748)
			(xy 66.281932 -247.968279) (xy 66.231499 -247.917846) (xy 66.18703 -247.862084) (xy 66.149084 -247.801693)
			(xy 66.118139 -247.737434) (xy 66.094582 -247.670114) (xy 66.078712 -247.600579) (xy 66.070726 -247.529705)
			(xy 42.829067 -247.529705) (xy 42.815026 -247.547248) (xy 42.76462 -247.597497) (xy 42.708915 -247.641799)
			(xy 42.648608 -247.679599) (xy 42.584454 -247.710424) (xy 42.517258 -247.733886) (xy 42.447862 -247.749693)
			(xy 42.377133 -247.757646) (xy 42.305959 -247.757646) (xy 42.23523 -247.749693) (xy 42.165834 -247.733886)
			(xy 42.098638 -247.710424) (xy 42.034484 -247.679599) (xy 41.974177 -247.641799) (xy 41.918472 -247.597497)
			(xy 41.868066 -247.547248) (xy 41.82359 -247.491681) (xy 41.785603 -247.431492) (xy 41.754579 -247.367435)
			(xy 41.730907 -247.300313) (xy 41.714884 -247.230966) (xy 41.70671 -247.160262) (xy 41.706488 -247.089088)
			(xy 41.714221 -247.018336) (xy 41.721532 -246.983504) (xy 41.725923 -246.961172) (xy 41.727779 -246.915704)
			(xy 41.721508 -246.870634) (xy 41.70731 -246.8274) (xy 41.685639 -246.787387) (xy 41.657188 -246.751872)
			(xy 41.622867 -246.721993) (xy 41.583774 -246.698704) (xy 41.541157 -246.682749) (xy 41.49638 -246.67464)
			(xy 41.473628 -246.674132) (xy 36.623244 -246.674132) (xy 36.60009 -246.674591) (xy 36.554553 -246.683008)
			(xy 36.511294 -246.699534) (xy 36.471744 -246.723624) (xy 36.437212 -246.754479) (xy 36.408841 -246.79108)
			(xy 36.38757 -246.832214) (xy 36.374102 -246.87652) (xy 36.368883 -246.922534) (xy 36.372085 -246.968732)
			(xy 36.383603 -247.013585) (xy 36.392866 -247.034812) (xy 36.41055 -247.074219) (xy 36.439515 -247.155597)
			(xy 36.460898 -247.239289) (xy 36.474518 -247.324588) (xy 36.480261 -247.410776) (xy 36.478079 -247.497128)
			(xy 36.46799 -247.582916) (xy 36.450079 -247.667419) (xy 36.424497 -247.749923) (xy 36.391459 -247.829735)
			(xy 36.371784 -247.868186) (xy 36.362065 -247.887659) (xy 36.348665 -247.929062) (xy 36.342519 -247.972143)
			(xy 36.343805 -248.015641) (xy 36.352487 -248.058283) (xy 36.368309 -248.098822) (xy 36.39081 -248.136071)
			(xy 36.419331 -248.16894) (xy 36.453036 -248.196466) (xy 36.49094 -248.217845) (xy 36.531933 -248.23245)
			(xy 36.574815 -248.239855) (xy 36.596574 -248.240296) (xy 43.77817 -248.240296) (xy 44.009056 -248.471182)
			(xy 44.021126 -248.482653) (xy 44.049931 -248.499339) (xy 44.082074 -248.508002) (xy 44.098718 -248.50852)
			(xy 44.455588 -248.50852) (xy 44.487202 -248.509066) (xy 44.54989 -248.517317) (xy 44.610965 -248.533681)
			(xy 44.669381 -248.557876) (xy 44.724139 -248.58949) (xy 44.774302 -248.62798) (xy 44.819012 -248.672689)
			(xy 44.857504 -248.722851) (xy 44.889118 -248.777608) (xy 44.913315 -248.836024) (xy 44.92968 -248.897098)
			(xy 44.937934 -248.959786) (xy 44.937934 -249.023014) (xy 44.92968 -249.085702) (xy 44.913315 -249.146776)
			(xy 44.889118 -249.205192) (xy 44.857504 -249.259949) (xy 44.819012 -249.310111) (xy 44.774302 -249.35482)
			(xy 44.724139 -249.39331) (xy 44.669381 -249.424924) (xy 44.610965 -249.449119) (xy 44.54989 -249.465483)
			(xy 44.487202 -249.473734) (xy 44.455588 -249.474228) (xy 43.645836 -249.474228) (xy 43.377866 -249.206512)
			(xy 43.166284 -249.206512) (xy 43.143711 -249.206989) (xy 43.099279 -249.214985) (xy 43.056958 -249.230706)
			(xy 43.018081 -249.253657) (xy 42.98387 -249.283115) (xy 42.955401 -249.318154) (xy 42.933571 -249.357672)
			(xy 42.919067 -249.400425) (xy 42.912344 -249.445068) (xy 42.913614 -249.490196) (xy 42.914119 -249.492617)
			(xy 66.070726 -249.492617) (xy 66.070726 -249.421295) (xy 66.078712 -249.350421) (xy 66.094582 -249.280886)
			(xy 66.118139 -249.213566) (xy 66.149084 -249.149307) (xy 66.18703 -249.088916) (xy 66.231499 -249.033154)
			(xy 66.281932 -248.982721) (xy 66.337694 -248.938252) (xy 66.398085 -248.900306) (xy 66.462344 -248.869361)
			(xy 66.529664 -248.845804) (xy 66.599199 -248.829934) (xy 66.670073 -248.821948) (xy 66.705734 -248.821448)
			(xy 66.741395 -248.821948) (xy 66.812269 -248.829934) (xy 66.881804 -248.845804) (xy 66.949124 -248.869361)
			(xy 67.013383 -248.900306) (xy 67.073774 -248.938252) (xy 67.129536 -248.982721) (xy 67.179969 -249.033154)
			(xy 67.224438 -249.088916) (xy 67.262384 -249.149307) (xy 67.293329 -249.213566) (xy 67.316886 -249.280886)
			(xy 67.332756 -249.350421) (xy 67.340742 -249.421295) (xy 67.340742 -249.492617) (xy 69.062338 -249.492617)
			(xy 69.062338 -249.421295) (xy 69.070324 -249.350421) (xy 69.086194 -249.280886) (xy 69.109751 -249.213566)
			(xy 69.140696 -249.149307) (xy 69.178642 -249.088916) (xy 69.223111 -249.033154) (xy 69.273544 -248.982721)
			(xy 69.329306 -248.938252) (xy 69.389697 -248.900306) (xy 69.453956 -248.869361) (xy 69.521276 -248.845804)
			(xy 69.590811 -248.829934) (xy 69.661685 -248.821948) (xy 69.697346 -248.821448) (xy 69.733007 -248.821948)
			(xy 69.803881 -248.829934) (xy 69.873416 -248.845804) (xy 69.940736 -248.869361) (xy 70.004995 -248.900306)
			(xy 70.065386 -248.938252) (xy 70.121148 -248.982721) (xy 70.171581 -249.033154) (xy 70.21605 -249.088916)
			(xy 70.253996 -249.149307) (xy 70.284941 -249.213566) (xy 70.308498 -249.280886) (xy 70.324368 -249.350421)
			(xy 70.332354 -249.421295) (xy 70.332354 -249.492617) (xy 70.324368 -249.563491) (xy 70.308498 -249.633026)
			(xy 70.284941 -249.700346) (xy 70.253996 -249.764605) (xy 70.21605 -249.824996) (xy 70.171581 -249.880758)
			(xy 70.121148 -249.931191) (xy 70.065386 -249.97566) (xy 70.004995 -250.013606) (xy 69.940736 -250.044551)
			(xy 69.873416 -250.068108) (xy 69.803881 -250.083978) (xy 69.733007 -250.091964) (xy 69.661685 -250.091964)
			(xy 69.590811 -250.083978) (xy 69.521276 -250.068108) (xy 69.453956 -250.044551) (xy 69.389697 -250.013606)
			(xy 69.329306 -249.97566) (xy 69.273544 -249.931191) (xy 69.223111 -249.880758) (xy 69.178642 -249.824996)
			(xy 69.140696 -249.764605) (xy 69.109751 -249.700346) (xy 69.086194 -249.633026) (xy 69.070324 -249.563491)
			(xy 69.062338 -249.492617) (xy 67.340742 -249.492617) (xy 67.332756 -249.563491) (xy 67.316886 -249.633026)
			(xy 67.293329 -249.700346) (xy 67.262384 -249.764605) (xy 67.224438 -249.824996) (xy 67.179969 -249.880758)
			(xy 67.129536 -249.931191) (xy 67.073774 -249.97566) (xy 67.013383 -250.013606) (xy 66.949124 -250.044551)
			(xy 66.881804 -250.068108) (xy 66.812269 -250.083978) (xy 66.741395 -250.091964) (xy 66.670073 -250.091964)
			(xy 66.599199 -250.083978) (xy 66.529664 -250.068108) (xy 66.462344 -250.044551) (xy 66.398085 -250.013606)
			(xy 66.337694 -249.97566) (xy 66.281932 -249.931191) (xy 66.231499 -249.880758) (xy 66.18703 -249.824996)
			(xy 66.149084 -249.764605) (xy 66.118139 -249.700346) (xy 66.094582 -249.633026) (xy 66.078712 -249.563491)
			(xy 66.070726 -249.492617) (xy 42.914119 -249.492617) (xy 42.922837 -249.53439) (xy 42.930826 -249.555508)
			(xy 42.944344 -249.590399) (xy 42.964008 -249.662599) (xy 42.97506 -249.736607) (xy 42.977345 -249.811402)
			(xy 42.970832 -249.885947) (xy 42.955612 -249.959212) (xy 42.931895 -250.030183) (xy 42.900008 -250.097879)
			(xy 42.860394 -250.161362) (xy 42.813599 -250.219754) (xy 42.787316 -250.246388) (xy 42.771259 -250.263008)
			(xy 42.744756 -250.300856) (xy 42.725533 -250.342872) (xy 42.714224 -250.387672) (xy 42.711202 -250.433778)
			(xy 42.716567 -250.47967) (xy 42.730141 -250.523836) (xy 42.751477 -250.564819) (xy 42.779872 -250.601269)
			(xy 42.81439 -250.631984) (xy 42.853893 -250.655952) (xy 42.897078 -250.672381) (xy 42.942522 -250.680731)
			(xy 42.965624 -250.681236) (xy 43.944032 -250.681236) (xy 44.22902 -250.966224) (xy 44.638468 -250.966224)
			(xy 44.670104 -250.966653) (xy 44.732834 -250.974908) (xy 44.79395 -250.99128) (xy 44.852406 -251.01549)
			(xy 44.907202 -251.047123) (xy 44.9574 -251.085638) (xy 45.002141 -251.130376) (xy 45.040659 -251.180572)
			(xy 45.072296 -251.235365) (xy 45.096509 -251.29382) (xy 45.112886 -251.354935) (xy 45.121145 -251.417664)
			(xy 45.121145 -251.480936) (xy 45.112886 -251.543665) (xy 45.096509 -251.60478) (xy 45.083526 -251.636123)
			(xy 66.070726 -251.636123) (xy 66.070726 -251.564801) (xy 66.078712 -251.493927) (xy 66.094582 -251.424392)
			(xy 66.118139 -251.357072) (xy 66.149084 -251.292813) (xy 66.18703 -251.232422) (xy 66.231499 -251.17666)
			(xy 66.281932 -251.126227) (xy 66.337694 -251.081758) (xy 66.398085 -251.043812) (xy 66.462344 -251.012867)
			(xy 66.529664 -250.98931) (xy 66.599199 -250.97344) (xy 66.670073 -250.965454) (xy 66.705734 -250.964954)
			(xy 66.741395 -250.965454) (xy 66.812269 -250.97344) (xy 66.881804 -250.98931) (xy 66.949124 -251.012867)
			(xy 67.013383 -251.043812) (xy 67.073774 -251.081758) (xy 67.129536 -251.126227) (xy 67.179969 -251.17666)
			(xy 67.224438 -251.232422) (xy 67.262384 -251.292813) (xy 67.293329 -251.357072) (xy 67.316886 -251.424392)
			(xy 67.332756 -251.493927) (xy 67.340742 -251.564801) (xy 67.340742 -251.636123) (xy 69.062338 -251.636123)
			(xy 69.062338 -251.564801) (xy 69.070324 -251.493927) (xy 69.086194 -251.424392) (xy 69.109751 -251.357072)
			(xy 69.140696 -251.292813) (xy 69.178642 -251.232422) (xy 69.223111 -251.17666) (xy 69.273544 -251.126227)
			(xy 69.329306 -251.081758) (xy 69.389697 -251.043812) (xy 69.453956 -251.012867) (xy 69.521276 -250.98931)
			(xy 69.590811 -250.97344) (xy 69.661685 -250.965454) (xy 69.697346 -250.964954) (xy 69.733007 -250.965454)
			(xy 69.803881 -250.97344) (xy 69.873416 -250.98931) (xy 69.940736 -251.012867) (xy 70.004995 -251.043812)
			(xy 70.065386 -251.081758) (xy 70.121148 -251.126227) (xy 70.171581 -251.17666) (xy 70.21605 -251.232422)
			(xy 70.253996 -251.292813) (xy 70.284941 -251.357072) (xy 70.308498 -251.424392) (xy 70.324368 -251.493927)
			(xy 70.332354 -251.564801) (xy 70.332354 -251.636123) (xy 70.324368 -251.706997) (xy 70.308498 -251.776532)
			(xy 70.284941 -251.843852) (xy 70.253996 -251.908111) (xy 70.21605 -251.968502) (xy 70.171581 -252.024264)
			(xy 70.121148 -252.074697) (xy 70.065386 -252.119166) (xy 70.004995 -252.157112) (xy 69.940736 -252.188057)
			(xy 69.873416 -252.211614) (xy 69.803881 -252.227484) (xy 69.733007 -252.23547) (xy 69.661685 -252.23547)
			(xy 69.590811 -252.227484) (xy 69.521276 -252.211614) (xy 69.453956 -252.188057) (xy 69.389697 -252.157112)
			(xy 69.329306 -252.119166) (xy 69.273544 -252.074697) (xy 69.223111 -252.024264) (xy 69.178642 -251.968502)
			(xy 69.140696 -251.908111) (xy 69.109751 -251.843852) (xy 69.086194 -251.776532) (xy 69.070324 -251.706997)
			(xy 69.062338 -251.636123) (xy 67.340742 -251.636123) (xy 67.332756 -251.706997) (xy 67.316886 -251.776532)
			(xy 67.293329 -251.843852) (xy 67.262384 -251.908111) (xy 67.224438 -251.968502) (xy 67.179969 -252.024264)
			(xy 67.129536 -252.074697) (xy 67.073774 -252.119166) (xy 67.013383 -252.157112) (xy 66.949124 -252.188057)
			(xy 66.881804 -252.211614) (xy 66.812269 -252.227484) (xy 66.741395 -252.23547) (xy 66.670073 -252.23547)
			(xy 66.599199 -252.227484) (xy 66.529664 -252.211614) (xy 66.462344 -252.188057) (xy 66.398085 -252.157112)
			(xy 66.337694 -252.119166) (xy 66.281932 -252.074697) (xy 66.231499 -252.024264) (xy 66.18703 -251.968502)
			(xy 66.149084 -251.908111) (xy 66.118139 -251.843852) (xy 66.094582 -251.776532) (xy 66.078712 -251.706997)
			(xy 66.070726 -251.636123) (xy 45.083526 -251.636123) (xy 45.072296 -251.663235) (xy 45.040659 -251.718028)
			(xy 45.002141 -251.768224) (xy 44.9574 -251.812962) (xy 44.907202 -251.851477) (xy 44.852406 -251.88311)
			(xy 44.79395 -251.90732) (xy 44.732834 -251.923692) (xy 44.670104 -251.931947) (xy 44.638468 -251.93244)
			(xy 43.828716 -251.93244) (xy 43.543728 -251.647452) (xy 43.032172 -251.647452) (xy 43.010156 -251.647865)
			(xy 42.966785 -251.655477) (xy 42.925376 -251.670451) (xy 42.887168 -251.692338) (xy 42.853304 -251.720484)
			(xy 42.824799 -251.754046) (xy 42.802505 -251.792018) (xy 42.78709 -251.833265) (xy 42.779016 -251.876552)
			(xy 42.778524 -251.920583) (xy 42.785629 -251.964039) (xy 42.800118 -252.00562) (xy 42.821558 -252.044081)
			(xy 42.835068 -252.061472) (xy 42.857235 -252.089577) (xy 42.895794 -252.149885) (xy 42.927333 -252.214145)
			(xy 42.95145 -252.281542) (xy 42.967841 -252.351223) (xy 42.976297 -252.422303) (xy 42.976712 -252.493884)
			(xy 42.969081 -252.565058) (xy 42.953499 -252.634924) (xy 42.930165 -252.702596) (xy 42.899374 -252.767217)
			(xy 42.861517 -252.827969) (xy 42.817072 -252.884082) (xy 42.766603 -252.934845) (xy 42.710749 -252.979614)
			(xy 42.650217 -253.017824) (xy 42.585776 -253.048989) (xy 42.51824 -253.072715) (xy 42.448466 -253.088701)
			(xy 42.377337 -253.096745) (xy 42.305755 -253.096745) (xy 42.234626 -253.088701) (xy 42.164852 -253.072715)
			(xy 42.097316 -253.048989) (xy 42.032875 -253.017824) (xy 41.972343 -252.979614) (xy 41.916489 -252.934845)
			(xy 41.86602 -252.884082) (xy 41.821575 -252.827969) (xy 41.783718 -252.767217) (xy 41.752927 -252.702596)
			(xy 41.729593 -252.634924) (xy 41.714011 -252.565058) (xy 41.70638 -252.493884) (xy 41.706795 -252.422303)
			(xy 41.715251 -252.351223) (xy 41.731642 -252.281542) (xy 41.755759 -252.214145) (xy 41.787298 -252.149885)
			(xy 41.825857 -252.089577) (xy 41.848024 -252.061472) (xy 41.861496 -252.044048) (xy 41.882964 -252.005599)
			(xy 41.897477 -251.964023) (xy 41.904602 -251.920566) (xy 41.904124 -251.876533) (xy 41.896058 -251.833241)
			(xy 41.880645 -251.79199) (xy 41.858347 -251.754016) (xy 41.829833 -251.720458) (xy 41.795958 -251.692321)
			(xy 41.757738 -251.670449) (xy 41.716317 -251.655497) (xy 41.672938 -251.647915) (xy 41.65092 -251.647452)
			(xy 36.56711 -251.647452) (xy 36.54483 -251.648009) (xy 36.500958 -251.655814) (xy 36.45912 -251.671153)
			(xy 36.420599 -251.693554) (xy 36.386576 -251.722331) (xy 36.358095 -251.756601) (xy 36.336027 -251.795314)
			(xy 36.321051 -251.837283) (xy 36.313624 -251.88122) (xy 36.313976 -251.92578) (xy 36.322095 -251.969595)
			(xy 36.337731 -252.011322) (xy 36.34867 -252.030738) (xy 36.37115 -252.069675) (xy 36.409405 -252.151047)
			(xy 36.439716 -252.2357) (xy 36.461806 -252.32286) (xy 36.475472 -252.411731) (xy 36.480591 -252.501501)
			(xy 36.477114 -252.59135) (xy 36.465075 -252.680456) (xy 36.444582 -252.768005) (xy 36.415824 -252.853198)
			(xy 36.379063 -252.935256) (xy 36.357306 -252.974602) (xy 36.346807 -252.994036) (xy 36.332007 -253.035652)
			(xy 36.324626 -253.0792) (xy 36.324885 -253.123369) (xy 36.332776 -253.166827) (xy 36.348062 -253.208267)
			(xy 36.370282 -253.24644) (xy 36.398767 -253.280197) (xy 36.43266 -253.30852) (xy 36.470939 -253.330557)
			(xy 36.512452 -253.345643) (xy 36.555948 -253.353326) (xy 36.578032 -253.353824) (xy 43.932602 -253.353824)
			(xy 44.222416 -253.06401) (xy 44.245149 -253.042008) (xy 44.295341 -253.003495) (xy 44.35013 -252.971862)
			(xy 44.40858 -252.947651) (xy 44.469689 -252.931277) (xy 44.532413 -252.923019) (xy 44.595679 -252.923019)
			(xy 44.658403 -252.931277) (xy 44.719512 -252.947651) (xy 44.777962 -252.971862) (xy 44.832751 -253.003495)
			(xy 44.882943 -253.042008) (xy 44.927678 -253.086743) (xy 44.966191 -253.136935) (xy 44.997824 -253.191724)
			(xy 45.022035 -253.250174) (xy 45.038409 -253.311283) (xy 45.046667 -253.374007) (xy 45.046667 -253.437273)
			(xy 45.038409 -253.499997) (xy 45.022035 -253.561106) (xy 44.997824 -253.619556) (xy 44.966191 -253.674345)
			(xy 44.927678 -253.724537) (xy 44.905676 -253.74727) (xy 44.332906 -254.32004) (xy 43.096688 -254.32004)
			(xy 43.074108 -254.320552) (xy 43.029655 -254.328517) (xy 42.98731 -254.344212) (xy 42.948405 -254.367144)
			(xy 42.914164 -254.39659) (xy 42.885666 -254.431623) (xy 42.863808 -254.471141) (xy 42.849277 -254.5139)
			(xy 42.842531 -254.558554) (xy 42.843783 -254.603697) (xy 42.852992 -254.647909) (xy 42.860976 -254.669036)
			(xy 42.873512 -254.701268) (xy 42.892288 -254.767835) (xy 42.903726 -254.836046) (xy 42.907692 -254.905096)
			(xy 42.90414 -254.974168) (xy 42.899076 -255.00838) (xy 42.896099 -255.030185) (xy 42.896634 -255.074182)
			(xy 42.904743 -255.117429) (xy 42.920181 -255.158631) (xy 42.942488 -255.196558) (xy 42.970997 -255.230073)
			(xy 43.004854 -255.258175) (xy 43.043047 -255.280023) (xy 43.084433 -255.294964) (xy 43.127774 -255.30255)
			(xy 43.149774 -255.30302) (xy 44.396152 -255.30302) (xy 44.968922 -255.87579) (xy 44.990924 -255.898523)
			(xy 45.029437 -255.948715) (xy 45.06107 -256.003504) (xy 45.085281 -256.061954) (xy 45.101655 -256.123063)
			(xy 45.109913 -256.185787) (xy 45.109913 -256.249053) (xy 45.101655 -256.311777) (xy 45.085281 -256.372886)
			(xy 45.06107 -256.431336) (xy 45.029437 -256.486125) (xy 44.990924 -256.536317) (xy 44.946189 -256.581052)
			(xy 44.895997 -256.619565) (xy 44.841208 -256.651198) (xy 44.782758 -256.675409) (xy 44.721649 -256.691783)
			(xy 44.658925 -256.700041) (xy 44.595659 -256.700041) (xy 44.532935 -256.691783) (xy 44.471826 -256.675409)
			(xy 44.413376 -256.651198) (xy 44.358587 -256.619565) (xy 44.308395 -256.581052) (xy 44.285662 -256.55905)
			(xy 43.995848 -256.269236) (xy 43.090846 -256.269236) (xy 43.068082 -256.269703) (xy 43.023284 -256.277824)
			(xy 42.98065 -256.293796) (xy 42.941544 -256.317108) (xy 42.907216 -256.347014) (xy 42.878765 -256.382558)
			(xy 42.857102 -256.422602) (xy 42.84292 -256.465864) (xy 42.836673 -256.510962) (xy 42.83856 -256.55645)
			(xy 42.84852 -256.600875) (xy 42.856912 -256.622042) (xy 42.869867 -256.653822) (xy 42.889653 -256.719541)
			(xy 42.902247 -256.787008) (xy 42.907504 -256.855439) (xy 42.905361 -256.924038) (xy 42.895845 -256.992007)
			(xy 42.8879 -257.025394) (xy 42.882824 -257.047931) (xy 42.879815 -257.09402) (xy 42.885179 -257.139896)
			(xy 42.898742 -257.184047) (xy 42.920056 -257.225024) (xy 42.94842 -257.261476) (xy 42.982902 -257.292206)
			(xy 43.022367 -257.316202) (xy 43.065517 -257.332676) (xy 43.110933 -257.341085) (xy 43.134026 -257.341624)
			(xy 43.845988 -257.341624) (xy 44.160694 -257.656076) (xy 44.570142 -257.656076) (xy 44.60177 -257.656628)
			(xy 44.664484 -257.664889) (xy 44.725583 -257.681265) (xy 44.784022 -257.705476) (xy 44.838801 -257.737107)
			(xy 44.888984 -257.775617) (xy 44.93371 -257.820348) (xy 44.972216 -257.870534) (xy 45.003842 -257.925316)
			(xy 45.028048 -257.983757) (xy 45.044419 -258.044857) (xy 45.052675 -258.107572) (xy 45.052675 -258.170828)
			(xy 45.044419 -258.233543) (xy 45.028048 -258.294643) (xy 45.003843 -258.353084) (xy 44.972216 -258.407866)
			(xy 44.93371 -258.458052) (xy 44.888984 -258.502783) (xy 44.838801 -258.541293) (xy 44.784022 -258.572924)
			(xy 44.725583 -258.597135) (xy 44.664484 -258.613511) (xy 44.60177 -258.621772) (xy 44.570142 -258.622292)
			(xy 43.76039 -258.622292) (xy 43.482768 -258.34467) (xy 43.470682 -258.333218) (xy 43.441885 -258.316524)
			(xy 43.409748 -258.307854) (xy 43.393106 -258.307332) (xy 43.038014 -258.307332) (xy 43.015724 -258.307696)
			(xy 42.971823 -258.315453) (xy 42.92995 -258.330749) (xy 42.891386 -258.353116) (xy 42.857316 -258.381867)
			(xy 42.828783 -258.41612) (xy 42.806664 -258.454826) (xy 42.791635 -258.496797) (xy 42.784159 -258.540745)
			(xy 42.784464 -258.585325) (xy 42.792541 -258.629167) (xy 42.808142 -258.670928) (xy 42.819066 -258.690364)
			(xy 42.836988 -258.721752) (xy 42.866407 -258.787777) (xy 42.888144 -258.856713) (xy 42.901919 -258.92767)
			(xy 42.907553 -258.999732) (xy 42.904975 -259.071968) (xy 42.894216 -259.143445) (xy 42.875417 -259.213239)
			(xy 42.84882 -259.28045) (xy 42.814768 -259.344209) (xy 42.773702 -259.403692) (xy 42.726152 -259.458131)
			(xy 42.672731 -259.506824) (xy 42.614131 -259.54914) (xy 42.551107 -259.584534) (xy 42.484475 -259.612548)
			(xy 42.415094 -259.632821) (xy 42.343861 -259.64509) (xy 42.271696 -259.649198) (xy 42.199531 -259.64509)
			(xy 42.128298 -259.632821) (xy 42.058917 -259.612548) (xy 41.992285 -259.584534) (xy 41.929261 -259.54914)
			(xy 41.870661 -259.506824) (xy 41.81724 -259.458131) (xy 41.76969 -259.403692) (xy 41.728624 -259.344209)
			(xy 41.694572 -259.28045) (xy 41.667975 -259.213239) (xy 41.649176 -259.143445) (xy 41.638417 -259.071968)
			(xy 41.635839 -258.999732) (xy 41.641473 -258.92767) (xy 41.655248 -258.856713) (xy 41.676985 -258.787777)
			(xy 41.706404 -258.721752) (xy 41.724326 -258.690364) (xy 41.735264 -258.670949) (xy 41.750821 -258.629192)
			(xy 41.758861 -258.585362) (xy 41.759139 -258.540802) (xy 41.751646 -258.496875) (xy 41.736611 -258.454927)
			(xy 41.714495 -258.416242) (xy 41.685975 -258.382003) (xy 41.651924 -258.353259) (xy 41.613384 -258.330891)
			(xy 41.571535 -258.315582) (xy 41.527658 -258.307802) (xy 41.505378 -258.307332) (xy 39.826438 -258.307332)
			(xy 38.775894 -259.357876) (xy 36.615878 -259.357876) (xy 36.592542 -259.3584) (xy 36.546656 -259.366925)
			(xy 36.503097 -259.383683) (xy 36.46333 -259.408111) (xy 36.42869 -259.439389) (xy 36.400343 -259.476465)
			(xy 36.37924 -259.518093) (xy 36.366092 -259.562874) (xy 36.36134 -259.609302) (xy 36.365144 -259.655818)
			(xy 36.377375 -259.700858) (xy 36.387024 -259.722112) (xy 36.404581 -259.759578) (xy 36.433773 -259.837006)
			(xy 36.456047 -259.9167) (xy 36.471231 -259.998042) (xy 36.479207 -260.080405) (xy 36.479215 -260.081286)
			(xy 44.296075 -260.081286) (xy 44.302175 -260.025849) (xy 44.316281 -259.971892) (xy 44.338093 -259.920563)
			(xy 44.367147 -259.872957) (xy 44.402822 -259.830089) (xy 44.444359 -259.792872) (xy 44.490872 -259.762099)
			(xy 44.541369 -259.738427) (xy 44.594776 -259.722359) (xy 44.649952 -259.714239) (xy 44.677838 -259.71373)
			(xy 44.705724 -259.714239) (xy 44.7609 -259.722359) (xy 44.814307 -259.738427) (xy 44.864804 -259.762099)
			(xy 44.911317 -259.792872) (xy 44.952854 -259.830089) (xy 44.988529 -259.872957) (xy 45.017583 -259.920563)
			(xy 45.039395 -259.971892) (xy 45.053501 -260.025849) (xy 45.059601 -260.081286) (xy 45.057564 -260.13702)
			(xy 45.047434 -260.191863) (xy 45.029427 -260.244647) (xy 45.003926 -260.294247) (xy 44.971475 -260.339605)
			(xy 44.932766 -260.379754) (xy 44.888623 -260.41384) (xy 44.839988 -260.441136) (xy 44.787897 -260.461059)
			(xy 44.73346 -260.473185) (xy 44.677838 -260.477256) (xy 44.622216 -260.473185) (xy 44.567779 -260.461059)
			(xy 44.515688 -260.441136) (xy 44.467053 -260.41384) (xy 44.42291 -260.379754) (xy 44.384201 -260.339605)
			(xy 44.35175 -260.294247) (xy 44.326249 -260.244647) (xy 44.308242 -260.191863) (xy 44.298112 -260.13702)
			(xy 44.296075 -260.081286) (xy 36.479215 -260.081286) (xy 36.479913 -260.16315) (xy 36.473345 -260.245637)
			(xy 36.459552 -260.327227) (xy 36.438642 -260.407289) (xy 36.410776 -260.485204) (xy 36.393882 -260.522974)
			(xy 36.384762 -260.544223) (xy 36.373405 -260.589039) (xy 36.370341 -260.63517) (xy 36.375673 -260.681095)
			(xy 36.389224 -260.725297) (xy 36.410546 -260.766319) (xy 36.438938 -260.802808) (xy 36.473461 -260.833559)
			(xy 36.512977 -260.857557) (xy 36.556183 -260.874013) (xy 36.601652 -260.882381) (xy 36.624768 -260.882892)
			(xy 47.526956 -260.882892) (xy 48.223424 -260.186424) (xy 63.859156 -260.186424) (xy 80.55864 -243.487194)
			(xy 80.570025 -243.475075) (xy 80.586615 -243.446269) (xy 80.595192 -243.414153) (xy 80.595724 -243.397532)
			(xy 80.595724 -239.272572) (xy 80.579722 -239.24387) (xy 80.566819 -239.219524) (xy 80.547359 -239.167976)
			(xy 80.535518 -239.114165) (xy 80.531543 -239.059211) (xy 80.535515 -239.004255) (xy 80.547353 -238.950444)
			(xy 80.566811 -238.898895) (xy 80.579722 -238.874554) (xy 80.595724 -238.845852) (xy 80.595724 -235.877354)
			(xy 82.647028 -233.82605) (xy 82.647028 -231.442006) (xy 82.646421 -231.41866) (xy 82.63791 -231.372752)
			(xy 82.621155 -231.329172) (xy 82.59672 -231.289386) (xy 82.565427 -231.254734) (xy 82.52833 -231.226382)
			(xy 82.486678 -231.205285) (xy 82.441872 -231.192152) (xy 82.395421 -231.187427) (xy 82.348889 -231.191268)
			(xy 82.326226 -231.196896) (xy 82.290077 -231.206257) (xy 82.216354 -231.218166) (xy 82.141789 -231.222289)
			(xy 82.067202 -231.218582) (xy 81.993414 -231.207085) (xy 81.921235 -231.187925) (xy 81.85146 -231.161312)
			(xy 81.784854 -231.127539) (xy 81.722152 -231.086977) (xy 81.664041 -231.040073) (xy 81.611162 -230.987341)
			(xy 81.564094 -230.929362) (xy 81.523357 -230.866773) (xy 81.489398 -230.800263) (xy 81.46259 -230.730562)
			(xy 81.443227 -230.658437) (xy 81.431524 -230.584681) (xy 81.427608 -230.510105) (xy 81.431523 -230.435529)
			(xy 81.443225 -230.361773) (xy 81.462586 -230.289648) (xy 81.489393 -230.219947) (xy 81.523352 -230.153436)
			(xy 81.564088 -230.090847) (xy 81.611155 -230.032867) (xy 81.664033 -229.980134) (xy 81.722143 -229.933229)
			(xy 81.784845 -229.892666) (xy 81.85145 -229.858892) (xy 81.921225 -229.832278) (xy 81.993404 -229.813117)
			(xy 82.067192 -229.801619) (xy 82.141778 -229.797911) (xy 82.216343 -229.802033) (xy 82.290066 -229.813941)
			(xy 82.326226 -229.823264) (xy 82.348905 -229.828824) (xy 82.395434 -229.83266) (xy 82.44188 -229.827935)
			(xy 82.486683 -229.814807) (xy 82.528335 -229.793718) (xy 82.565435 -229.765378) (xy 82.596736 -229.730738)
			(xy 82.621185 -229.690966) (xy 82.637959 -229.647397) (xy 82.646495 -229.601497) (xy 82.647028 -229.578154)
			(xy 82.647028 -229.106984) (xy 86.238842 -225.514916) (xy 91.94546 -225.514916) (xy 93.189552 -226.759008)
			(xy 93.189552 -227.899722) (xy 92.246196 -228.842824) (xy 92.140278 -228.842824) (xy 92.12362 -228.843276)
			(xy 92.091441 -228.851904) (xy 92.062592 -228.868567) (xy 92.039039 -228.892129) (xy 92.022386 -228.920984)
			(xy 92.01377 -228.953166) (xy 92.013278 -228.969824) (xy 92.013278 -229.016052) (xy 92.072206 -229.086664)
			(xy 92.117418 -229.094792) (xy 92.153904 -229.101927) (xy 92.225255 -229.122819) (xy 92.29404 -229.151035)
			(xy 92.359509 -229.186268) (xy 92.420949 -229.228133) (xy 92.47769 -229.276175) (xy 92.529113 -229.32987)
			(xy 92.57466 -229.388632) (xy 92.613833 -229.451822) (xy 92.646206 -229.518752) (xy 92.671426 -229.588691)
			(xy 92.689217 -229.660878) (xy 92.699387 -229.734526) (xy 92.701825 -229.808834) (xy 92.696503 -229.88299)
			(xy 92.683481 -229.956188) (xy 92.662899 -230.02763) (xy 92.634982 -230.096537) (xy 92.600034 -230.162159)
			(xy 92.558437 -230.22378) (xy 92.510642 -230.280729) (xy 92.457172 -230.332386) (xy 92.398608 -230.378187)
			(xy 92.367354 -230.39832) (xy 92.353941 -230.407229) (xy 92.331788 -230.430589) (xy 92.316188 -230.45875)
			(xy 92.31044 -230.480991) (xy 93.154757 -230.480991) (xy 93.160779 -230.364808) (xy 93.174802 -230.249317)
			(xy 93.19676 -230.135069) (xy 93.226547 -230.022608) (xy 93.264022 -229.91247) (xy 93.309007 -229.80518)
			(xy 93.361286 -229.701249) (xy 93.420611 -229.601173) (xy 93.486699 -229.505427) (xy 93.559235 -229.41447)
			(xy 93.637874 -229.328734) (xy 93.72224 -229.248627) (xy 93.811932 -229.174531) (xy 93.906522 -229.106801)
			(xy 94.00556 -229.045757) (xy 94.108573 -228.991692) (xy 94.21507 -228.944862) (xy 94.324545 -228.905491)
			(xy 94.436475 -228.873767) (xy 94.550327 -228.849841) (xy 94.665559 -228.833827) (xy 94.781621 -228.8258)
			(xy 94.83979 -228.825298) (xy 94.897959 -228.8258) (xy 95.014021 -228.833827) (xy 95.129253 -228.849841)
			(xy 95.243105 -228.873767) (xy 95.355035 -228.905491) (xy 95.46451 -228.944862) (xy 95.571007 -228.991692)
			(xy 95.67402 -229.045757) (xy 95.773058 -229.106801) (xy 95.867648 -229.174531) (xy 95.95734 -229.248627)
			(xy 96.041706 -229.328734) (xy 96.120345 -229.41447) (xy 96.192881 -229.505427) (xy 96.258969 -229.601173)
			(xy 96.318294 -229.701249) (xy 96.370573 -229.80518) (xy 96.415558 -229.91247) (xy 96.453033 -230.022608)
			(xy 96.48282 -230.135069) (xy 96.504778 -230.249317) (xy 96.518801 -230.364808) (xy 96.524823 -230.480991)
			(xy 96.522815 -230.597313) (xy 96.512786 -230.713219) (xy 96.494785 -230.828156) (xy 96.468897 -230.941579)
			(xy 96.435246 -231.052944) (xy 96.393992 -231.161723) (xy 96.345331 -231.267397) (xy 96.289495 -231.369461)
			(xy 96.226752 -231.46743) (xy 96.157398 -231.560837) (xy 96.081766 -231.649237) (xy 96.000215 -231.732208)
			(xy 95.913134 -231.809355) (xy 95.820938 -231.88031) (xy 95.724066 -231.944736) (xy 95.622981 -232.002325)
			(xy 95.518163 -232.052802) (xy 95.410112 -232.095928) (xy 95.299344 -232.131497) (xy 95.186385 -232.159339)
			(xy 95.071775 -232.179321) (xy 94.95606 -232.191348) (xy 94.83979 -232.195364) (xy 94.72352 -232.191348)
			(xy 94.607805 -232.179321) (xy 94.493195 -232.159339) (xy 94.380236 -232.131497) (xy 94.269468 -232.095928)
			(xy 94.161417 -232.052802) (xy 94.056599 -232.002325) (xy 93.955514 -231.944736) (xy 93.858642 -231.88031)
			(xy 93.766446 -231.809355) (xy 93.679365 -231.732208) (xy 93.597814 -231.649237) (xy 93.522182 -231.560837)
			(xy 93.452828 -231.46743) (xy 93.390085 -231.369461) (xy 93.334249 -231.267397) (xy 93.285588 -231.161723)
			(xy 93.244334 -231.052944) (xy 93.210683 -230.941579) (xy 93.184795 -230.828156) (xy 93.166794 -230.713219)
			(xy 93.156765 -230.597313) (xy 93.154757 -230.480991) (xy 92.31044 -230.480991) (xy 92.308133 -230.489919)
			(xy 92.307664 -230.506016) (xy 92.307664 -232.596436) (xy 87.66429 -237.240064) (xy 87.6554 -237.27156)
			(xy 87.647331 -237.297931) (xy 87.624623 -237.348188) (xy 87.594919 -237.394653) (xy 87.558836 -237.436359)
			(xy 87.517127 -237.472438) (xy 87.470659 -237.502139) (xy 87.420401 -237.524842) (xy 87.394034 -237.532926)
			(xy 87.362538 -237.541816) (xy 85.678772 -239.225328) (xy 85.667424 -239.237479) (xy 85.650824 -239.26627)
			(xy 85.64223 -239.298373) (xy 85.641688 -239.31499) (xy 85.641688 -242.000786) (xy 85.334693 -242.307796)
			(xy 86.877655 -242.307796) (xy 86.879665 -242.117113) (xy 86.889712 -241.926684) (xy 86.907778 -241.736848)
			(xy 86.933831 -241.547942) (xy 86.967824 -241.360303) (xy 87.009697 -241.174263) (xy 87.059376 -240.990154)
			(xy 87.116772 -240.808303) (xy 87.181783 -240.629033) (xy 87.254294 -240.452663) (xy 87.334175 -240.279507)
			(xy 87.421285 -240.109872) (xy 87.515469 -239.94406) (xy 87.61656 -239.782366) (xy 87.724376 -239.625078)
			(xy 87.838728 -239.472475) (xy 87.959411 -239.324827) (xy 88.086212 -239.182399) (xy 88.218903 -239.045443)
			(xy 88.357251 -238.914202) (xy 88.501008 -238.78891) (xy 88.649919 -238.66979) (xy 88.80372 -238.557054)
			(xy 88.962136 -238.450901) (xy 89.124887 -238.351521) (xy 89.291682 -238.259091) (xy 89.462226 -238.173774)
			(xy 89.636214 -238.095722) (xy 89.813339 -238.025075) (xy 89.993284 -237.961957) (xy 90.17573 -237.906481)
			(xy 90.360353 -237.858746) (xy 90.546823 -237.818836) (xy 90.734811 -237.786823) (xy 90.923981 -237.762763)
			(xy 91.113997 -237.7467) (xy 91.304521 -237.738661) (xy 91.399868 -237.738158) (xy 91.495215 -237.738661)
			(xy 91.685739 -237.7467) (xy 91.875755 -237.762763) (xy 92.064925 -237.786823) (xy 92.252913 -237.818836)
			(xy 92.439383 -237.858746) (xy 92.624006 -237.906481) (xy 92.806452 -237.961957) (xy 92.986397 -238.025075)
			(xy 93.163522 -238.095722) (xy 93.33751 -238.173774) (xy 93.508054 -238.259091) (xy 93.674849 -238.351521)
			(xy 93.8376 -238.450901) (xy 93.996016 -238.557054) (xy 94.149817 -238.66979) (xy 94.298728 -238.78891)
			(xy 94.442485 -238.914202) (xy 94.580833 -239.045443) (xy 94.713524 -239.182399) (xy 94.840325 -239.324827)
			(xy 94.961008 -239.472475) (xy 95.07536 -239.625078) (xy 95.183176 -239.782366) (xy 95.284267 -239.94406)
			(xy 95.378451 -240.109872) (xy 95.465561 -240.279507) (xy 95.545442 -240.452663) (xy 95.617953 -240.629033)
			(xy 95.682964 -240.808303) (xy 95.74036 -240.990154) (xy 95.790039 -241.174263) (xy 95.831912 -241.360303)
			(xy 95.865905 -241.547942) (xy 95.891958 -241.736848) (xy 95.910024 -241.926684) (xy 95.920071 -242.117113)
			(xy 95.922081 -242.307796) (xy 95.916051 -242.498395) (xy 95.901992 -242.688569) (xy 95.879927 -242.877982)
			(xy 95.849898 -243.066297) (xy 95.811956 -243.253178) (xy 95.76617 -243.438294) (xy 95.712621 -243.621314)
			(xy 95.651403 -243.801915) (xy 95.582627 -243.979774) (xy 95.506414 -244.154576) (xy 95.4229 -244.32601)
			(xy 95.332233 -244.49377) (xy 95.234574 -244.657559) (xy 95.130097 -244.817086) (xy 95.018988 -244.972067)
			(xy 94.901445 -245.122225) (xy 94.777675 -245.267295) (xy 94.6479 -245.407019) (xy 94.512351 -245.541147)
			(xy 94.371267 -245.669441) (xy 94.2249 -245.791675) (xy 94.073511 -245.907629) (xy 93.917368 -246.017098)
			(xy 93.756749 -246.119887) (xy 93.591939 -246.215813) (xy 93.423232 -246.304707) (xy 93.250927 -246.386409)
			(xy 93.075332 -246.460775) (xy 92.896757 -246.527673) (xy 92.715521 -246.586983) (xy 92.531946 -246.6386)
			(xy 92.346358 -246.682432) (xy 92.159088 -246.718401) (xy 91.970467 -246.746444) (xy 91.780832 -246.76651)
			(xy 91.590519 -246.778564) (xy 91.399868 -246.782585) (xy 91.209217 -246.778564) (xy 91.018904 -246.76651)
			(xy 90.829269 -246.746444) (xy 90.640648 -246.718401) (xy 90.453378 -246.682432) (xy 90.26779 -246.6386)
			(xy 90.084215 -246.586983) (xy 89.902979 -246.527673) (xy 89.724404 -246.460775) (xy 89.548809 -246.386409)
			(xy 89.376504 -246.304707) (xy 89.207797 -246.215813) (xy 89.042987 -246.119887) (xy 88.882368 -246.017098)
			(xy 88.726225 -245.907629) (xy 88.574836 -245.791675) (xy 88.428469 -245.669441) (xy 88.287385 -245.541147)
			(xy 88.151836 -245.407019) (xy 88.022061 -245.267295) (xy 87.898291 -245.122225) (xy 87.780748 -244.972067)
			(xy 87.669639 -244.817086) (xy 87.565162 -244.657559) (xy 87.467503 -244.49377) (xy 87.376836 -244.32601)
			(xy 87.293322 -244.154576) (xy 87.217109 -243.979774) (xy 87.148333 -243.801915) (xy 87.087115 -243.621314)
			(xy 87.033566 -243.438294) (xy 86.98778 -243.253178) (xy 86.949838 -243.066297) (xy 86.919809 -242.877982)
			(xy 86.897744 -242.688569) (xy 86.883685 -242.498395) (xy 86.877655 -242.307796) (xy 85.334693 -242.307796)
			(xy 80.426052 -247.216676) (xy 80.410128 -247.233328) (xy 80.38395 -247.271238) (xy 80.365035 -247.313246)
			(xy 80.354004 -247.357976) (xy 80.351217 -247.403962) (xy 80.356767 -247.449696) (xy 80.37047 -247.493681)
			(xy 80.391878 -247.534475) (xy 80.42029 -247.570741) (xy 80.454775 -247.60129) (xy 80.494202 -247.625122)
			(xy 80.537279 -247.641456) (xy 80.582595 -247.649756) (xy 80.60563 -247.650254) (xy 93.117162 -247.650254)
			(xy 99.134676 -241.632994) (xy 99.146052 -241.620866) (xy 99.162647 -241.592065) (xy 99.171228 -241.559952)
			(xy 99.17176 -241.543332) (xy 99.17176 -198.785988) (xy 99.17125 -198.769369) (xy 99.16264 -198.737264)
			(xy 99.146034 -198.708471) (xy 99.134676 -198.696326) (xy 92.020644 -191.582548) (xy 91.989148 -191.573658)
			(xy 91.962769 -191.565611) (xy 91.912511 -191.542901) (xy 91.866046 -191.513194) (xy 91.82434 -191.477108)
			(xy 91.788262 -191.435395) (xy 91.758564 -191.388923) (xy 91.735863 -191.338661) (xy 91.727782 -191.312292)
			(xy 91.718892 -191.280796) (xy 91.29649 -190.858394) (xy 91.284391 -190.846956) (xy 91.255601 -190.830256)
			(xy 91.223469 -190.821581) (xy 91.206828 -190.821056) (xy 88.558878 -190.821056) (xy 85.322156 -187.584588)
			(xy 85.322156 -187.326016) (xy 85.321693 -187.30992) (xy 85.313635 -187.278753) (xy 85.298028 -187.250598)
			(xy 85.275867 -187.227248) (xy 85.262466 -187.21832) (xy 85.23111 -187.198153) (xy 85.17241 -187.152183)
			(xy 85.118838 -187.100328) (xy 85.070981 -187.043156) (xy 85.029362 -186.981295) (xy 84.994438 -186.915422)
			(xy 84.966592 -186.84626) (xy 84.946129 -186.774565) (xy 84.933272 -186.701123) (xy 84.928164 -186.626741)
			(xy 84.930859 -186.552231) (xy 84.941329 -186.478412) (xy 84.959459 -186.406092) (xy 84.985049 -186.336063)
			(xy 85.01782 -186.269093) (xy 85.057413 -186.205916) (xy 85.103393 -186.147224) (xy 85.155256 -186.09366)
			(xy 85.212435 -186.045812) (xy 85.274303 -186.004203) (xy 85.340182 -185.96929) (xy 85.409349 -185.941455)
			(xy 85.481047 -185.921003) (xy 85.55449 -185.908158) (xy 85.59165 -185.90514) (xy 85.607484 -185.903534)
			(xy 85.637679 -185.893509) (xy 85.664454 -185.876324) (xy 85.686143 -185.853048) (xy 85.701398 -185.825128)
			(xy 85.70927 -185.794302) (xy 85.70976 -185.778394) (xy 85.70976 -184.911746) (xy 85.709235 -184.895837)
			(xy 85.701388 -184.865004) (xy 85.686146 -184.837077) (xy 85.664461 -184.813796) (xy 85.637684 -184.796613)
			(xy 85.607485 -184.786601) (xy 85.59165 -184.785) (xy 85.553827 -184.781901) (xy 85.479091 -184.768697)
			(xy 85.406185 -184.747616) (xy 85.335935 -184.718898) (xy 85.26914 -184.682868) (xy 85.206558 -184.639935)
			(xy 85.148899 -184.590588) (xy 85.096818 -184.535385) (xy 85.050907 -184.474955) (xy 85.011686 -184.409982)
			(xy 84.9796 -184.341205) (xy 84.955015 -184.269405) (xy 84.938209 -184.195396) (xy 84.929373 -184.120019)
			(xy 84.928608 -184.04413) (xy 84.935921 -183.96859) (xy 84.951231 -183.894257) (xy 84.974362 -183.821976)
			(xy 85.005054 -183.752565) (xy 85.042956 -183.686815) (xy 85.087639 -183.62547) (xy 85.138596 -183.569228)
			(xy 85.195248 -183.518728) (xy 85.256951 -183.474541) (xy 85.323006 -183.437171) (xy 85.392662 -183.407041)
			(xy 85.465128 -183.384494) (xy 85.539582 -183.369786) (xy 85.615178 -183.363082) (xy 85.691059 -183.364461)
			(xy 85.766362 -183.373905) (xy 85.840232 -183.391308) (xy 85.911832 -183.416473) (xy 85.980347 -183.449112)
			(xy 86.045001 -183.488857) (xy 86.105059 -183.535255) (xy 86.159839 -183.58778) (xy 86.208719 -183.645836)
			(xy 86.251145 -183.708763) (xy 86.269322 -183.742076) (xy 86.279815 -183.760936) (xy 86.306176 -183.795106)
			(xy 86.337932 -183.82433) (xy 86.374168 -183.84777) (xy 86.413843 -183.864751) (xy 86.455816 -183.874786)
			(xy 86.498882 -183.877585) (xy 86.541801 -183.873069) (xy 86.583341 -183.861367) (xy 86.622307 -183.842815)
			(xy 86.657578 -183.817947) (xy 86.673182 -183.803036) (xy 86.701884 -183.774588) (xy 87.45855 -183.774588)
			(xy 87.47501 -183.774044) (xy 87.506832 -183.765611) (xy 87.535437 -183.749317) (xy 87.558923 -183.726248)
			(xy 87.56777 -183.712358) (xy 87.568024 -183.712104) (xy 87.587669 -183.680099) (xy 87.632549 -183.619888)
			(xy 87.68352 -183.564737) (xy 87.740015 -183.515261) (xy 87.801407 -183.472009) (xy 87.867011 -183.435462)
			(xy 87.9361 -183.406027) (xy 88.007903 -183.384031) (xy 88.081624 -183.369719) (xy 88.156443 -183.363249)
			(xy 88.231526 -183.364694) (xy 88.30604 -183.374038) (xy 88.379156 -183.391176) (xy 88.45006 -183.415919)
			(xy 88.517964 -183.44799) (xy 88.582114 -183.487034) (xy 88.641796 -183.532616) (xy 88.696346 -183.58423)
			(xy 88.745157 -183.641301) (xy 88.787687 -183.703194) (xy 88.823463 -183.769222) (xy 88.852087 -183.838651)
			(xy 88.87324 -183.910707) (xy 88.880442 -183.947562) (xy 88.892126 -184.011824) (xy 88.939624 -184.051702)
			(xy 88.95635 -184.051229) (xy 88.988665 -184.042587) (xy 89.017627 -184.025851) (xy 89.029794 -184.014364)
			(xy 89.08288 -183.961024) (xy 89.08288 -183.482996) (xy 89.08248 -183.468046) (xy 89.075548 -183.438961)
			(xy 89.06202 -183.412297) (xy 89.042643 -183.389526) (xy 89.03081 -183.38038) (xy 89.000348 -183.357564)
			(xy 88.943976 -183.306426) (xy 88.89338 -183.249566) (xy 88.84914 -183.187632) (xy 88.811758 -183.121333)
			(xy 88.781663 -183.051424) (xy 88.759197 -182.978704) (xy 88.744617 -182.904002) (xy 88.738089 -182.828171)
			(xy 88.739688 -182.752076) (xy 88.749396 -182.676586) (xy 88.767101 -182.602562) (xy 88.792602 -182.53085)
			(xy 88.825608 -182.462267) (xy 88.865742 -182.397596) (xy 88.912545 -182.337576) (xy 88.965484 -182.282892)
			(xy 89.023955 -182.234167) (xy 89.08729 -182.191957) (xy 89.154767 -182.156745) (xy 89.225615 -182.128932)
			(xy 89.299026 -182.108836) (xy 89.374161 -182.096686) (xy 89.450164 -182.09262) (xy 89.526167 -182.096686)
			(xy 89.601302 -182.108836) (xy 89.674713 -182.128932) (xy 89.745561 -182.156745) (xy 89.813038 -182.191957)
			(xy 89.876373 -182.234167) (xy 89.934844 -182.282892) (xy 89.987783 -182.337576) (xy 90.034586 -182.397596)
			(xy 90.07472 -182.462267) (xy 90.107726 -182.53085) (xy 90.133227 -182.602562) (xy 90.150932 -182.676586)
			(xy 90.16064 -182.752076) (xy 90.161355 -182.786111) (xy 91.278203 -182.786111) (xy 91.284252 -182.710541)
			(xy 91.298299 -182.636043) (xy 91.320185 -182.56346) (xy 91.349662 -182.493614) (xy 91.386397 -182.427297)
			(xy 91.429972 -182.365261) (xy 91.479894 -182.308208) (xy 91.535598 -182.256784) (xy 91.596453 -182.211573)
			(xy 91.661768 -182.173086) (xy 91.730804 -182.14176) (xy 91.802779 -182.11795) (xy 91.876877 -182.101925)
			(xy 91.952258 -182.093866) (xy 91.990164 -182.093362) (xy 92.02807 -182.093866) (xy 92.103451 -182.101925)
			(xy 92.177549 -182.11795) (xy 92.249524 -182.14176) (xy 92.31856 -182.173086) (xy 92.383875 -182.211573)
			(xy 92.44473 -182.256784) (xy 92.500434 -182.308208) (xy 92.550356 -182.365261) (xy 92.593931 -182.427297)
			(xy 92.630666 -182.493614) (xy 92.660143 -182.56346) (xy 92.682029 -182.636043) (xy 92.696076 -182.710541)
			(xy 92.702125 -182.786111) (xy 92.700106 -182.861895) (xy 92.690044 -182.937035) (xy 92.672052 -183.01068)
			(xy 92.646334 -183.081996) (xy 92.613182 -183.150173) (xy 92.57297 -183.214441) (xy 92.526155 -183.27407)
			(xy 92.473267 -183.328386) (xy 92.414905 -183.376772) (xy 92.35173 -183.41868) (xy 92.284459 -183.453636)
			(xy 92.213854 -183.481243) (xy 92.140713 -183.501189) (xy 92.065868 -183.513248) (xy 91.990164 -183.517283)
			(xy 91.91446 -183.513248) (xy 91.839615 -183.501189) (xy 91.766474 -183.481243) (xy 91.695869 -183.453636)
			(xy 91.628598 -183.41868) (xy 91.565423 -183.376772) (xy 91.507061 -183.328386) (xy 91.454173 -183.27407)
			(xy 91.407358 -183.214441) (xy 91.367146 -183.150173) (xy 91.333994 -183.081996) (xy 91.308276 -183.01068)
			(xy 91.290284 -182.937035) (xy 91.280222 -182.861895) (xy 91.278203 -182.786111) (xy 90.161355 -182.786111)
			(xy 90.162239 -182.828171) (xy 90.155711 -182.904002) (xy 90.141131 -182.978704) (xy 90.118665 -183.051424)
			(xy 90.08857 -183.121333) (xy 90.051188 -183.187632) (xy 90.006948 -183.249566) (xy 89.956352 -183.306426)
			(xy 89.89998 -183.357564) (xy 89.869518 -183.38038) (xy 89.857726 -183.38957) (xy 89.838372 -183.412343)
			(xy 89.824839 -183.43899) (xy 89.81787 -183.468053) (xy 89.817448 -183.482996) (xy 89.817448 -183.977534)
			(xy 89.891616 -184.051702) (xy 89.941146 -184.051702) (xy 90.011758 -183.992774) (xy 90.019886 -183.947562)
			(xy 90.027126 -183.910608) (xy 90.048364 -183.838359) (xy 90.077111 -183.768756) (xy 90.113046 -183.702577)
			(xy 90.155766 -183.640561) (xy 90.204795 -183.583402) (xy 90.259584 -183.531738) (xy 90.319521 -183.486147)
			(xy 90.383936 -183.447138) (xy 90.45211 -183.415148) (xy 90.523279 -183.390533) (xy 90.59665 -183.37357)
			(xy 90.671401 -183.364447) (xy 90.746698 -183.363266) (xy 90.821698 -183.370041) (xy 90.895565 -183.384697)
			(xy 90.967471 -183.407068) (xy 91.036614 -183.436906) (xy 91.10222 -183.473876) (xy 91.163557 -183.517566)
			(xy 91.219938 -183.567487) (xy 91.270735 -183.623081) (xy 91.315378 -183.683727) (xy 91.353369 -183.748747)
			(xy 91.384284 -183.817415) (xy 91.407777 -183.888963) (xy 91.423586 -183.962591) (xy 91.431533 -184.037476)
			(xy 91.431529 -184.112782) (xy 91.423576 -184.187667) (xy 91.407762 -184.261294) (xy 91.384263 -184.33284)
			(xy 91.353342 -184.401505) (xy 91.315346 -184.466522) (xy 91.270697 -184.527165) (xy 91.219896 -184.582755)
			(xy 91.16351 -184.632671) (xy 91.10217 -184.676356) (xy 91.036561 -184.713321) (xy 90.967415 -184.743152)
			(xy 90.895507 -184.765518) (xy 90.82164 -184.780167) (xy 90.746639 -184.786936) (xy 90.671342 -184.785749)
			(xy 90.596592 -184.77662) (xy 90.523222 -184.759651) (xy 90.452055 -184.73503) (xy 90.383884 -184.703034)
			(xy 90.319472 -184.66402) (xy 90.259539 -184.618424) (xy 90.204754 -184.566756) (xy 90.15573 -184.509592)
			(xy 90.113015 -184.447573) (xy 90.077086 -184.381391) (xy 90.048345 -184.311785) (xy 90.027112 -184.239534)
			(xy 90.019886 -184.202578) (xy 90.01125 -184.154064) (xy 89.944448 -184.098438) (xy 89.927792 -184.098937)
			(xy 89.895614 -184.10755) (xy 89.866763 -184.124201) (xy 89.843207 -184.147755) (xy 89.826554 -184.176604)
			(xy 89.817938 -184.208782) (xy 89.817448 -184.225438) (xy 89.817448 -184.265316) (xy 89.636854 -184.445656)
			(xy 89.633852 -184.468204) (xy 89.635061 -184.513673) (xy 89.644347 -184.558201) (xy 89.661411 -184.600363)
			(xy 89.685711 -184.638814) (xy 89.716467 -184.672324) (xy 89.752699 -184.699823) (xy 89.772744 -184.710578)
			(xy 89.806062 -184.727984) (xy 89.869107 -184.768934) (xy 89.927484 -184.816301) (xy 89.980545 -184.869556)
			(xy 90.027697 -184.928107) (xy 90.068416 -184.991301) (xy 90.102249 -185.058434) (xy 90.128818 -185.128759)
			(xy 90.147828 -185.201493) (xy 90.159066 -185.275825) (xy 90.161304 -185.326111) (xy 91.278203 -185.326111)
			(xy 91.284252 -185.250541) (xy 91.298299 -185.176043) (xy 91.320185 -185.10346) (xy 91.349662 -185.033614)
			(xy 91.386397 -184.967297) (xy 91.429972 -184.905261) (xy 91.479894 -184.848208) (xy 91.535598 -184.796784)
			(xy 91.596453 -184.751573) (xy 91.661768 -184.713086) (xy 91.730804 -184.68176) (xy 91.802779 -184.65795)
			(xy 91.876877 -184.641925) (xy 91.952258 -184.633866) (xy 91.990164 -184.633362) (xy 92.02807 -184.633866)
			(xy 92.103451 -184.641925) (xy 92.177549 -184.65795) (xy 92.249524 -184.68176) (xy 92.31856 -184.713086)
			(xy 92.383875 -184.751573) (xy 92.44473 -184.796784) (xy 92.500434 -184.848208) (xy 92.550356 -184.905261)
			(xy 92.593931 -184.967297) (xy 92.630666 -185.033614) (xy 92.660143 -185.10346) (xy 92.682029 -185.176043)
			(xy 92.696076 -185.250541) (xy 92.702125 -185.326111) (xy 92.700106 -185.401895) (xy 92.690044 -185.477035)
			(xy 92.672052 -185.55068) (xy 92.646334 -185.621996) (xy 92.613182 -185.690173) (xy 92.57297 -185.754441)
			(xy 92.526155 -185.81407) (xy 92.473267 -185.868386) (xy 92.414905 -185.916772) (xy 92.35173 -185.95868)
			(xy 92.284459 -185.993636) (xy 92.213854 -186.021243) (xy 92.178109 -186.030991) (xy 93.155011 -186.030991)
			(xy 93.161033 -185.914808) (xy 93.175056 -185.799317) (xy 93.197014 -185.685069) (xy 93.226801 -185.572608)
			(xy 93.264276 -185.46247) (xy 93.309261 -185.35518) (xy 93.36154 -185.251249) (xy 93.420865 -185.151173)
			(xy 93.486953 -185.055427) (xy 93.559489 -184.96447) (xy 93.638128 -184.878734) (xy 93.722494 -184.798627)
			(xy 93.812186 -184.724531) (xy 93.906776 -184.656801) (xy 94.005814 -184.595757) (xy 94.108827 -184.541692)
			(xy 94.215324 -184.494862) (xy 94.324799 -184.455491) (xy 94.436729 -184.423767) (xy 94.550581 -184.399841)
			(xy 94.665813 -184.383827) (xy 94.781875 -184.3758) (xy 94.840044 -184.375298) (xy 94.898213 -184.3758)
			(xy 95.014275 -184.383827) (xy 95.129507 -184.399841) (xy 95.243359 -184.423767) (xy 95.355289 -184.455491)
			(xy 95.464764 -184.494862) (xy 95.571261 -184.541692) (xy 95.674274 -184.595757) (xy 95.773312 -184.656801)
			(xy 95.867902 -184.724531) (xy 95.957594 -184.798627) (xy 96.04196 -184.878734) (xy 96.120599 -184.96447)
			(xy 96.193135 -185.055427) (xy 96.259223 -185.151173) (xy 96.318548 -185.251249) (xy 96.370827 -185.35518)
			(xy 96.415812 -185.46247) (xy 96.453287 -185.572608) (xy 96.483074 -185.685069) (xy 96.505032 -185.799317)
			(xy 96.519055 -185.914808) (xy 96.525077 -186.030991) (xy 96.523069 -186.147313) (xy 96.51304 -186.263219)
			(xy 96.495039 -186.378156) (xy 96.469151 -186.491579) (xy 96.4355 -186.602944) (xy 96.394246 -186.711723)
			(xy 96.345585 -186.817397) (xy 96.289749 -186.919461) (xy 96.227006 -187.01743) (xy 96.157652 -187.110837)
			(xy 96.08202 -187.199237) (xy 96.000469 -187.282208) (xy 95.913388 -187.359355) (xy 95.821192 -187.43031)
			(xy 95.72432 -187.494736) (xy 95.623235 -187.552325) (xy 95.518417 -187.602802) (xy 95.410366 -187.645928)
			(xy 95.299598 -187.681497) (xy 95.186639 -187.709339) (xy 95.072029 -187.729321) (xy 94.956314 -187.741348)
			(xy 94.840044 -187.745364) (xy 94.723774 -187.741348) (xy 94.608059 -187.729321) (xy 94.493449 -187.709339)
			(xy 94.38049 -187.681497) (xy 94.269722 -187.645928) (xy 94.161671 -187.602802) (xy 94.056853 -187.552325)
			(xy 93.955768 -187.494736) (xy 93.858896 -187.43031) (xy 93.7667 -187.359355) (xy 93.679619 -187.282208)
			(xy 93.598068 -187.199237) (xy 93.522436 -187.110837) (xy 93.453082 -187.01743) (xy 93.390339 -186.919461)
			(xy 93.334503 -186.817397) (xy 93.285842 -186.711723) (xy 93.244588 -186.602944) (xy 93.210937 -186.491579)
			(xy 93.185049 -186.378156) (xy 93.167048 -186.263219) (xy 93.157019 -186.147313) (xy 93.155011 -186.030991)
			(xy 92.178109 -186.030991) (xy 92.140713 -186.041189) (xy 92.065868 -186.053248) (xy 91.990164 -186.057283)
			(xy 91.91446 -186.053248) (xy 91.839615 -186.041189) (xy 91.766474 -186.021243) (xy 91.695869 -185.993636)
			(xy 91.628598 -185.95868) (xy 91.565423 -185.916772) (xy 91.507061 -185.868386) (xy 91.454173 -185.81407)
			(xy 91.407358 -185.754441) (xy 91.367146 -185.690173) (xy 91.333994 -185.621996) (xy 91.308276 -185.55068)
			(xy 91.290284 -185.477035) (xy 91.280222 -185.401895) (xy 91.278203 -185.326111) (xy 90.161304 -185.326111)
			(xy 90.162408 -185.350927) (xy 90.157817 -185.425964) (xy 90.145343 -185.500098) (xy 90.125126 -185.572506)
			(xy 90.09739 -185.642379) (xy 90.062445 -185.70894) (xy 90.020679 -185.771448) (xy 89.972559 -185.829205)
			(xy 89.91862 -185.88157) (xy 89.859462 -185.927959) (xy 89.827862 -185.94832) (xy 89.81445 -185.957232)
			(xy 89.792297 -185.98059) (xy 89.776696 -186.008751) (xy 89.768642 -186.039919) (xy 89.768172 -186.056016)
			(xy 89.768172 -186.464702) (xy 89.768741 -186.481348) (xy 89.777357 -186.513506) (xy 89.794001 -186.542339)
			(xy 89.81754 -186.565883) (xy 89.84637 -186.582533) (xy 89.878526 -186.591155) (xy 89.895172 -186.591702)
			(xy 89.941146 -186.591702) (xy 90.011758 -186.532774) (xy 90.019886 -186.487562) (xy 90.027196 -186.450621)
			(xy 90.048436 -186.378372) (xy 90.077185 -186.308769) (xy 90.113121 -186.242591) (xy 90.155845 -186.180577)
			(xy 90.204877 -186.12342) (xy 90.259669 -186.07176) (xy 90.31961 -186.026173) (xy 90.384029 -185.98717)
			(xy 90.452206 -185.955186) (xy 90.523378 -185.930579) (xy 90.596751 -185.913625) (xy 90.671504 -185.904511)
			(xy 90.746801 -185.903342) (xy 90.821801 -185.910129) (xy 90.895665 -185.924796) (xy 90.967567 -185.94718)
			(xy 91.036705 -185.977031) (xy 91.102304 -186.014014) (xy 91.163632 -186.057717) (xy 91.220002 -186.107651)
			(xy 91.270786 -186.163257) (xy 91.315415 -186.223914) (xy 91.35339 -186.288944) (xy 91.384287 -186.35762)
			(xy 91.40776 -186.429175) (xy 91.423548 -186.502808) (xy 91.431472 -186.577696) (xy 91.431446 -186.653002)
			(xy 91.423469 -186.727884) (xy 91.40763 -186.801506) (xy 91.384107 -186.873044) (xy 91.353162 -186.941699)
			(xy 91.315141 -187.006702) (xy 91.27047 -187.067328) (xy 91.219647 -187.122899) (xy 91.163242 -187.172793)
			(xy 91.101883 -187.216453) (xy 91.036258 -187.25339) (xy 90.9671 -187.283193) (xy 90.895182 -187.305526)
			(xy 90.85834 -187.313316) (xy 90.83599 -187.318251) (xy 90.793413 -187.335039) (xy 90.754531 -187.35918)
			(xy 90.7206 -187.389892) (xy 90.692717 -187.426184) (xy 90.671783 -187.466882) (xy 90.658474 -187.510671)
			(xy 90.653222 -187.556135) (xy 90.656195 -187.601805) (xy 90.667298 -187.646205) (xy 90.686171 -187.687898)
			(xy 90.712205 -187.725539) (xy 90.728038 -187.742068) (xy 90.797634 -187.811918) (xy 90.809755 -187.823394)
			(xy 90.838635 -187.840113) (xy 90.870865 -187.848762) (xy 90.88755 -187.849256) (xy 93.124528 -187.849256)
			(xy 99.432364 -194.156838) (xy 99.468178 -194.164712) (xy 99.494367 -194.171074) (xy 99.544768 -194.190157)
			(xy 99.591984 -194.21614) (xy 99.635075 -194.248507) (xy 99.673184 -194.286614) (xy 99.705552 -194.329704)
			(xy 99.731537 -194.376919) (xy 99.750621 -194.427319) (xy 99.756976 -194.45351) (xy 99.76485 -194.489324)
			(xy 101.847396 -196.57187) (xy 101.847396 -242.886484) (xy 94.144592 -250.589288) (xy 80.7974 -250.589288)
			(xy 78.09865 -253.288038) (xy 78.083326 -253.30408) (xy 78.057873 -253.340409) (xy 78.039115 -253.380606)
			(xy 78.027623 -253.423449) (xy 78.023745 -253.467638) (xy 78.027601 -253.511828) (xy 78.039072 -253.554677)
			(xy 78.05781 -253.594883) (xy 78.083246 -253.631224) (xy 78.114606 -253.662596) (xy 78.150938 -253.688044)
			(xy 78.191137 -253.706797) (xy 78.212442 -253.71298) (xy 78.247064 -253.722736) (xy 78.313984 -253.749126)
			(xy 78.377496 -253.782903) (xy 78.436786 -253.823638) (xy 78.491098 -253.870807) (xy 78.539734 -253.923809)
			(xy 78.582074 -253.981964) (xy 78.617576 -254.044528) (xy 78.645785 -254.110702) (xy 78.66634 -254.179638)
			(xy 78.678978 -254.250454) (xy 78.683539 -254.322244) (xy 78.681545 -254.362305) (xy 80.217002 -254.362305)
			(xy 80.217002 -254.290983) (xy 80.224988 -254.220109) (xy 80.240858 -254.150574) (xy 80.264415 -254.083254)
			(xy 80.29536 -254.018995) (xy 80.333306 -253.958604) (xy 80.377775 -253.902842) (xy 80.428208 -253.852409)
			(xy 80.48397 -253.80794) (xy 80.544361 -253.769994) (xy 80.60862 -253.739049) (xy 80.67594 -253.715492)
			(xy 80.745475 -253.699622) (xy 80.816349 -253.691636) (xy 80.85201 -253.691136) (xy 80.887671 -253.691636)
			(xy 80.958545 -253.699622) (xy 81.02808 -253.715492) (xy 81.0954 -253.739049) (xy 81.159659 -253.769994)
			(xy 81.22005 -253.80794) (xy 81.275812 -253.852409) (xy 81.326245 -253.902842) (xy 81.370714 -253.958604)
			(xy 81.40866 -254.018995) (xy 81.439605 -254.083254) (xy 81.463162 -254.150574) (xy 81.479032 -254.220109)
			(xy 81.487018 -254.290983) (xy 81.487018 -254.362305) (xy 81.479032 -254.433179) (xy 81.463162 -254.502714)
			(xy 81.439605 -254.570034) (xy 81.40866 -254.634293) (xy 81.370714 -254.694684) (xy 81.326245 -254.750446)
			(xy 81.275812 -254.800879) (xy 81.22005 -254.845348) (xy 81.159659 -254.883294) (xy 81.0954 -254.914239)
			(xy 81.02808 -254.937796) (xy 80.958545 -254.953666) (xy 80.887671 -254.961652) (xy 80.816349 -254.961652)
			(xy 80.745475 -254.953666) (xy 80.67594 -254.937796) (xy 80.60862 -254.914239) (xy 80.544361 -254.883294)
			(xy 80.48397 -254.845348) (xy 80.428208 -254.800879) (xy 80.377775 -254.750446) (xy 80.333306 -254.694684)
			(xy 80.29536 -254.634293) (xy 80.264415 -254.570034) (xy 80.240858 -254.502714) (xy 80.224988 -254.433179)
			(xy 80.217002 -254.362305) (xy 78.681545 -254.362305) (xy 78.679962 -254.394091) (xy 78.668295 -254.465073)
			(xy 78.648686 -254.534284) (xy 78.621386 -254.600838) (xy 78.586745 -254.663883) (xy 78.545205 -254.722613)
			(xy 78.497299 -254.776275) (xy 78.443639 -254.824184) (xy 78.384912 -254.865727) (xy 78.321869 -254.900371)
			(xy 78.255317 -254.927675) (xy 78.186107 -254.947287) (xy 78.115124 -254.958959) (xy 78.043278 -254.962539)
			(xy 77.971488 -254.957983) (xy 77.900671 -254.945348) (xy 77.831734 -254.924796) (xy 77.765559 -254.896591)
			(xy 77.702992 -254.861093) (xy 77.644835 -254.818756) (xy 77.591831 -254.770122) (xy 77.544659 -254.715813)
			(xy 77.503921 -254.656525) (xy 77.47014 -254.593015) (xy 77.443747 -254.526096) (xy 77.433932 -254.49149)
			(xy 77.427752 -254.470188) (xy 77.408984 -254.430001) (xy 77.383526 -254.393682) (xy 77.35215 -254.362333)
			(xy 77.315809 -254.336907) (xy 77.275606 -254.318173) (xy 77.232762 -254.306703) (xy 77.188578 -254.302843)
			(xy 77.144394 -254.30671) (xy 77.101552 -254.318189) (xy 77.061352 -254.336929) (xy 77.025016 -254.362362)
			(xy 77.00899 -254.377698) (xy 75.496032 -255.890623) (xy 77.362804 -255.890623) (xy 77.362804 -255.819301)
			(xy 77.37079 -255.748427) (xy 77.38666 -255.678892) (xy 77.410217 -255.611572) (xy 77.441162 -255.547313)
			(xy 77.479108 -255.486922) (xy 77.523577 -255.43116) (xy 77.57401 -255.380727) (xy 77.629772 -255.336258)
			(xy 77.690163 -255.298312) (xy 77.754422 -255.267367) (xy 77.821742 -255.24381) (xy 77.891277 -255.22794)
			(xy 77.962151 -255.219954) (xy 77.997812 -255.219454) (xy 78.033473 -255.219954) (xy 78.104347 -255.22794)
			(xy 78.173882 -255.24381) (xy 78.241202 -255.267367) (xy 78.305461 -255.298312) (xy 78.365852 -255.336258)
			(xy 78.421614 -255.380727) (xy 78.472047 -255.43116) (xy 78.516516 -255.486922) (xy 78.554462 -255.547313)
			(xy 78.585407 -255.611572) (xy 78.608964 -255.678892) (xy 78.624834 -255.748427) (xy 78.63282 -255.819301)
			(xy 78.63282 -255.890623) (xy 80.167218 -255.890623) (xy 80.167218 -255.819301) (xy 80.175204 -255.748427)
			(xy 80.191074 -255.678892) (xy 80.214631 -255.611572) (xy 80.245576 -255.547313) (xy 80.283522 -255.486922)
			(xy 80.327991 -255.43116) (xy 80.378424 -255.380727) (xy 80.434186 -255.336258) (xy 80.494577 -255.298312)
			(xy 80.558836 -255.267367) (xy 80.626156 -255.24381) (xy 80.695691 -255.22794) (xy 80.766565 -255.219954)
			(xy 80.802226 -255.219454) (xy 80.837887 -255.219954) (xy 80.908761 -255.22794) (xy 80.978296 -255.24381)
			(xy 81.045616 -255.267367) (xy 81.109875 -255.298312) (xy 81.170266 -255.336258) (xy 81.226028 -255.380727)
			(xy 81.276461 -255.43116) (xy 81.32093 -255.486922) (xy 81.358876 -255.547313) (xy 81.389821 -255.611572)
			(xy 81.413378 -255.678892) (xy 81.429248 -255.748427) (xy 81.437234 -255.819301) (xy 81.437234 -255.890623)
			(xy 81.429248 -255.961497) (xy 81.413378 -256.031032) (xy 81.389821 -256.098352) (xy 81.358876 -256.162611)
			(xy 81.32093 -256.223002) (xy 81.276461 -256.278764) (xy 81.226028 -256.329197) (xy 81.170266 -256.373666)
			(xy 81.109875 -256.411612) (xy 81.045616 -256.442557) (xy 80.978296 -256.466114) (xy 80.908761 -256.481984)
			(xy 80.837887 -256.48997) (xy 80.766565 -256.48997) (xy 80.695691 -256.481984) (xy 80.626156 -256.466114)
			(xy 80.558836 -256.442557) (xy 80.494577 -256.411612) (xy 80.434186 -256.373666) (xy 80.378424 -256.329197)
			(xy 80.327991 -256.278764) (xy 80.283522 -256.223002) (xy 80.245576 -256.162611) (xy 80.214631 -256.098352)
			(xy 80.191074 -256.031032) (xy 80.175204 -255.961497) (xy 80.167218 -255.890623) (xy 78.63282 -255.890623)
			(xy 78.624834 -255.961497) (xy 78.608964 -256.031032) (xy 78.585407 -256.098352) (xy 78.554462 -256.162611)
			(xy 78.516516 -256.223002) (xy 78.472047 -256.278764) (xy 78.421614 -256.329197) (xy 78.365852 -256.373666)
			(xy 78.305461 -256.411612) (xy 78.241202 -256.442557) (xy 78.173882 -256.466114) (xy 78.104347 -256.481984)
			(xy 78.033473 -256.48997) (xy 77.962151 -256.48997) (xy 77.891277 -256.481984) (xy 77.821742 -256.466114)
			(xy 77.754422 -256.442557) (xy 77.690163 -256.411612) (xy 77.629772 -256.373666) (xy 77.57401 -256.329197)
			(xy 77.523577 -256.278764) (xy 77.479108 -256.223002) (xy 77.441162 -256.162611) (xy 77.410217 -256.098352)
			(xy 77.38666 -256.031032) (xy 77.37079 -255.961497) (xy 77.362804 -255.890623) (xy 75.496032 -255.890623)
			(xy 73.771081 -257.615537) (xy 77.379314 -257.615537) (xy 77.379314 -257.544215) (xy 77.3873 -257.473341)
			(xy 77.40317 -257.403806) (xy 77.426727 -257.336486) (xy 77.457672 -257.272227) (xy 77.495618 -257.211836)
			(xy 77.540087 -257.156074) (xy 77.59052 -257.105641) (xy 77.646282 -257.061172) (xy 77.706673 -257.023226)
			(xy 77.770932 -256.992281) (xy 77.838252 -256.968724) (xy 77.907787 -256.952854) (xy 77.978661 -256.944868)
			(xy 78.014322 -256.944368) (xy 78.049983 -256.944868) (xy 78.120857 -256.952854) (xy 78.190392 -256.968724)
			(xy 78.257712 -256.992281) (xy 78.321971 -257.023226) (xy 78.382362 -257.061172) (xy 78.438124 -257.105641)
			(xy 78.488557 -257.156074) (xy 78.533026 -257.211836) (xy 78.570972 -257.272227) (xy 78.601917 -257.336486)
			(xy 78.625474 -257.403806) (xy 78.641344 -257.473341) (xy 78.64933 -257.544215) (xy 78.64933 -257.615537)
			(xy 80.183728 -257.615537) (xy 80.183728 -257.544215) (xy 80.191714 -257.473341) (xy 80.207584 -257.403806)
			(xy 80.231141 -257.336486) (xy 80.262086 -257.272227) (xy 80.300032 -257.211836) (xy 80.344501 -257.156074)
			(xy 80.394934 -257.105641) (xy 80.450696 -257.061172) (xy 80.511087 -257.023226) (xy 80.575346 -256.992281)
			(xy 80.642666 -256.968724) (xy 80.712201 -256.952854) (xy 80.783075 -256.944868) (xy 80.818736 -256.944368)
			(xy 80.854397 -256.944868) (xy 80.925271 -256.952854) (xy 80.994806 -256.968724) (xy 81.062126 -256.992281)
			(xy 81.126385 -257.023226) (xy 81.186776 -257.061172) (xy 81.242538 -257.105641) (xy 81.292971 -257.156074)
			(xy 81.33744 -257.211836) (xy 81.375386 -257.272227) (xy 81.406331 -257.336486) (xy 81.429888 -257.403806)
			(xy 81.445758 -257.473341) (xy 81.453744 -257.544215) (xy 81.453744 -257.615537) (xy 81.445758 -257.686411)
			(xy 81.429888 -257.755946) (xy 81.406331 -257.823266) (xy 81.375386 -257.887525) (xy 81.33744 -257.947916)
			(xy 81.292971 -258.003678) (xy 81.242538 -258.054111) (xy 81.186776 -258.09858) (xy 81.126385 -258.136526)
			(xy 81.062126 -258.167471) (xy 80.994806 -258.191028) (xy 80.925271 -258.206898) (xy 80.854397 -258.214884)
			(xy 80.783075 -258.214884) (xy 80.712201 -258.206898) (xy 80.642666 -258.191028) (xy 80.575346 -258.167471)
			(xy 80.511087 -258.136526) (xy 80.450696 -258.09858) (xy 80.394934 -258.054111) (xy 80.344501 -258.003678)
			(xy 80.300032 -257.947916) (xy 80.262086 -257.887525) (xy 80.231141 -257.823266) (xy 80.207584 -257.755946)
			(xy 80.191714 -257.686411) (xy 80.183728 -257.615537) (xy 78.64933 -257.615537) (xy 78.641344 -257.686411)
			(xy 78.625474 -257.755946) (xy 78.601917 -257.823266) (xy 78.570972 -257.887525) (xy 78.533026 -257.947916)
			(xy 78.488557 -258.003678) (xy 78.438124 -258.054111) (xy 78.382362 -258.09858) (xy 78.321971 -258.136526)
			(xy 78.257712 -258.167471) (xy 78.190392 -258.191028) (xy 78.120857 -258.206898) (xy 78.049983 -258.214884)
			(xy 77.978661 -258.214884) (xy 77.907787 -258.206898) (xy 77.838252 -258.191028) (xy 77.770932 -258.167471)
			(xy 77.706673 -258.136526) (xy 77.646282 -258.09858) (xy 77.59052 -258.054111) (xy 77.540087 -258.003678)
			(xy 77.495618 -257.947916) (xy 77.457672 -257.887525) (xy 77.426727 -257.823266) (xy 77.40317 -257.755946)
			(xy 77.3873 -257.686411) (xy 77.379314 -257.615537) (xy 73.771081 -257.615537) (xy 72.104043 -259.282539)
			(xy 77.392268 -259.282539) (xy 77.392268 -259.211217) (xy 77.400254 -259.140343) (xy 77.416124 -259.070808)
			(xy 77.439681 -259.003488) (xy 77.470626 -258.939229) (xy 77.508572 -258.878838) (xy 77.553041 -258.823076)
			(xy 77.603474 -258.772643) (xy 77.659236 -258.728174) (xy 77.719627 -258.690228) (xy 77.783886 -258.659283)
			(xy 77.851206 -258.635726) (xy 77.920741 -258.619856) (xy 77.991615 -258.61187) (xy 78.027276 -258.61137)
			(xy 78.062937 -258.61187) (xy 78.133811 -258.619856) (xy 78.203346 -258.635726) (xy 78.270666 -258.659283)
			(xy 78.334925 -258.690228) (xy 78.395316 -258.728174) (xy 78.451078 -258.772643) (xy 78.501511 -258.823076)
			(xy 78.54598 -258.878838) (xy 78.583926 -258.939229) (xy 78.614871 -259.003488) (xy 78.638428 -259.070808)
			(xy 78.654298 -259.140343) (xy 78.662284 -259.211217) (xy 78.662284 -259.282539) (xy 80.196682 -259.282539)
			(xy 80.196682 -259.211217) (xy 80.204668 -259.140343) (xy 80.220538 -259.070808) (xy 80.244095 -259.003488)
			(xy 80.27504 -258.939229) (xy 80.312986 -258.878838) (xy 80.357455 -258.823076) (xy 80.407888 -258.772643)
			(xy 80.46365 -258.728174) (xy 80.524041 -258.690228) (xy 80.5883 -258.659283) (xy 80.65562 -258.635726)
			(xy 80.725155 -258.619856) (xy 80.796029 -258.61187) (xy 80.83169 -258.61137) (xy 80.867351 -258.61187)
			(xy 80.938225 -258.619856) (xy 81.00776 -258.635726) (xy 81.07508 -258.659283) (xy 81.139339 -258.690228)
			(xy 81.19973 -258.728174) (xy 81.255492 -258.772643) (xy 81.305925 -258.823076) (xy 81.350394 -258.878838)
			(xy 81.38834 -258.939229) (xy 81.419285 -259.003488) (xy 81.442842 -259.070808) (xy 81.458712 -259.140343)
			(xy 81.466698 -259.211217) (xy 81.466698 -259.282539) (xy 81.458712 -259.353413) (xy 81.442842 -259.422948)
			(xy 81.419285 -259.490268) (xy 81.38834 -259.554527) (xy 81.350394 -259.614918) (xy 81.305925 -259.67068)
			(xy 81.255492 -259.721113) (xy 81.19973 -259.765582) (xy 81.139339 -259.803528) (xy 81.07508 -259.834473)
			(xy 81.00776 -259.85803) (xy 80.938225 -259.8739) (xy 80.867351 -259.881886) (xy 80.796029 -259.881886)
			(xy 80.725155 -259.8739) (xy 80.65562 -259.85803) (xy 80.5883 -259.834473) (xy 80.524041 -259.803528)
			(xy 80.46365 -259.765582) (xy 80.407888 -259.721113) (xy 80.357455 -259.67068) (xy 80.312986 -259.614918)
			(xy 80.27504 -259.554527) (xy 80.244095 -259.490268) (xy 80.220538 -259.422948) (xy 80.204668 -259.353413)
			(xy 80.196682 -259.282539) (xy 78.662284 -259.282539) (xy 78.654298 -259.353413) (xy 78.638428 -259.422948)
			(xy 78.614871 -259.490268) (xy 78.583926 -259.554527) (xy 78.54598 -259.614918) (xy 78.501511 -259.67068)
			(xy 78.451078 -259.721113) (xy 78.395316 -259.765582) (xy 78.334925 -259.803528) (xy 78.270666 -259.834473)
			(xy 78.203346 -259.85803) (xy 78.133811 -259.8739) (xy 78.062937 -259.881886) (xy 77.991615 -259.881886)
			(xy 77.920741 -259.8739) (xy 77.851206 -259.85803) (xy 77.783886 -259.834473) (xy 77.719627 -259.803528)
			(xy 77.659236 -259.765582) (xy 77.603474 -259.721113) (xy 77.553041 -259.67068) (xy 77.508572 -259.614918)
			(xy 77.470626 -259.554527) (xy 77.439681 -259.490268) (xy 77.416124 -259.422948) (xy 77.400254 -259.353413)
			(xy 77.392268 -259.282539) (xy 72.104043 -259.282539) (xy 70.472311 -260.914235) (xy 77.375758 -260.914235)
			(xy 77.375758 -260.842913) (xy 77.383744 -260.772039) (xy 77.399614 -260.702504) (xy 77.423171 -260.635184)
			(xy 77.454116 -260.570925) (xy 77.492062 -260.510534) (xy 77.536531 -260.454772) (xy 77.586964 -260.404339)
			(xy 77.642726 -260.35987) (xy 77.703117 -260.321924) (xy 77.767376 -260.290979) (xy 77.834696 -260.267422)
			(xy 77.904231 -260.251552) (xy 77.975105 -260.243566) (xy 78.010766 -260.243066) (xy 78.046427 -260.243566)
			(xy 78.117301 -260.251552) (xy 78.186836 -260.267422) (xy 78.254156 -260.290979) (xy 78.318415 -260.321924)
			(xy 78.378806 -260.35987) (xy 78.434568 -260.404339) (xy 78.485001 -260.454772) (xy 78.52947 -260.510534)
			(xy 78.567416 -260.570925) (xy 78.598361 -260.635184) (xy 78.621918 -260.702504) (xy 78.637788 -260.772039)
			(xy 78.645774 -260.842913) (xy 78.645774 -260.914235) (xy 80.180172 -260.914235) (xy 80.180172 -260.842913)
			(xy 80.188158 -260.772039) (xy 80.204028 -260.702504) (xy 80.227585 -260.635184) (xy 80.25853 -260.570925)
			(xy 80.296476 -260.510534) (xy 80.340945 -260.454772) (xy 80.391378 -260.404339) (xy 80.44714 -260.35987)
			(xy 80.507531 -260.321924) (xy 80.57179 -260.290979) (xy 80.63911 -260.267422) (xy 80.708645 -260.251552)
			(xy 80.779519 -260.243566) (xy 80.81518 -260.243066) (xy 80.850841 -260.243566) (xy 80.921715 -260.251552)
			(xy 80.99125 -260.267422) (xy 81.05857 -260.290979) (xy 81.122829 -260.321924) (xy 81.18322 -260.35987)
			(xy 81.238982 -260.404339) (xy 81.289415 -260.454772) (xy 81.333884 -260.510534) (xy 81.37183 -260.570925)
			(xy 81.402775 -260.635184) (xy 81.426332 -260.702504) (xy 81.442202 -260.772039) (xy 81.450188 -260.842913)
			(xy 81.450188 -260.914235) (xy 81.442202 -260.985109) (xy 81.426332 -261.054644) (xy 81.402775 -261.121964)
			(xy 81.37183 -261.186223) (xy 81.333884 -261.246614) (xy 81.289415 -261.302376) (xy 81.238982 -261.352809)
			(xy 81.18322 -261.397278) (xy 81.122829 -261.435224) (xy 81.05857 -261.466169) (xy 80.99125 -261.489726)
			(xy 80.921715 -261.505596) (xy 80.850841 -261.513582) (xy 80.779519 -261.513582) (xy 80.708645 -261.505596)
			(xy 80.63911 -261.489726) (xy 80.57179 -261.466169) (xy 80.507531 -261.435224) (xy 80.44714 -261.397278)
			(xy 80.391378 -261.352809) (xy 80.340945 -261.302376) (xy 80.296476 -261.246614) (xy 80.25853 -261.186223)
			(xy 80.227585 -261.121964) (xy 80.204028 -261.054644) (xy 80.188158 -260.985109) (xy 80.180172 -260.914235)
			(xy 78.645774 -260.914235) (xy 78.637788 -260.985109) (xy 78.621918 -261.054644) (xy 78.598361 -261.121964)
			(xy 78.567416 -261.186223) (xy 78.52947 -261.246614) (xy 78.485001 -261.302376) (xy 78.434568 -261.352809)
			(xy 78.378806 -261.397278) (xy 78.318415 -261.435224) (xy 78.254156 -261.466169) (xy 78.186836 -261.489726)
			(xy 78.117301 -261.505596) (xy 78.046427 -261.513582) (xy 77.975105 -261.513582) (xy 77.904231 -261.505596)
			(xy 77.834696 -261.489726) (xy 77.767376 -261.466169) (xy 77.703117 -261.435224) (xy 77.642726 -261.397278)
			(xy 77.586964 -261.352809) (xy 77.536531 -261.302376) (xy 77.492062 -261.246614) (xy 77.454116 -261.186223)
			(xy 77.423171 -261.121964) (xy 77.399614 -261.054644) (xy 77.383744 -260.985109) (xy 77.375758 -260.914235)
			(xy 70.472311 -260.914235) (xy 68.786477 -262.600033) (xy 77.342738 -262.600033) (xy 77.342738 -262.528711)
			(xy 77.350724 -262.457837) (xy 77.366594 -262.388302) (xy 77.390151 -262.320982) (xy 77.421096 -262.256723)
			(xy 77.459042 -262.196332) (xy 77.503511 -262.14057) (xy 77.553944 -262.090137) (xy 77.609706 -262.045668)
			(xy 77.670097 -262.007722) (xy 77.734356 -261.976777) (xy 77.801676 -261.95322) (xy 77.871211 -261.93735)
			(xy 77.942085 -261.929364) (xy 77.977746 -261.928864) (xy 78.013407 -261.929364) (xy 78.084281 -261.93735)
			(xy 78.153816 -261.95322) (xy 78.221136 -261.976777) (xy 78.285395 -262.007722) (xy 78.345786 -262.045668)
			(xy 78.401548 -262.090137) (xy 78.451981 -262.14057) (xy 78.49645 -262.196332) (xy 78.534396 -262.256723)
			(xy 78.565341 -262.320982) (xy 78.588898 -262.388302) (xy 78.604768 -262.457837) (xy 78.612754 -262.528711)
			(xy 78.612754 -262.600033) (xy 80.147152 -262.600033) (xy 80.147152 -262.528711) (xy 80.155138 -262.457837)
			(xy 80.171008 -262.388302) (xy 80.194565 -262.320982) (xy 80.22551 -262.256723) (xy 80.263456 -262.196332)
			(xy 80.307925 -262.14057) (xy 80.358358 -262.090137) (xy 80.41412 -262.045668) (xy 80.474511 -262.007722)
			(xy 80.53877 -261.976777) (xy 80.60609 -261.95322) (xy 80.675625 -261.93735) (xy 80.746499 -261.929364)
			(xy 80.78216 -261.928864) (xy 80.817821 -261.929364) (xy 80.888695 -261.93735) (xy 80.95823 -261.95322)
			(xy 81.02555 -261.976777) (xy 81.089809 -262.007722) (xy 81.1502 -262.045668) (xy 81.205962 -262.090137)
			(xy 81.256395 -262.14057) (xy 81.300864 -262.196332) (xy 81.33881 -262.256723) (xy 81.369755 -262.320982)
			(xy 81.393312 -262.388302) (xy 81.409182 -262.457837) (xy 81.417168 -262.528711) (xy 81.417168 -262.600033)
			(xy 81.409182 -262.670907) (xy 81.393312 -262.740442) (xy 81.369755 -262.807762) (xy 81.33881 -262.872021)
			(xy 81.300864 -262.932412) (xy 81.256395 -262.988174) (xy 81.205962 -263.038607) (xy 81.1502 -263.083076)
			(xy 81.089809 -263.121022) (xy 81.02555 -263.151967) (xy 80.95823 -263.175524) (xy 80.888695 -263.191394)
			(xy 80.817821 -263.19938) (xy 80.746499 -263.19938) (xy 80.675625 -263.191394) (xy 80.60609 -263.175524)
			(xy 80.53877 -263.151967) (xy 80.474511 -263.121022) (xy 80.41412 -263.083076) (xy 80.358358 -263.038607)
			(xy 80.307925 -262.988174) (xy 80.263456 -262.932412) (xy 80.22551 -262.872021) (xy 80.194565 -262.807762)
			(xy 80.171008 -262.740442) (xy 80.155138 -262.670907) (xy 80.147152 -262.600033) (xy 78.612754 -262.600033)
			(xy 78.604768 -262.670907) (xy 78.588898 -262.740442) (xy 78.565341 -262.807762) (xy 78.534396 -262.872021)
			(xy 78.49645 -262.932412) (xy 78.451981 -262.988174) (xy 78.401548 -263.038607) (xy 78.345786 -263.083076)
			(xy 78.285395 -263.121022) (xy 78.221136 -263.151967) (xy 78.153816 -263.175524) (xy 78.084281 -263.191394)
			(xy 78.013407 -263.19938) (xy 77.942085 -263.19938) (xy 77.871211 -263.191394) (xy 77.801676 -263.175524)
			(xy 77.734356 -263.151967) (xy 77.670097 -263.121022) (xy 77.609706 -263.083076) (xy 77.553944 -263.038607)
			(xy 77.503511 -262.988174) (xy 77.459042 -262.932412) (xy 77.421096 -262.872021) (xy 77.390151 -262.807762)
			(xy 77.366594 -262.740442) (xy 77.350724 -262.670907) (xy 77.342738 -262.600033) (xy 68.786477 -262.600033)
			(xy 65.258696 -266.127738) (xy 65.242724 -266.144356) (xy 65.216548 -266.182292) (xy 65.197642 -266.224326)
			(xy 65.186625 -266.26908) (xy 65.183859 -266.315087) (xy 65.189434 -266.360839) (xy 65.203167 -266.404835)
			(xy 65.224608 -266.445634) (xy 65.253054 -266.481899) (xy 65.287573 -266.512439) (xy 65.327033 -266.536255)
			(xy 65.370141 -266.552565) (xy 65.415483 -266.560835) (xy 65.438528 -266.561316) (xy 80.69453 -266.561316)
			(xy 80.965294 -266.290552) (xy 83.224878 -266.290552) (xy 83.495642 -266.561316) (xy 84.636864 -266.561316)
			(xy 84.658927 -266.560827) (xy 84.702382 -266.553148) (xy 84.743859 -266.538085) (xy 84.782114 -266.51609)
			(xy 84.815999 -266.487822) (xy 84.844496 -266.45413) (xy 84.866751 -266.416025) (xy 84.882095 -266.374651)
			(xy 84.886546 -266.353036) (xy 84.892046 -266.325643) (xy 84.909992 -266.272733) (xy 84.935461 -266.223006)
			(xy 84.967909 -266.177523) (xy 85.006642 -266.137258) (xy 85.050831 -266.10307) (xy 85.099533 -266.075691)
			(xy 85.151707 -266.055705) (xy 85.206237 -266.04354) (xy 85.261958 -266.039456) (xy 85.317679 -266.04354)
			(xy 85.372209 -266.055705) (xy 85.424383 -266.075691) (xy 85.473085 -266.10307) (xy 85.517274 -266.137258)
			(xy 85.556007 -266.177523) (xy 85.588455 -266.223006) (xy 85.613924 -266.272733) (xy 85.63187 -266.325643)
			(xy 85.63737 -266.353036) (xy 85.641783 -266.374669) (xy 85.657074 -266.416084) (xy 85.679302 -266.454227)
			(xy 85.707797 -266.487947) (xy 85.741697 -266.516226) (xy 85.779981 -266.538211) (xy 85.821492 -266.553238)
			(xy 85.864978 -266.560853) (xy 85.887052 -266.561316) (xy 87.160608 -266.561316) (xy 87.183697 -266.560871)
			(xy 87.229105 -266.552477) (xy 87.272251 -266.53602) (xy 87.311716 -266.512041) (xy 87.346202 -266.48133)
			(xy 87.374574 -266.444896) (xy 87.395899 -266.403937) (xy 87.409478 -266.3598) (xy 87.414862 -266.313937)
			(xy 87.411875 -266.267855) (xy 87.406734 -266.24534) (xy 87.400458 -266.21831) (xy 87.394876 -266.163104)
			(xy 87.39735 -266.107671) (xy 87.407827 -266.05318) (xy 87.426085 -266.000782) (xy 87.451741 -265.951581)
			(xy 87.484252 -265.906615) (xy 87.522934 -265.866832) (xy 87.566969 -265.833071) (xy 87.615431 -265.806044)
			(xy 87.667296 -265.786321) (xy 87.72147 -265.774319) (xy 87.776812 -265.77029) (xy 87.832154 -265.774319)
			(xy 87.886328 -265.786321) (xy 87.938193 -265.806044) (xy 87.986655 -265.833071) (xy 88.03069 -265.866832)
			(xy 88.069372 -265.906615) (xy 88.101883 -265.951581) (xy 88.127539 -266.000782) (xy 88.145797 -266.05318)
			(xy 88.156274 -266.107671) (xy 88.158748 -266.163104) (xy 88.153166 -266.21831) (xy 88.14689 -266.24534)
			(xy 88.141764 -266.267866) (xy 88.13872 -266.313954) (xy 88.144064 -266.359834) (xy 88.157619 -266.403989)
			(xy 88.178939 -266.444963) (xy 88.20732 -266.481405) (xy 88.241826 -266.51211) (xy 88.281317 -266.536067)
			(xy 88.32449 -266.552484) (xy 88.369921 -266.560819) (xy 88.393016 -266.561316) (xy 94.16923 -266.561316)
			(xy 101.046788 -273.439128) (xy 101.046788 -289.476688) (xy 98.569272 -291.954458) (xy 98.569272 -299.466254)
			(xy 98.58502 -299.494956) (xy 98.597945 -299.519291) (xy 98.617406 -299.570841) (xy 98.629246 -299.624655)
			(xy 98.633219 -299.679612) (xy 98.629242 -299.73457) (xy 98.617399 -299.788383) (xy 98.597935 -299.839931)
			(xy 98.58502 -299.864272) (xy 98.569272 -299.892974) (xy 98.569272 -311.512712) (xy 92.338906 -317.742824)
			(xy 92.140278 -317.742824) (xy 92.12362 -317.743276) (xy 92.091441 -317.751904) (xy 92.062592 -317.768567)
			(xy 92.039039 -317.792129) (xy 92.022386 -317.820984) (xy 92.01377 -317.853166) (xy 92.013278 -317.869824)
			(xy 92.013278 -317.916052) (xy 92.072206 -317.986664) (xy 92.117418 -317.994792) (xy 92.154938 -318.002082)
			(xy 92.228237 -318.023759) (xy 92.29879 -318.053167) (xy 92.365786 -318.089966) (xy 92.428452 -318.133734)
			(xy 92.486066 -318.183966) (xy 92.537965 -318.240082) (xy 92.583552 -318.301438) (xy 92.6223 -318.367326)
			(xy 92.653764 -318.436987) (xy 92.677581 -318.509618) (xy 92.693477 -318.584384) (xy 92.701269 -318.660423)
			(xy 92.700867 -318.736859) (xy 92.692276 -318.812812) (xy 92.675594 -318.887407) (xy 92.651014 -318.959784)
			(xy 92.618819 -319.02911) (xy 92.579379 -319.094586) (xy 92.53315 -319.155459) (xy 92.480663 -319.211027)
			(xy 92.422523 -319.260649) (xy 92.3594 -319.303755) (xy 92.292021 -319.339848) (xy 92.221162 -319.368512)
			(xy 92.177273 -319.380991) (xy 93.154757 -319.380991) (xy 93.160779 -319.264808) (xy 93.174802 -319.149317)
			(xy 93.19676 -319.035069) (xy 93.226547 -318.922608) (xy 93.264022 -318.81247) (xy 93.309007 -318.70518)
			(xy 93.361286 -318.601249) (xy 93.420611 -318.501173) (xy 93.486699 -318.405427) (xy 93.559235 -318.31447)
			(xy 93.637874 -318.228734) (xy 93.72224 -318.148627) (xy 93.811932 -318.074531) (xy 93.906522 -318.006801)
			(xy 94.00556 -317.945757) (xy 94.108573 -317.891692) (xy 94.21507 -317.844862) (xy 94.324545 -317.805491)
			(xy 94.436475 -317.773767) (xy 94.550327 -317.749841) (xy 94.665559 -317.733827) (xy 94.781621 -317.7258)
			(xy 94.83979 -317.725298) (xy 94.897959 -317.7258) (xy 95.014021 -317.733827) (xy 95.129253 -317.749841)
			(xy 95.243105 -317.773767) (xy 95.355035 -317.805491) (xy 95.46451 -317.844862) (xy 95.571007 -317.891692)
			(xy 95.67402 -317.945757) (xy 95.773058 -318.006801) (xy 95.867648 -318.074531) (xy 95.95734 -318.148627)
			(xy 96.041706 -318.228734) (xy 96.120345 -318.31447) (xy 96.192881 -318.405427) (xy 96.258969 -318.501173)
			(xy 96.318294 -318.601249) (xy 96.370573 -318.70518) (xy 96.415558 -318.81247) (xy 96.453033 -318.922608)
			(xy 96.48282 -319.035069) (xy 96.504778 -319.149317) (xy 96.518801 -319.264808) (xy 96.524823 -319.380991)
			(xy 96.522815 -319.497313) (xy 96.512786 -319.613219) (xy 96.494785 -319.728156) (xy 96.468897 -319.841579)
			(xy 96.435246 -319.952944) (xy 96.393992 -320.061723) (xy 96.345331 -320.167397) (xy 96.289495 -320.269461)
			(xy 96.226752 -320.36743) (xy 96.157398 -320.460837) (xy 96.081766 -320.549237) (xy 96.000215 -320.632208)
			(xy 95.913134 -320.709355) (xy 95.820938 -320.78031) (xy 95.724066 -320.844736) (xy 95.622981 -320.902325)
			(xy 95.518163 -320.952802) (xy 95.410112 -320.995928) (xy 95.299344 -321.031497) (xy 95.186385 -321.059339)
			(xy 95.071775 -321.079321) (xy 94.95606 -321.091348) (xy 94.83979 -321.095364) (xy 94.72352 -321.091348)
			(xy 94.607805 -321.079321) (xy 94.493195 -321.059339) (xy 94.380236 -321.031497) (xy 94.269468 -320.995928)
			(xy 94.161417 -320.952802) (xy 94.056599 -320.902325) (xy 93.955514 -320.844736) (xy 93.858642 -320.78031)
			(xy 93.766446 -320.709355) (xy 93.679365 -320.632208) (xy 93.597814 -320.549237) (xy 93.522182 -320.460837)
			(xy 93.452828 -320.36743) (xy 93.390085 -320.269461) (xy 93.334249 -320.167397) (xy 93.285588 -320.061723)
			(xy 93.244334 -319.952944) (xy 93.210683 -319.841579) (xy 93.184795 -319.728156) (xy 93.166794 -319.613219)
			(xy 93.156765 -319.497313) (xy 93.154757 -319.380991) (xy 92.177273 -319.380991) (xy 92.147639 -319.389417)
			(xy 92.072299 -319.402321) (xy 91.99601 -319.407078) (xy 91.919651 -319.403631) (xy 91.844101 -319.392021)
			(xy 91.77023 -319.372381) (xy 91.698889 -319.344937) (xy 91.630901 -319.310005) (xy 91.567048 -319.267989)
			(xy 91.508065 -319.219371) (xy 91.454633 -319.164712) (xy 91.407365 -319.104642) (xy 91.38666 -319.072514)
			(xy 91.377745 -319.059104) (xy 91.35439 -319.036947) (xy 91.32623 -319.021345) (xy 91.295061 -319.013291)
			(xy 91.278964 -319.012824) (xy 90.866214 -319.012824) (xy 90.820748 -319.05829) (xy 90.80928 -319.070417)
			(xy 90.79257 -319.099296) (xy 90.78392 -319.131521) (xy 90.783921 -319.164887) (xy 90.792573 -319.197111)
			(xy 90.809286 -319.22599) (xy 90.820748 -319.238122) (xy 90.846402 -319.263776) (xy 90.881708 -319.271904)
			(xy 90.91786 -319.280869) (xy 90.988232 -319.305284) (xy 91.05567 -319.336914) (xy 91.119436 -319.375413)
			(xy 91.178833 -319.420361) (xy 91.233211 -319.471266) (xy 91.281976 -319.527572) (xy 91.324594 -319.588662)
			(xy 91.360599 -319.653869) (xy 91.389598 -319.722479) (xy 91.411273 -319.793743) (xy 91.425387 -319.86688)
			(xy 91.431787 -319.941092) (xy 91.430402 -320.015566) (xy 91.421247 -320.089488) (xy 91.404422 -320.16205)
			(xy 91.380111 -320.232459) (xy 91.348581 -320.299943) (xy 91.310176 -320.363766) (xy 91.265315 -320.423229)
			(xy 91.21449 -320.477682) (xy 91.158257 -320.526529) (xy 91.097229 -320.569238) (xy 91.032076 -320.605339)
			(xy 90.963508 -320.634439) (xy 90.892277 -320.656219) (xy 90.81916 -320.670442) (xy 90.744958 -320.676951)
			(xy 90.670482 -320.675675) (xy 90.596546 -320.666629) (xy 90.560144 -320.658744) (xy 90.52814 -320.651378)
			(xy 90.464894 -320.669412) (xy 89.422732 -321.711828) (xy 85.344508 -321.711828) (xy 84.666328 -321.033648)
			(xy 84.654196 -321.022187) (xy 84.625317 -321.005478) (xy 84.593094 -320.996827) (xy 84.55973 -320.996827)
			(xy 84.527507 -321.005478) (xy 84.498628 -321.022187) (xy 84.486496 -321.033648) (xy 81.593436 -323.926708)
			(xy 81.593436 -324.295534) (xy 84.261705 -324.295534) (xy 84.267805 -324.240097) (xy 84.281911 -324.18614)
			(xy 84.303723 -324.134811) (xy 84.332777 -324.087205) (xy 84.368452 -324.044337) (xy 84.409989 -324.00712)
			(xy 84.456502 -323.976347) (xy 84.506999 -323.952675) (xy 84.560406 -323.936607) (xy 84.615582 -323.928487)
			(xy 84.643468 -323.927978) (xy 84.671354 -323.928487) (xy 84.72653 -323.936607) (xy 84.779937 -323.952675)
			(xy 84.830434 -323.976347) (xy 84.876947 -324.00712) (xy 84.918484 -324.044337) (xy 84.954159 -324.087205)
			(xy 84.983213 -324.134811) (xy 85.005025 -324.18614) (xy 85.019131 -324.240097) (xy 85.025231 -324.295534)
			(xy 85.023194 -324.351268) (xy 85.013064 -324.406111) (xy 84.995057 -324.458895) (xy 84.969556 -324.508495)
			(xy 84.937105 -324.553853) (xy 84.898396 -324.594002) (xy 84.854253 -324.628088) (xy 84.805618 -324.655384)
			(xy 84.753527 -324.675307) (xy 84.69909 -324.687433) (xy 84.643468 -324.691504) (xy 84.587846 -324.687433)
			(xy 84.533409 -324.675307) (xy 84.481318 -324.655384) (xy 84.432683 -324.628088) (xy 84.38854 -324.594002)
			(xy 84.349831 -324.553853) (xy 84.31738 -324.508495) (xy 84.291879 -324.458895) (xy 84.273872 -324.406111)
			(xy 84.263742 -324.351268) (xy 84.261705 -324.295534) (xy 81.593436 -324.295534) (xy 81.593436 -324.965586)
			(xy 82.791045 -324.965586) (xy 82.797145 -324.910149) (xy 82.811251 -324.856192) (xy 82.833063 -324.804863)
			(xy 82.862117 -324.757257) (xy 82.897792 -324.714389) (xy 82.939329 -324.677172) (xy 82.985842 -324.646399)
			(xy 83.036339 -324.622727) (xy 83.089746 -324.606659) (xy 83.144922 -324.598539) (xy 83.172808 -324.59803)
			(xy 83.200694 -324.598539) (xy 83.25587 -324.606659) (xy 83.309277 -324.622727) (xy 83.359774 -324.646399)
			(xy 83.406287 -324.677172) (xy 83.447824 -324.714389) (xy 83.483499 -324.757257) (xy 83.512553 -324.804863)
			(xy 83.534365 -324.856192) (xy 83.548471 -324.910149) (xy 83.554571 -324.965586) (xy 83.552534 -325.02132)
			(xy 83.542404 -325.076163) (xy 83.524397 -325.128947) (xy 83.498896 -325.178547) (xy 83.466445 -325.223905)
			(xy 83.427736 -325.264054) (xy 83.383593 -325.29814) (xy 83.334958 -325.325436) (xy 83.282867 -325.345359)
			(xy 83.22843 -325.357485) (xy 83.172808 -325.361556) (xy 83.117186 -325.357485) (xy 83.062749 -325.345359)
			(xy 83.010658 -325.325436) (xy 82.962023 -325.29814) (xy 82.91788 -325.264054) (xy 82.879171 -325.223905)
			(xy 82.84672 -325.178547) (xy 82.821219 -325.128947) (xy 82.803212 -325.076163) (xy 82.793082 -325.02132)
			(xy 82.791045 -324.965586) (xy 81.593436 -324.965586) (xy 81.593436 -325.017638) (xy 81.593933 -325.040975)
			(xy 81.602444 -325.086865) (xy 81.619192 -325.13043) (xy 81.643612 -325.170204) (xy 81.674885 -325.204851)
			(xy 81.711958 -325.233205) (xy 81.753585 -325.254313) (xy 81.798367 -325.267466) (xy 81.821528 -325.270368)
			(xy 81.849358 -325.273646) (xy 81.903661 -325.287487) (xy 81.955355 -325.309122) (xy 82.003328 -325.338086)
			(xy 82.046549 -325.373756) (xy 82.084087 -325.415364) (xy 82.115134 -325.462016) (xy 82.139024 -325.512708)
			(xy 82.155242 -325.566349) (xy 82.163438 -325.621785) (xy 82.163438 -325.677824) (xy 82.15524 -325.73326)
			(xy 82.139021 -325.786901) (xy 82.11513 -325.837592) (xy 82.084081 -325.884243) (xy 82.046542 -325.92585)
			(xy 82.003321 -325.961519) (xy 81.955347 -325.990482) (xy 81.903652 -326.012116) (xy 81.849349 -326.025955)
			(xy 81.821528 -326.02932) (xy 81.798378 -326.032276) (xy 81.75361 -326.045436) (xy 81.711996 -326.066545)
			(xy 81.674934 -326.094894) (xy 81.646753 -326.126112) (xy 83.341463 -326.126112) (xy 83.347563 -326.070675)
			(xy 83.361669 -326.016718) (xy 83.383481 -325.965389) (xy 83.412535 -325.917783) (xy 83.44821 -325.874915)
			(xy 83.489747 -325.837698) (xy 83.53626 -325.806925) (xy 83.586757 -325.783253) (xy 83.640164 -325.767185)
			(xy 83.69534 -325.759065) (xy 83.723226 -325.758556) (xy 83.751112 -325.759065) (xy 83.799554 -325.766194)
			(xy 85.482175 -325.766194) (xy 85.488275 -325.710757) (xy 85.502381 -325.6568) (xy 85.524193 -325.605471)
			(xy 85.553247 -325.557865) (xy 85.588922 -325.514997) (xy 85.630459 -325.47778) (xy 85.676972 -325.447007)
			(xy 85.727469 -325.423335) (xy 85.780876 -325.407267) (xy 85.836052 -325.399147) (xy 85.863938 -325.398638)
			(xy 85.891824 -325.399147) (xy 85.947 -325.407267) (xy 86.000407 -325.423335) (xy 86.050904 -325.447007)
			(xy 86.097417 -325.47778) (xy 86.138954 -325.514997) (xy 86.174629 -325.557865) (xy 86.203683 -325.605471)
			(xy 86.225495 -325.6568) (xy 86.239601 -325.710757) (xy 86.245701 -325.766194) (xy 86.243664 -325.821928)
			(xy 86.233534 -325.876771) (xy 86.215527 -325.929555) (xy 86.190026 -325.979155) (xy 86.157575 -326.024513)
			(xy 86.118866 -326.064662) (xy 86.074723 -326.098748) (xy 86.026088 -326.126044) (xy 85.973997 -326.145967)
			(xy 85.91956 -326.158093) (xy 85.863938 -326.162164) (xy 85.808316 -326.158093) (xy 85.753879 -326.145967)
			(xy 85.701788 -326.126044) (xy 85.653153 -326.098748) (xy 85.60901 -326.064662) (xy 85.570301 -326.024513)
			(xy 85.53785 -325.979155) (xy 85.512349 -325.929555) (xy 85.494342 -325.876771) (xy 85.484212 -325.821928)
			(xy 85.482175 -325.766194) (xy 83.799554 -325.766194) (xy 83.806288 -325.767185) (xy 83.859695 -325.783253)
			(xy 83.910192 -325.806925) (xy 83.956705 -325.837698) (xy 83.998242 -325.874915) (xy 84.033917 -325.917783)
			(xy 84.062971 -325.965389) (xy 84.084783 -326.016718) (xy 84.098889 -326.070675) (xy 84.104989 -326.126112)
			(xy 84.102952 -326.181846) (xy 84.092822 -326.236689) (xy 84.074815 -326.289473) (xy 84.049314 -326.339073)
			(xy 84.016863 -326.384431) (xy 83.978154 -326.42458) (xy 83.934011 -326.458666) (xy 83.885376 -326.485962)
			(xy 83.833285 -326.505885) (xy 83.778848 -326.518011) (xy 83.723226 -326.522082) (xy 83.667604 -326.518011)
			(xy 83.613167 -326.505885) (xy 83.561076 -326.485962) (xy 83.512441 -326.458666) (xy 83.468298 -326.42458)
			(xy 83.429589 -326.384431) (xy 83.397138 -326.339073) (xy 83.371637 -326.289473) (xy 83.35363 -326.236689)
			(xy 83.3435 -326.181846) (xy 83.341463 -326.126112) (xy 81.646753 -326.126112) (xy 81.643667 -326.129531)
			(xy 81.619246 -326.169292) (xy 81.602493 -326.212843) (xy 81.593968 -326.258719) (xy 81.593436 -326.28205)
			(xy 81.593436 -327.448182) (xy 82.912965 -327.448182) (xy 82.919065 -327.392745) (xy 82.933171 -327.338788)
			(xy 82.954983 -327.287459) (xy 82.984037 -327.239853) (xy 83.019712 -327.196985) (xy 83.061249 -327.159768)
			(xy 83.107762 -327.128995) (xy 83.158259 -327.105323) (xy 83.211666 -327.089255) (xy 83.266842 -327.081135)
			(xy 83.294728 -327.080626) (xy 83.322614 -327.081135) (xy 83.37779 -327.089255) (xy 83.431197 -327.105323)
			(xy 83.481694 -327.128995) (xy 83.528207 -327.159768) (xy 83.569744 -327.196985) (xy 83.605419 -327.239853)
			(xy 83.634473 -327.287459) (xy 83.656285 -327.338788) (xy 83.670391 -327.392745) (xy 83.676491 -327.448182)
			(xy 83.674454 -327.503916) (xy 83.664324 -327.558759) (xy 83.646317 -327.611543) (xy 83.620816 -327.661143)
			(xy 83.588365 -327.706501) (xy 83.549656 -327.74665) (xy 83.505513 -327.780736) (xy 83.456878 -327.808032)
			(xy 83.404787 -327.827955) (xy 83.35035 -327.840081) (xy 83.294728 -327.844152) (xy 83.239106 -327.840081)
			(xy 83.184669 -327.827955) (xy 83.132578 -327.808032) (xy 83.083943 -327.780736) (xy 83.0398 -327.74665)
			(xy 83.001091 -327.706501) (xy 82.96864 -327.661143) (xy 82.943139 -327.611543) (xy 82.925132 -327.558759)
			(xy 82.915002 -327.503916) (xy 82.912965 -327.448182) (xy 81.593436 -327.448182) (xy 81.593436 -330.159868)
			(xy 80.545552 -331.207796) (xy 86.877655 -331.207796) (xy 86.879665 -331.017113) (xy 86.889712 -330.826684)
			(xy 86.907778 -330.636848) (xy 86.933831 -330.447942) (xy 86.967824 -330.260303) (xy 87.009697 -330.074263)
			(xy 87.059376 -329.890154) (xy 87.116772 -329.708303) (xy 87.181783 -329.529033) (xy 87.254294 -329.352663)
			(xy 87.334175 -329.179507) (xy 87.421285 -329.009872) (xy 87.515469 -328.84406) (xy 87.61656 -328.682366)
			(xy 87.724376 -328.525078) (xy 87.838728 -328.372475) (xy 87.959411 -328.224827) (xy 88.086212 -328.082399)
			(xy 88.218903 -327.945443) (xy 88.357251 -327.814202) (xy 88.501008 -327.68891) (xy 88.649919 -327.56979)
			(xy 88.80372 -327.457054) (xy 88.962136 -327.350901) (xy 89.124887 -327.251521) (xy 89.291682 -327.159091)
			(xy 89.462226 -327.073774) (xy 89.636214 -326.995722) (xy 89.813339 -326.925075) (xy 89.993284 -326.861957)
			(xy 90.17573 -326.806481) (xy 90.360353 -326.758746) (xy 90.546823 -326.718836) (xy 90.734811 -326.686823)
			(xy 90.923981 -326.662763) (xy 91.113997 -326.6467) (xy 91.304521 -326.638661) (xy 91.399868 -326.638158)
			(xy 91.495215 -326.638661) (xy 91.685739 -326.6467) (xy 91.875755 -326.662763) (xy 92.064925 -326.686823)
			(xy 92.252913 -326.718836) (xy 92.439383 -326.758746) (xy 92.624006 -326.806481) (xy 92.806452 -326.861957)
			(xy 92.986397 -326.925075) (xy 93.163522 -326.995722) (xy 93.33751 -327.073774) (xy 93.508054 -327.159091)
			(xy 93.674849 -327.251521) (xy 93.8376 -327.350901) (xy 93.996016 -327.457054) (xy 94.149817 -327.56979)
			(xy 94.298728 -327.68891) (xy 94.442485 -327.814202) (xy 94.580833 -327.945443) (xy 94.713524 -328.082399)
			(xy 94.840325 -328.224827) (xy 94.961008 -328.372475) (xy 95.07536 -328.525078) (xy 95.183176 -328.682366)
			(xy 95.284267 -328.84406) (xy 95.378451 -329.009872) (xy 95.465561 -329.179507) (xy 95.545442 -329.352663)
			(xy 95.617953 -329.529033) (xy 95.682964 -329.708303) (xy 95.74036 -329.890154) (xy 95.790039 -330.074263)
			(xy 95.831912 -330.260303) (xy 95.865905 -330.447942) (xy 95.891958 -330.636848) (xy 95.910024 -330.826684)
			(xy 95.920071 -331.017113) (xy 95.922081 -331.207796) (xy 95.916051 -331.398395) (xy 95.901992 -331.588569)
			(xy 95.879927 -331.777982) (xy 95.849898 -331.966297) (xy 95.811956 -332.153178) (xy 95.76617 -332.338294)
			(xy 95.712621 -332.521314) (xy 95.651403 -332.701915) (xy 95.582627 -332.879774) (xy 95.506414 -333.054576)
			(xy 95.4229 -333.22601) (xy 95.332233 -333.39377) (xy 95.234574 -333.557559) (xy 95.130097 -333.717086)
			(xy 95.018988 -333.872067) (xy 94.901445 -334.022225) (xy 94.777675 -334.167295) (xy 94.6479 -334.307019)
			(xy 94.512351 -334.441147) (xy 94.371267 -334.569441) (xy 94.2249 -334.691675) (xy 94.073511 -334.807629)
			(xy 93.917368 -334.917098) (xy 93.756749 -335.019887) (xy 93.591939 -335.115813) (xy 93.423232 -335.204707)
			(xy 93.250927 -335.286409) (xy 93.075332 -335.360775) (xy 92.896757 -335.427673) (xy 92.715521 -335.486983)
			(xy 92.531946 -335.5386) (xy 92.346358 -335.582432) (xy 92.159088 -335.618401) (xy 91.970467 -335.646444)
			(xy 91.780832 -335.66651) (xy 91.590519 -335.678564) (xy 91.399868 -335.682585) (xy 91.209217 -335.678564)
			(xy 91.018904 -335.66651) (xy 90.829269 -335.646444) (xy 90.640648 -335.618401) (xy 90.453378 -335.582432)
			(xy 90.26779 -335.5386) (xy 90.084215 -335.486983) (xy 89.902979 -335.427673) (xy 89.724404 -335.360775)
			(xy 89.548809 -335.286409) (xy 89.376504 -335.204707) (xy 89.207797 -335.115813) (xy 89.042987 -335.019887)
			(xy 88.882368 -334.917098) (xy 88.726225 -334.807629) (xy 88.574836 -334.691675) (xy 88.428469 -334.569441)
			(xy 88.287385 -334.441147) (xy 88.151836 -334.307019) (xy 88.022061 -334.167295) (xy 87.898291 -334.022225)
			(xy 87.780748 -333.872067) (xy 87.669639 -333.717086) (xy 87.565162 -333.557559) (xy 87.467503 -333.39377)
			(xy 87.376836 -333.22601) (xy 87.293322 -333.054576) (xy 87.217109 -332.879774) (xy 87.148333 -332.701915)
			(xy 87.087115 -332.521314) (xy 87.033566 -332.338294) (xy 86.98778 -332.153178) (xy 86.949838 -331.966297)
			(xy 86.919809 -331.777982) (xy 86.897744 -331.588569) (xy 86.883685 -331.398395) (xy 86.877655 -331.207796)
			(xy 80.545552 -331.207796) (xy 75.581256 -336.172302) (xy 75.566008 -336.188339) (xy 75.540609 -336.224566)
			(xy 75.521867 -336.264644) (xy 75.51035 -336.307362) (xy 75.506405 -336.351429) (xy 75.510152 -336.395513)
			(xy 75.521478 -336.438283) (xy 75.540039 -336.478445) (xy 75.565276 -336.514785) (xy 75.596424 -336.546205)
			(xy 75.632544 -336.571756) (xy 75.672543 -336.590665) (xy 75.715213 -336.602361) (xy 75.759263 -336.60649)
			(xy 75.803363 -336.602928) (xy 75.84618 -336.591782) (xy 75.866498 -336.58302) (xy 75.958885 -336.541329)
			(xy 76.14643 -336.464388) (xy 76.336867 -336.394913) (xy 76.529899 -336.333014) (xy 76.725226 -336.278787)
			(xy 76.922541 -336.232316) (xy 77.121538 -336.193673) (xy 77.321906 -336.162921) (xy 77.523332 -336.140105)
			(xy 77.725502 -336.125262) (xy 77.9281 -336.118415) (xy 78.130811 -336.119575) (xy 78.333318 -336.12874)
			(xy 78.535305 -336.145895) (xy 78.736456 -336.171014) (xy 78.936459 -336.204058) (xy 79.135001 -336.244974)
			(xy 79.331772 -336.2937) (xy 79.526465 -336.350159) (xy 79.718776 -336.414263) (xy 79.908406 -336.485912)
			(xy 80.095058 -336.564994) (xy 80.278441 -336.651386) (xy 80.45827 -336.744953) (xy 80.634262 -336.845549)
			(xy 80.806145 -336.953018) (xy 80.973649 -337.06719) (xy 81.136513 -337.187889) (xy 81.294484 -337.314926)
			(xy 81.447314 -337.448102) (xy 81.594765 -337.587211) (xy 81.736607 -337.732034) (xy 81.872619 -337.882346)
			(xy 82.002589 -338.037912) (xy 82.126313 -338.19849) (xy 82.243599 -338.363829) (xy 82.354264 -338.533671)
			(xy 82.458135 -338.707751) (xy 82.555049 -338.885798) (xy 82.644857 -339.067533) (xy 82.727417 -339.252673)
			(xy 82.802601 -339.440929) (xy 82.870291 -339.632008) (xy 82.930382 -339.825611) (xy 82.98278 -340.021436)
			(xy 83.027404 -340.219177) (xy 83.064183 -340.418527) (xy 83.09306 -340.619173) (xy 83.113991 -340.820804)
			(xy 83.126942 -341.023104) (xy 83.131894 -341.225758) (xy 83.128838 -341.428449) (xy 83.11778 -341.630861)
			(xy 83.098736 -341.832678) (xy 83.071737 -342.033587) (xy 83.036824 -342.233272) (xy 82.994052 -342.431422)
			(xy 82.943488 -342.627728) (xy 82.885211 -342.821885) (xy 82.819311 -343.013588) (xy 82.745891 -343.20254)
			(xy 82.665067 -343.388444) (xy 82.576963 -343.571011) (xy 82.481718 -343.749956) (xy 82.37948 -343.925)
			(xy 82.270409 -344.09587) (xy 82.154675 -344.262299) (xy 82.032458 -344.424027) (xy 81.903949 -344.580802)
			(xy 81.769349 -344.73238) (xy 81.628868 -344.878524) (xy 81.482724 -345.019005) (xy 81.331146 -345.153606)
			(xy 81.174371 -345.282115) (xy 81.012643 -345.404332) (xy 80.846214 -345.520066) (xy 80.675345 -345.629137)
			(xy 80.500301 -345.731376) (xy 80.321356 -345.826621) (xy 80.138789 -345.914724) (xy 79.952885 -345.995549)
			(xy 79.763933 -346.068969) (xy 79.57223 -346.134869) (xy 79.378074 -346.193147) (xy 79.181767 -346.243711)
			(xy 78.983617 -346.286483) (xy 78.783932 -346.321396) (xy 78.583024 -346.348395) (xy 78.381206 -346.367439)
			(xy 78.178794 -346.378498) (xy 77.976103 -346.381554) (xy 77.773449 -346.376602) (xy 77.571149 -346.363651)
			(xy 77.369519 -346.342721) (xy 77.168872 -346.313844) (xy 76.969522 -346.277065) (xy 76.771781 -346.232441)
			(xy 76.575956 -346.180043) (xy 76.382353 -346.119953) (xy 76.191274 -346.052263) (xy 76.003018 -345.977079)
			(xy 75.817878 -345.894519) (xy 75.636142 -345.804712) (xy 75.458096 -345.707797) (xy 75.284016 -345.603927)
			(xy 75.114174 -345.493262) (xy 74.948835 -345.375976) (xy 74.788256 -345.252252) (xy 74.63269 -345.122283)
			(xy 74.482378 -344.986271) (xy 74.337554 -344.844429) (xy 74.198446 -344.696977) (xy 74.065269 -344.544148)
			(xy 73.938232 -344.386177) (xy 73.817533 -344.223313) (xy 73.703361 -344.055809) (xy 73.595892 -343.883927)
			(xy 73.495296 -343.707934) (xy 73.401728 -343.528106) (xy 73.315336 -343.344723) (xy 73.236254 -343.158071)
			(xy 73.164605 -342.968441) (xy 73.1005 -342.77613) (xy 73.044041 -342.581437) (xy 72.995315 -342.384666)
			(xy 72.954399 -342.186125) (xy 72.921355 -341.986122) (xy 72.896236 -341.78497) (xy 72.87908 -341.582983)
			(xy 72.869915 -341.380476) (xy 72.868755 -341.177766) (xy 72.875602 -340.975167) (xy 72.890445 -340.772997)
			(xy 72.91326 -340.571571) (xy 72.944013 -340.371203) (xy 72.982654 -340.172206) (xy 73.029125 -339.974891)
			(xy 73.083352 -339.779564) (xy 73.145251 -339.586532) (xy 73.214726 -339.396095) (xy 73.291667 -339.20855)
			(xy 73.333356 -339.116162) (xy 73.342196 -339.095857) (xy 73.353398 -339.053013) (xy 73.357004 -339.008877)
			(xy 73.352904 -338.964783) (xy 73.341224 -338.922067) (xy 73.322316 -338.882023) (xy 73.296753 -338.845862)
			(xy 73.26531 -338.81468) (xy 73.228937 -338.78942) (xy 73.188736 -338.770847) (xy 73.145924 -338.759524)
			(xy 73.101798 -338.755793) (xy 73.057693 -338.759768) (xy 73.014944 -338.771327) (xy 72.974847 -338.790121)
			(xy 72.938614 -338.815581) (xy 72.922638 -338.83092) (xy 60.21324 -351.540064) (xy 60.197315 -351.556741)
			(xy 60.171118 -351.594682) (xy 60.152192 -351.636726) (xy 60.141157 -351.681493) (xy 60.138376 -351.727515)
			(xy 60.14394 -351.773285) (xy 60.157665 -351.817301) (xy 60.179103 -351.858121) (xy 60.20755 -351.894406)
			(xy 60.242074 -351.924967) (xy 60.281542 -351.948801) (xy 60.324662 -351.965127) (xy 60.370018 -351.97341)
			(xy 60.393072 -351.973896) (xy 64.949324 -351.973896) (xy 66.05524 -350.86798) (xy 75.283822 -350.86798)
			(xy 76.389738 -351.973896) (xy 95.595694 -351.973896) (xy 101.291644 -357.669592) (xy 101.291644 -390.377934)
			(xy 93.804232 -397.865346) (xy 93.795342 -397.896842) (xy 93.787299 -397.923222) (xy 93.764589 -397.973481)
			(xy 93.734882 -398.019947) (xy 93.698795 -398.061653) (xy 93.657081 -398.097731) (xy 93.610609 -398.127428)
			(xy 93.560345 -398.150127) (xy 93.533976 -398.158208) (xy 93.50248 -398.167098) (xy 92.344748 -399.324576)
			(xy 92.33339 -399.336719) (xy 92.316789 -399.365512) (xy 92.308201 -399.39762) (xy 92.307664 -399.414238)
			(xy 92.307664 -404.344124) (xy 92.308135 -404.360219) (xy 92.316197 -404.391382) (xy 92.331802 -404.419536)
			(xy 92.353957 -404.442888) (xy 92.367354 -404.45182) (xy 92.399518 -404.472485) (xy 92.459617 -404.519746)
			(xy 92.514303 -404.573177) (xy 92.562947 -404.632162) (xy 92.604989 -404.69602) (xy 92.639944 -404.764017)
			(xy 92.667409 -404.835369) (xy 92.687069 -404.909254) (xy 92.698696 -404.98482) (xy 92.702156 -405.061198)
			(xy 92.69741 -405.137506) (xy 92.684512 -405.212865) (xy 92.663611 -405.286409) (xy 92.634948 -405.357288)
			(xy 92.598853 -405.424687) (xy 92.555742 -405.487828) (xy 92.506111 -405.545985) (xy 92.450533 -405.598488)
			(xy 92.389648 -405.644731) (xy 92.324156 -405.684181) (xy 92.254814 -405.716385) (xy 92.182419 -405.74097)
			(xy 92.107806 -405.757655) (xy 92.031835 -405.766246) (xy 91.95538 -405.766644) (xy 91.879324 -405.758846)
			(xy 91.804541 -405.74294) (xy 91.731894 -405.719111) (xy 91.662219 -405.687632) (xy 91.59632 -405.648866)
			(xy 91.534956 -405.603261) (xy 91.478833 -405.55134) (xy 91.428599 -405.493704) (xy 91.384832 -405.431015)
			(xy 91.348036 -405.363996) (xy 91.318636 -405.29342) (xy 91.296969 -405.220098) (xy 91.289632 -405.182578)
			(xy 91.281504 -405.137366) (xy 91.210892 -405.078438) (xy 91.164664 -405.078438) (xy 91.148005 -405.078864)
			(xy 91.115823 -405.087497) (xy 91.086973 -405.104164) (xy 91.063419 -405.127732) (xy 91.046768 -405.156592)
			(xy 91.038154 -405.188778) (xy 91.037664 -405.205438) (xy 91.037664 -405.614124) (xy 91.038135 -405.630219)
			(xy 91.046197 -405.661382) (xy 91.061802 -405.689536) (xy 91.083957 -405.712888) (xy 91.097354 -405.72182)
			(xy 91.128899 -405.742128) (xy 91.187962 -405.788394) (xy 91.24183 -405.840618) (xy 91.289903 -405.89822)
			(xy 91.33165 -405.96056) (xy 91.366606 -406.026946) (xy 91.394383 -406.096642) (xy 91.414673 -406.168873)
			(xy 91.427251 -406.242838) (xy 91.431977 -406.317716) (xy 91.428799 -406.392676) (xy 91.417751 -406.466885)
			(xy 91.398957 -406.53952) (xy 91.372625 -406.609774) (xy 91.339048 -406.676868) (xy 91.298597 -406.740057)
			(xy 91.251723 -406.798639) (xy 91.198946 -406.851965) (xy 91.140851 -406.899441) (xy 91.078083 -406.940542)
			(xy 91.01134 -406.97481) (xy 90.941361 -407.001866) (xy 90.868924 -407.021409) (xy 90.794833 -407.033223)
			(xy 90.71991 -407.037175) (xy 90.644987 -407.033223) (xy 90.570896 -407.021409) (xy 90.498459 -407.001866)
			(xy 90.42848 -406.97481) (xy 90.361737 -406.940542) (xy 90.298969 -406.899441) (xy 90.240874 -406.851965)
			(xy 90.188097 -406.798639) (xy 90.141223 -406.740057) (xy 90.100772 -406.676868) (xy 90.067195 -406.609774)
			(xy 90.040863 -406.53952) (xy 90.022069 -406.466885) (xy 90.011021 -406.392676) (xy 90.007843 -406.317716)
			(xy 90.012569 -406.242838) (xy 90.025147 -406.168873) (xy 90.045437 -406.096642) (xy 90.073214 -406.026946)
			(xy 90.10817 -405.96056) (xy 90.149917 -405.89822) (xy 90.19799 -405.840618) (xy 90.251858 -405.788394)
			(xy 90.310921 -405.742128) (xy 90.342466 -405.72182) (xy 90.355844 -405.712861) (xy 90.378005 -405.689521)
			(xy 90.393616 -405.661375) (xy 90.401681 -405.630216) (xy 90.402156 -405.614124) (xy 90.402156 -405.205438)
			(xy 90.401672 -405.188781) (xy 90.393056 -405.156602) (xy 90.376402 -405.12775) (xy 90.352845 -405.104195)
			(xy 90.323993 -405.087542) (xy 90.291813 -405.078927) (xy 90.275156 -405.078438) (xy 90.228928 -405.078438)
			(xy 90.158316 -405.137366) (xy 90.150188 -405.182578) (xy 90.142904 -405.2199) (xy 90.121386 -405.292839)
			(xy 90.092215 -405.363068) (xy 90.055724 -405.429787) (xy 90.012328 -405.492236) (xy 89.962522 -405.549703)
			(xy 89.906873 -405.601533) (xy 89.846017 -405.647135) (xy 89.780645 -405.685989) (xy 89.711504 -405.717653)
			(xy 89.639382 -405.741766) (xy 89.5651 -405.758053) (xy 89.489505 -405.766328) (xy 89.413459 -405.766497)
			(xy 89.337828 -405.758558) (xy 89.263474 -405.742602) (xy 89.191245 -405.71881) (xy 89.121964 -405.687454)
			(xy 89.056421 -405.648891) (xy 88.995362 -405.60356) (xy 88.939483 -405.551978) (xy 88.889422 -405.494734)
			(xy 88.845749 -405.432478) (xy 88.808961 -405.365922) (xy 88.779478 -405.295823) (xy 88.757636 -405.222981)
			(xy 88.743684 -405.148225) (xy 88.737781 -405.072408) (xy 88.739994 -404.996394) (xy 88.750298 -404.921049)
			(xy 88.768575 -404.847231) (xy 88.794617 -404.775783) (xy 88.828128 -404.707518) (xy 88.868726 -404.643215)
			(xy 88.915947 -404.583605) (xy 88.969253 -404.52937) (xy 89.028038 -404.481126) (xy 89.09163 -404.439425)
			(xy 89.159306 -404.40474) (xy 89.230294 -404.377467) (xy 89.303785 -404.357917) (xy 89.378941 -404.346314)
			(xy 89.454906 -404.342788) (xy 89.530813 -404.347381) (xy 89.605799 -404.36004) (xy 89.679008 -404.38062)
			(xy 89.749605 -404.408888) (xy 89.816787 -404.44452) (xy 89.879787 -404.487112) (xy 89.937888 -404.536177)
			(xy 89.964514 -404.563326) (xy 89.98092 -404.57982) (xy 90.018648 -404.607034) (xy 90.060698 -404.626928)
			(xy 90.105666 -404.638839) (xy 90.152051 -404.642369) (xy 90.198304 -404.637401) (xy 90.24288 -404.6241)
			(xy 90.284293 -404.602911) (xy 90.321159 -404.57454) (xy 90.352247 -404.539935) (xy 90.37652 -404.500251)
			(xy 90.393168 -404.456813) (xy 90.401634 -404.411071) (xy 90.402156 -404.387812) (xy 90.402156 -399.95475)
			(xy 90.401663 -399.931689) (xy 90.393404 -399.886313) (xy 90.377094 -399.843173) (xy 90.353269 -399.803683)
			(xy 90.322709 -399.769139) (xy 90.286419 -399.740676) (xy 90.245588 -399.719228) (xy 90.201559 -399.705498)
			(xy 90.155774 -399.699938) (xy 90.109738 -399.702729) (xy 90.064961 -399.713781) (xy 90.022912 -399.732729)
			(xy 89.984973 -399.758954) (xy 89.968324 -399.774918) (xy 87.227664 -402.515578) (xy 87.227664 -404.344124)
			(xy 87.228135 -404.360219) (xy 87.236197 -404.391382) (xy 87.251802 -404.419536) (xy 87.273957 -404.442888)
			(xy 87.287354 -404.45182) (xy 87.319518 -404.472485) (xy 87.379617 -404.519746) (xy 87.434303 -404.573177)
			(xy 87.482947 -404.632162) (xy 87.524989 -404.69602) (xy 87.559944 -404.764017) (xy 87.587409 -404.835369)
			(xy 87.607069 -404.909254) (xy 87.618696 -404.98482) (xy 87.622156 -405.061198) (xy 87.61741 -405.137506)
			(xy 87.604512 -405.212865) (xy 87.583611 -405.286409) (xy 87.554948 -405.357288) (xy 87.518853 -405.424687)
			(xy 87.475742 -405.487828) (xy 87.426111 -405.545985) (xy 87.370533 -405.598488) (xy 87.309648 -405.644731)
			(xy 87.244156 -405.684181) (xy 87.174814 -405.716385) (xy 87.102419 -405.74097) (xy 87.027806 -405.757655)
			(xy 86.951835 -405.766246) (xy 86.87538 -405.766644) (xy 86.799324 -405.758846) (xy 86.724541 -405.74294)
			(xy 86.651894 -405.719111) (xy 86.582219 -405.687632) (xy 86.51632 -405.648866) (xy 86.454956 -405.603261)
			(xy 86.398833 -405.55134) (xy 86.348599 -405.493704) (xy 86.304832 -405.431015) (xy 86.268036 -405.363996)
			(xy 86.238636 -405.29342) (xy 86.216969 -405.220098) (xy 86.209632 -405.182578) (xy 86.201504 -405.137366)
			(xy 86.130892 -405.078438) (xy 86.084664 -405.078438) (xy 86.068005 -405.078864) (xy 86.035823 -405.087497)
			(xy 86.006973 -405.104164) (xy 85.983419 -405.127732) (xy 85.966768 -405.156592) (xy 85.958154 -405.188778)
			(xy 85.957664 -405.205438) (xy 85.957664 -405.614124) (xy 85.958135 -405.630219) (xy 85.966197 -405.661382)
			(xy 85.981802 -405.689536) (xy 86.003957 -405.712888) (xy 86.017354 -405.72182) (xy 86.049266 -405.742512)
			(xy 86.10908 -405.78949) (xy 86.163543 -405.842578) (xy 86.212035 -405.901172) (xy 86.254001 -405.964603)
			(xy 86.288964 -406.032147) (xy 86.316525 -406.103035) (xy 86.336369 -406.176457) (xy 86.34827 -406.251577)
			(xy 86.351014 -406.306111) (xy 87.467949 -406.306111) (xy 87.473998 -406.230541) (xy 87.488045 -406.156043)
			(xy 87.509931 -406.08346) (xy 87.539408 -406.013614) (xy 87.576143 -405.947297) (xy 87.619718 -405.885261)
			(xy 87.66964 -405.828208) (xy 87.725344 -405.776784) (xy 87.786199 -405.731573) (xy 87.851514 -405.693086)
			(xy 87.92055 -405.66176) (xy 87.992525 -405.63795) (xy 88.066623 -405.621925) (xy 88.142004 -405.613866)
			(xy 88.17991 -405.613362) (xy 88.217816 -405.613866) (xy 88.293197 -405.621925) (xy 88.367295 -405.63795)
			(xy 88.43927 -405.66176) (xy 88.508306 -405.693086) (xy 88.573621 -405.731573) (xy 88.634476 -405.776784)
			(xy 88.69018 -405.828208) (xy 88.740102 -405.885261) (xy 88.783677 -405.947297) (xy 88.820412 -406.013614)
			(xy 88.849889 -406.08346) (xy 88.871775 -406.156043) (xy 88.885822 -406.230541) (xy 88.891871 -406.306111)
			(xy 88.889852 -406.381895) (xy 88.87979 -406.457035) (xy 88.861798 -406.53068) (xy 88.83608 -406.601996)
			(xy 88.802928 -406.670173) (xy 88.762716 -406.734441) (xy 88.715901 -406.79407) (xy 88.663013 -406.848386)
			(xy 88.604651 -406.896772) (xy 88.541476 -406.93868) (xy 88.474205 -406.973636) (xy 88.4036 -407.001243)
			(xy 88.330459 -407.021189) (xy 88.255614 -407.033248) (xy 88.17991 -407.037283) (xy 88.104206 -407.033248)
			(xy 88.029361 -407.021189) (xy 87.95622 -407.001243) (xy 87.885615 -406.973636) (xy 87.818344 -406.93868)
			(xy 87.755169 -406.896772) (xy 87.696807 -406.848386) (xy 87.643919 -406.79407) (xy 87.597104 -406.734441)
			(xy 87.556892 -406.670173) (xy 87.52374 -406.601996) (xy 87.498022 -406.53068) (xy 87.48003 -406.457035)
			(xy 87.469968 -406.381895) (xy 87.467949 -406.306111) (xy 86.351014 -406.306111) (xy 86.352092 -406.327538)
			(xy 86.347792 -406.403473) (xy 86.335419 -406.478517) (xy 86.315114 -406.551813) (xy 86.287109 -406.622526)
			(xy 86.251722 -406.68985) (xy 86.209358 -406.753015) (xy 86.160499 -406.811303) (xy 86.105703 -406.864048)
			(xy 86.045595 -406.910649) (xy 85.98086 -406.950575) (xy 85.912237 -406.983369) (xy 85.840508 -407.008659)
			(xy 85.766491 -407.026155) (xy 85.69103 -407.035658) (xy 85.614986 -407.03706) (xy 85.539226 -407.030344)
			(xy 85.464615 -407.015588) (xy 85.392002 -406.992959) (xy 85.322217 -406.962716) (xy 85.256054 -406.925204)
			(xy 85.224874 -406.903428) (xy 85.205714 -406.89028) (xy 85.163683 -406.870477) (xy 85.118751 -406.858647)
			(xy 85.072418 -406.855184) (xy 85.026227 -406.860204) (xy 84.981719 -406.87354) (xy 84.940378 -406.894747)
			(xy 84.903582 -406.923117) (xy 84.872558 -406.957705) (xy 84.848342 -406.997358) (xy 84.831739 -407.040753)
			(xy 84.823304 -407.086444) (xy 84.822792 -407.109676) (xy 84.822792 -407.576111) (xy 86.197949 -407.576111)
			(xy 86.203998 -407.500541) (xy 86.218045 -407.426043) (xy 86.239931 -407.35346) (xy 86.269408 -407.283614)
			(xy 86.306143 -407.217297) (xy 86.349718 -407.155261) (xy 86.39964 -407.098208) (xy 86.455344 -407.046784)
			(xy 86.516199 -407.001573) (xy 86.581514 -406.963086) (xy 86.65055 -406.93176) (xy 86.722525 -406.90795)
			(xy 86.796623 -406.891925) (xy 86.872004 -406.883866) (xy 86.90991 -406.883362) (xy 86.947816 -406.883866)
			(xy 87.023197 -406.891925) (xy 87.097295 -406.90795) (xy 87.16927 -406.93176) (xy 87.238306 -406.963086)
			(xy 87.303621 -407.001573) (xy 87.364476 -407.046784) (xy 87.42018 -407.098208) (xy 87.470102 -407.155261)
			(xy 87.513677 -407.217297) (xy 87.550412 -407.283614) (xy 87.579889 -407.35346) (xy 87.601775 -407.426043)
			(xy 87.615822 -407.500541) (xy 87.621871 -407.576111) (xy 88.737949 -407.576111) (xy 88.743998 -407.500541)
			(xy 88.758045 -407.426043) (xy 88.779931 -407.35346) (xy 88.809408 -407.283614) (xy 88.846143 -407.217297)
			(xy 88.889718 -407.155261) (xy 88.93964 -407.098208) (xy 88.995344 -407.046784) (xy 89.056199 -407.001573)
			(xy 89.121514 -406.963086) (xy 89.19055 -406.93176) (xy 89.262525 -406.90795) (xy 89.336623 -406.891925)
			(xy 89.412004 -406.883866) (xy 89.44991 -406.883362) (xy 89.487816 -406.883866) (xy 89.563197 -406.891925)
			(xy 89.637295 -406.90795) (xy 89.70927 -406.93176) (xy 89.778306 -406.963086) (xy 89.843621 -407.001573)
			(xy 89.904476 -407.046784) (xy 89.96018 -407.098208) (xy 90.010102 -407.155261) (xy 90.053677 -407.217297)
			(xy 90.090412 -407.283614) (xy 90.119889 -407.35346) (xy 90.141775 -407.426043) (xy 90.155822 -407.500541)
			(xy 90.161871 -407.576111) (xy 90.159852 -407.651895) (xy 90.14979 -407.727035) (xy 90.131798 -407.80068)
			(xy 90.10608 -407.871996) (xy 90.072928 -407.940173) (xy 90.032716 -408.004441) (xy 89.985901 -408.06407)
			(xy 89.933013 -408.118386) (xy 89.874651 -408.166772) (xy 89.811476 -408.20868) (xy 89.744205 -408.243636)
			(xy 89.6736 -408.271243) (xy 89.600459 -408.291189) (xy 89.525614 -408.303248) (xy 89.44991 -408.307283)
			(xy 89.374206 -408.303248) (xy 89.299361 -408.291189) (xy 89.22622 -408.271243) (xy 89.155615 -408.243636)
			(xy 89.088344 -408.20868) (xy 89.025169 -408.166772) (xy 88.966807 -408.118386) (xy 88.913919 -408.06407)
			(xy 88.867104 -408.004441) (xy 88.826892 -407.940173) (xy 88.79374 -407.871996) (xy 88.768022 -407.80068)
			(xy 88.75003 -407.727035) (xy 88.739968 -407.651895) (xy 88.737949 -407.576111) (xy 87.621871 -407.576111)
			(xy 87.619852 -407.651895) (xy 87.60979 -407.727035) (xy 87.591798 -407.80068) (xy 87.56608 -407.871996)
			(xy 87.532928 -407.940173) (xy 87.492716 -408.004441) (xy 87.445901 -408.06407) (xy 87.393013 -408.118386)
			(xy 87.334651 -408.166772) (xy 87.271476 -408.20868) (xy 87.204205 -408.243636) (xy 87.1336 -408.271243)
			(xy 87.060459 -408.291189) (xy 86.985614 -408.303248) (xy 86.90991 -408.307283) (xy 86.834206 -408.303248)
			(xy 86.759361 -408.291189) (xy 86.68622 -408.271243) (xy 86.615615 -408.243636) (xy 86.548344 -408.20868)
			(xy 86.485169 -408.166772) (xy 86.426807 -408.118386) (xy 86.373919 -408.06407) (xy 86.327104 -408.004441)
			(xy 86.286892 -407.940173) (xy 86.25374 -407.871996) (xy 86.228022 -407.80068) (xy 86.21003 -407.727035)
			(xy 86.199968 -407.651895) (xy 86.197949 -407.576111) (xy 84.822792 -407.576111) (xy 84.822792 -408.080464)
			(xy 84.823374 -408.103687) (xy 84.831826 -408.149356) (xy 84.848438 -408.192729) (xy 84.872656 -408.232361)
			(xy 84.903673 -408.266932) (xy 84.940456 -408.295289) (xy 84.981781 -408.31649) (xy 85.02627 -408.329827)
			(xy 85.072442 -408.334857) (xy 85.11876 -408.331411) (xy 85.163679 -408.319605) (xy 85.205706 -408.299832)
			(xy 85.224874 -408.286712) (xy 85.255763 -408.265143) (xy 85.32126 -408.227908) (xy 85.390325 -408.1978)
			(xy 85.462183 -408.175156) (xy 85.536032 -408.160231) (xy 85.611044 -408.15319) (xy 85.68638 -408.154113)
			(xy 85.761197 -408.162989) (xy 85.834658 -408.17972) (xy 85.90594 -408.204117) (xy 85.974247 -408.235907)
			(xy 86.038812 -408.274736) (xy 86.098915 -408.320168) (xy 86.153882 -408.371695) (xy 86.203098 -408.42874)
			(xy 86.246012 -408.490666) (xy 86.282144 -408.556778) (xy 86.31109 -408.626337) (xy 86.332526 -408.698565)
			(xy 86.346212 -408.772654) (xy 86.351995 -408.847773) (xy 86.34981 -408.923083) (xy 86.339681 -408.997741)
			(xy 86.321722 -409.070911) (xy 86.296134 -409.141775) (xy 86.263203 -409.209538) (xy 86.243668 -409.241752)
			(xy 86.232191 -409.261181) (xy 86.215411 -409.303062) (xy 86.20629 -409.347247) (xy 86.205115 -409.392349)
			(xy 86.211923 -409.43695) (xy 86.2265 -409.479647) (xy 86.248387 -409.519099) (xy 86.276898 -409.554066)
			(xy 86.311136 -409.583449) (xy 86.350024 -409.606324) (xy 86.39234 -409.621973) (xy 86.436755 -409.629903)
			(xy 86.459314 -409.630372) (xy 87.360506 -409.630372) (xy 87.383071 -409.629919) (xy 87.4275 -409.621999)
			(xy 87.469831 -409.606356) (xy 87.508734 -409.583483) (xy 87.542985 -409.554097) (xy 87.571507 -409.519124)
			(xy 87.593403 -409.479663) (xy 87.607986 -409.436955) (xy 87.614795 -409.392343) (xy 87.613618 -409.347229)
			(xy 87.60449 -409.303033) (xy 87.5877 -409.261144) (xy 87.576152 -409.241752) (xy 87.556529 -409.209349)
			(xy 87.523484 -409.14118) (xy 87.497867 -409.069886) (xy 87.479969 -408.996274) (xy 87.469992 -408.921177)
			(xy 87.468048 -408.845446) (xy 87.474161 -408.769936) (xy 87.48826 -408.695503) (xy 87.510187 -408.622989)
			(xy 87.539692 -408.553215) (xy 87.576443 -408.48697) (xy 87.620023 -408.425003) (xy 87.669939 -408.368017)
			(xy 87.725626 -408.316656) (xy 87.786454 -408.271501) (xy 87.851735 -408.233063) (xy 87.92073 -408.201777)
			(xy 87.992657 -408.177998) (xy 88.066704 -408.161994) (xy 88.142032 -408.153946) (xy 88.217788 -408.153946)
			(xy 88.293116 -408.161994) (xy 88.367163 -408.177998) (xy 88.43909 -408.201777) (xy 88.508085 -408.233063)
			(xy 88.573366 -408.271501) (xy 88.634194 -408.316656) (xy 88.689881 -408.368017) (xy 88.739797 -408.425003)
			(xy 88.783377 -408.48697) (xy 88.820128 -408.553215) (xy 88.849633 -408.622989) (xy 88.87156 -408.695503)
			(xy 88.885659 -408.769936) (xy 88.891772 -408.845446) (xy 88.889828 -408.921177) (xy 88.879851 -408.996274)
			(xy 88.861953 -409.069886) (xy 88.836336 -409.14118) (xy 88.803291 -409.209349) (xy 88.783668 -409.241752)
			(xy 88.772191 -409.261181) (xy 88.755411 -409.303062) (xy 88.74629 -409.347247) (xy 88.745115 -409.392349)
			(xy 88.751923 -409.43695) (xy 88.7665 -409.479647) (xy 88.788387 -409.519099) (xy 88.816898 -409.554066)
			(xy 88.851136 -409.583449) (xy 88.890024 -409.606324) (xy 88.93234 -409.621973) (xy 88.976755 -409.629903)
			(xy 88.999314 -409.630372) (xy 89.505282 -409.630372) (xy 90.015568 -409.120086) (xy 90.033602 -409.05684)
			(xy 90.026236 -409.024836) (xy 90.018217 -408.987755) (xy 90.009151 -408.912428) (xy 90.008149 -408.836565)
			(xy 90.015221 -408.761025) (xy 90.030288 -408.686666) (xy 90.053177 -408.614331) (xy 90.083631 -408.544841)
			(xy 90.121303 -408.478984) (xy 90.165765 -408.417508) (xy 90.216514 -408.361109) (xy 90.272974 -408.310428)
			(xy 90.334504 -408.266039) (xy 90.400406 -408.228447) (xy 90.469932 -408.198077) (xy 90.542294 -408.175274)
			(xy 90.616671 -408.160297) (xy 90.69222 -408.153315) (xy 90.768082 -408.154408) (xy 90.843397 -408.163564)
			(xy 90.917312 -408.180679) (xy 90.988987 -408.205558) (xy 91.057609 -408.237919) (xy 91.122401 -408.277395)
			(xy 91.182626 -408.323538) (xy 91.237601 -408.375826) (xy 91.286704 -408.433664) (xy 91.329376 -408.496396)
			(xy 91.365134 -408.563311) (xy 91.393572 -408.63365) (xy 91.40444 -408.669998) (xy 91.41333 -408.701494)
			(xy 91.436698 -408.724862) (xy 91.448794 -408.736318) (xy 91.477617 -408.75301) (xy 91.509777 -408.761674)
			(xy 91.543084 -408.761718) (xy 91.575268 -408.753141) (xy 91.604135 -408.736526) (xy 91.616276 -408.725116)
			(xy 91.634818 -408.70632) (xy 91.646244 -408.694211) (xy 91.662946 -408.665426) (xy 91.671628 -408.633297)
			(xy 91.672156 -408.616658) (xy 91.672156 -408.306016) (xy 91.671693 -408.28992) (xy 91.663635 -408.258753)
			(xy 91.648028 -408.230598) (xy 91.625867 -408.207248) (xy 91.612466 -408.19832) (xy 91.580921 -408.178012)
			(xy 91.521858 -408.131746) (xy 91.46799 -408.079522) (xy 91.419917 -408.02192) (xy 91.37817 -407.95958)
			(xy 91.343214 -407.893194) (xy 91.315437 -407.823498) (xy 91.295147 -407.751267) (xy 91.282569 -407.677302)
			(xy 91.277843 -407.602424) (xy 91.281021 -407.527464) (xy 91.292069 -407.453255) (xy 91.310863 -407.38062)
			(xy 91.337195 -407.310366) (xy 91.370772 -407.243272) (xy 91.411223 -407.180083) (xy 91.458097 -407.121501)
			(xy 91.510874 -407.068175) (xy 91.568969 -407.020699) (xy 91.631737 -406.979598) (xy 91.69848 -406.94533)
			(xy 91.768459 -406.918274) (xy 91.840896 -406.898731) (xy 91.914987 -406.886917) (xy 91.98991 -406.882965)
			(xy 92.064833 -406.886917) (xy 92.138924 -406.898731) (xy 92.211361 -406.918274) (xy 92.28134 -406.94533)
			(xy 92.348083 -406.979598) (xy 92.410851 -407.020699) (xy 92.468946 -407.068175) (xy 92.521723 -407.121501)
			(xy 92.568597 -407.180083) (xy 92.609048 -407.243272) (xy 92.642625 -407.310366) (xy 92.668957 -407.38062)
			(xy 92.687751 -407.453255) (xy 92.698799 -407.527464) (xy 92.701977 -407.602424) (xy 92.697251 -407.677302)
			(xy 92.684673 -407.751267) (xy 92.664383 -407.823498) (xy 92.636606 -407.893194) (xy 92.60165 -407.95958)
			(xy 92.559903 -408.02192) (xy 92.51183 -408.079522) (xy 92.457962 -408.131746) (xy 92.398899 -408.178012)
			(xy 92.367354 -408.19832) (xy 92.353941 -408.207229) (xy 92.331788 -408.230589) (xy 92.316188 -408.25875)
			(xy 92.31044 -408.280991) (xy 93.154757 -408.280991) (xy 93.160779 -408.164808) (xy 93.174802 -408.049317)
			(xy 93.19676 -407.935069) (xy 93.226547 -407.822608) (xy 93.264022 -407.71247) (xy 93.309007 -407.60518)
			(xy 93.361286 -407.501249) (xy 93.420611 -407.401173) (xy 93.486699 -407.305427) (xy 93.559235 -407.21447)
			(xy 93.637874 -407.128734) (xy 93.72224 -407.048627) (xy 93.811932 -406.974531) (xy 93.906522 -406.906801)
			(xy 94.00556 -406.845757) (xy 94.108573 -406.791692) (xy 94.21507 -406.744862) (xy 94.324545 -406.705491)
			(xy 94.436475 -406.673767) (xy 94.550327 -406.649841) (xy 94.665559 -406.633827) (xy 94.781621 -406.6258)
			(xy 94.83979 -406.625298) (xy 94.897959 -406.6258) (xy 95.014021 -406.633827) (xy 95.129253 -406.649841)
			(xy 95.243105 -406.673767) (xy 95.355035 -406.705491) (xy 95.46451 -406.744862) (xy 95.571007 -406.791692)
			(xy 95.67402 -406.845757) (xy 95.773058 -406.906801) (xy 95.867648 -406.974531) (xy 95.95734 -407.048627)
			(xy 96.041706 -407.128734) (xy 96.120345 -407.21447) (xy 96.192881 -407.305427) (xy 96.258969 -407.401173)
			(xy 96.318294 -407.501249) (xy 96.370573 -407.60518) (xy 96.415558 -407.71247) (xy 96.453033 -407.822608)
			(xy 96.48282 -407.935069) (xy 96.504778 -408.049317) (xy 96.518801 -408.164808) (xy 96.524823 -408.280991)
			(xy 96.522815 -408.397313) (xy 96.512786 -408.513219) (xy 96.494785 -408.628156) (xy 96.468897 -408.741579)
			(xy 96.435246 -408.852944) (xy 96.393992 -408.961723) (xy 96.345331 -409.067397) (xy 96.289495 -409.169461)
			(xy 96.226752 -409.26743) (xy 96.157398 -409.360837) (xy 96.081766 -409.449237) (xy 96.000215 -409.532208)
			(xy 95.913134 -409.609355) (xy 95.820938 -409.68031) (xy 95.724066 -409.744736) (xy 95.622981 -409.802325)
			(xy 95.518163 -409.852802) (xy 95.410112 -409.895928) (xy 95.299344 -409.931497) (xy 95.186385 -409.959339)
			(xy 95.071775 -409.979321) (xy 94.95606 -409.991348) (xy 94.83979 -409.995364) (xy 94.72352 -409.991348)
			(xy 94.607805 -409.979321) (xy 94.493195 -409.959339) (xy 94.380236 -409.931497) (xy 94.269468 -409.895928)
			(xy 94.161417 -409.852802) (xy 94.056599 -409.802325) (xy 93.955514 -409.744736) (xy 93.858642 -409.68031)
			(xy 93.766446 -409.609355) (xy 93.679365 -409.532208) (xy 93.597814 -409.449237) (xy 93.522182 -409.360837)
			(xy 93.452828 -409.26743) (xy 93.390085 -409.169461) (xy 93.334249 -409.067397) (xy 93.285588 -408.961723)
			(xy 93.244334 -408.852944) (xy 93.210683 -408.741579) (xy 93.184795 -408.628156) (xy 93.166794 -408.513219)
			(xy 93.156765 -408.397313) (xy 93.154757 -408.280991) (xy 92.31044 -408.280991) (xy 92.308133 -408.289919)
			(xy 92.307664 -408.306016) (xy 92.307664 -408.93238) (xy 90.371422 -410.868876) (xy 84.915756 -410.868876)
			(xy 83.584288 -409.537408) (xy 83.584288 -402.49856) (xy 86.848442 -399.234406) (xy 86.857332 -399.20291)
			(xy 86.865422 -399.176545) (xy 86.888123 -399.126287) (xy 86.917822 -399.07982) (xy 86.953901 -399.038111)
			(xy 86.995608 -399.002031) (xy 87.042074 -398.97233) (xy 87.092331 -398.949627) (xy 87.118698 -398.941544)
			(xy 87.150194 -398.932654) (xy 98.72472 -387.358382) (xy 98.736062 -387.346225) (xy 98.752665 -387.317438)
			(xy 98.761261 -387.285336) (xy 98.761804 -387.26872) (xy 98.761804 -358.770682) (xy 98.761285 -358.754064)
			(xy 98.752677 -358.72196) (xy 98.736075 -358.693166) (xy 98.72472 -358.68102) (xy 94.547182 -354.503736)
			(xy 88.227154 -354.503736) (xy 88.204108 -354.504191) (xy 88.158764 -354.512458) (xy 88.115655 -354.528766)
			(xy 88.076193 -354.552582) (xy 88.041674 -354.583123) (xy 88.013227 -354.619388) (xy 87.991788 -354.660189)
			(xy 87.978058 -354.704188) (xy 87.972487 -354.749941) (xy 87.975259 -354.795949) (xy 87.986283 -354.840702)
			(xy 88.005196 -354.882734) (xy 88.031379 -354.920665) (xy 88.047322 -354.937314) (xy 89.160858 -356.050596)
			(xy 89.190322 -356.059994) (xy 89.215091 -356.068289) (xy 89.262279 -356.090688) (xy 89.30597 -356.119316)
			(xy 89.345346 -356.153638) (xy 89.379671 -356.193012) (xy 89.408301 -356.236701) (xy 89.430703 -356.283888)
			(xy 89.438988 -356.30866) (xy 89.448386 -356.338124) (xy 93.208348 -360.098086) (xy 93.208348 -362.4961)
			(xy 93.2088 -362.519168) (xy 93.217181 -362.564538) (xy 93.233613 -362.60765) (xy 93.257556 -362.647088)
			(xy 93.288224 -362.681557) (xy 93.324609 -362.709925) (xy 93.365517 -362.73126) (xy 93.409604 -362.744861)
			(xy 93.455422 -362.750281) (xy 93.501465 -362.747344) (xy 93.546223 -362.736144) (xy 93.588223 -362.71705)
			(xy 93.626088 -362.690689) (xy 93.642688 -362.674662) (xy 93.683905 -362.633698) (xy 93.771171 -362.556944)
			(xy 93.86352 -362.486386) (xy 93.960512 -362.422362) (xy 94.061687 -362.365175) (xy 94.166562 -362.315098)
			(xy 94.27464 -362.272368) (xy 94.385406 -362.23719) (xy 94.498333 -362.209729) (xy 94.612884 -362.190118)
			(xy 94.728515 -362.178449) (xy 94.844675 -362.174777) (xy 94.960812 -362.179121) (xy 95.076373 -362.191459)
			(xy 95.190809 -362.211733) (xy 95.303575 -362.239846) (xy 95.414136 -362.275665) (xy 95.521964 -362.319019)
			(xy 95.626548 -362.369702) (xy 95.72739 -362.427473) (xy 95.824011 -362.492058) (xy 95.915949 -362.563148)
			(xy 96.00277 -362.640407) (xy 96.084058 -362.723465) (xy 96.159429 -362.81193) (xy 96.228523 -362.905378)
			(xy 96.291011 -363.003367) (xy 96.346597 -363.10543) (xy 96.395016 -363.211081) (xy 96.436038 -363.319819)
			(xy 96.469467 -363.431125) (xy 96.495145 -363.544471) (xy 96.512949 -363.659317) (xy 96.522796 -363.775117)
			(xy 96.524637 -363.89132) (xy 96.518464 -364.007374) (xy 96.504307 -364.122727) (xy 96.482233 -364.236829)
			(xy 96.452347 -364.349139) (xy 96.414791 -364.459121) (xy 96.369744 -364.566254) (xy 96.317419 -364.670026)
			(xy 96.258066 -364.769946) (xy 96.191968 -364.865536) (xy 96.119438 -364.956344) (xy 96.040821 -365.041936)
			(xy 95.956492 -365.121907) (xy 95.866852 -365.195874) (xy 95.772326 -365.263487) (xy 95.673365 -365.324424)
			(xy 95.570439 -365.378396) (xy 95.464038 -365.425144) (xy 95.354668 -365.464448) (xy 95.242849 -365.496119)
			(xy 95.129113 -365.520009) (xy 95.014001 -365.536002) (xy 94.89806 -365.544022) (xy 94.781842 -365.544033)
			(xy 94.665899 -365.536033) (xy 94.550784 -365.52006) (xy 94.437044 -365.496192) (xy 94.325219 -365.46454)
			(xy 94.215842 -365.425256) (xy 94.109432 -365.378526) (xy 94.006497 -365.324574) (xy 93.907525 -365.263654)
			(xy 93.812987 -365.196058) (xy 93.723334 -365.122107) (xy 93.63899 -365.042151) (xy 93.560358 -364.956573)
			(xy 93.487812 -364.865778) (xy 93.421696 -364.770199) (xy 93.362326 -364.670291) (xy 93.309983 -364.566527)
			(xy 93.264916 -364.459403) (xy 93.22734 -364.349427) (xy 93.211904 -364.293404) (xy 93.205684 -364.272087)
			(xy 93.186966 -364.231826) (xy 93.161539 -364.195428) (xy 93.130176 -364.164) (xy 93.093831 -364.138498)
			(xy 93.053608 -364.119696) (xy 93.010732 -364.108167) (xy 92.966504 -364.104261) (xy 92.92227 -364.108096)
			(xy 92.879375 -364.119557) (xy 92.839123 -364.138294) (xy 92.802737 -364.163738) (xy 92.786708 -364.179104)
			(xy 91.08059 -365.884968) (xy 86.660482 -365.884968) (xy 85.894926 -365.119412) (xy 85.83168 -365.101378)
			(xy 85.799676 -365.108744) (xy 85.762567 -365.11672) (xy 85.687208 -365.125801) (xy 85.611311 -365.12681)
			(xy 85.535737 -365.119737) (xy 85.461345 -365.104663) (xy 85.38898 -365.081757) (xy 85.319462 -365.051281)
			(xy 85.253583 -365.013581) (xy 85.192089 -364.969084) (xy 85.13568 -364.918296) (xy 85.084996 -364.861793)
			(xy 85.040612 -364.800218) (xy 85.003032 -364.73427) (xy 84.972684 -364.664697) (xy 84.949911 -364.592289)
			(xy 84.934973 -364.51787) (xy 84.928039 -364.442283) (xy 84.929188 -364.366388) (xy 84.938406 -364.291046)
			(xy 84.95559 -364.217112) (xy 84.980543 -364.145427) (xy 85.012984 -364.076804) (xy 85.052542 -364.012024)
			(xy 85.098769 -363.95182) (xy 85.15114 -363.896878) (xy 85.209061 -363.84782) (xy 85.271873 -363.805205)
			(xy 85.305138 -363.786928) (xy 85.323994 -363.776462) (xy 85.358091 -363.75006) (xy 85.387238 -363.718277)
			(xy 85.410595 -363.682026) (xy 85.427492 -363.642349) (xy 85.437442 -363.600389) (xy 85.44016 -363.55735)
			(xy 85.435567 -363.514471) (xy 85.423795 -363.472984) (xy 85.405183 -363.434083) (xy 85.380266 -363.398886)
			(xy 85.365336 -363.383322) (xy 84.20608 -362.224066) (xy 84.20608 -361.447842) (xy 81.830926 -359.072688)
			(xy 39.523416 -359.072688) (xy 37.947854 -357.496872) (xy 37.93571 -357.485516) (xy 37.906916 -357.468918)
			(xy 37.87481 -357.460327) (xy 37.858192 -357.459788) (xy 36.634928 -357.459788) (xy 36.612036 -357.460304)
			(xy 36.566993 -357.468501) (xy 36.524147 -357.484635) (xy 36.484885 -357.508183) (xy 36.450476 -357.538384)
			(xy 36.422034 -357.574261) (xy 36.40048 -357.614653) (xy 36.38651 -357.658252) (xy 36.380578 -357.703649)
			(xy 36.382873 -357.749375) (xy 36.393324 -357.793949) (xy 36.40201 -357.815134) (xy 36.418829 -357.855064)
			(xy 36.445919 -357.937371) (xy 36.465322 -358.021821) (xy 36.476873 -358.107698) (xy 36.480474 -358.194273)
			(xy 36.476094 -358.280813) (xy 36.46377 -358.366582) (xy 36.443608 -358.450854) (xy 36.415778 -358.532913)
			(xy 36.380516 -358.612064) (xy 36.338121 -358.687635) (xy 36.288953 -358.758985) (xy 36.233429 -358.825508)
			(xy 36.172021 -358.886641) (xy 36.105248 -358.941865) (xy 36.033677 -358.990711) (xy 35.957917 -359.032765)
			(xy 35.878608 -359.06767) (xy 35.796424 -359.095131) (xy 35.712062 -359.114914) (xy 35.626238 -359.126851)
			(xy 35.53968 -359.130841) (xy 35.453122 -359.126851) (xy 35.367298 -359.114914) (xy 35.282936 -359.095131)
			(xy 35.200752 -359.06767) (xy 35.121443 -359.032765) (xy 35.045683 -358.990711) (xy 34.974112 -358.941865)
			(xy 34.907339 -358.886641) (xy 34.845931 -358.825508) (xy 34.790407 -358.758985) (xy 34.741239 -358.687635)
			(xy 34.698844 -358.612064) (xy 34.663582 -358.532913) (xy 34.635752 -358.450854) (xy 34.61559 -358.366582)
			(xy 34.603266 -358.280813) (xy 34.598886 -358.194273) (xy 34.602487 -358.107698) (xy 34.614038 -358.021821)
			(xy 34.633441 -357.937371) (xy 34.660531 -357.855064) (xy 34.67735 -357.815134) (xy 34.686012 -357.79394)
			(xy 34.696459 -357.749367) (xy 34.698753 -357.703643) (xy 34.692821 -357.658248) (xy 34.678853 -357.61465)
			(xy 34.657302 -357.574259) (xy 34.628864 -357.538381) (xy 34.594461 -357.508178) (xy 34.555203 -357.484624)
			(xy 34.512362 -357.468484) (xy 34.467322 -357.460278) (xy 34.444432 -357.459788) (xy 31.554928 -357.459788)
			(xy 31.532036 -357.460304) (xy 31.486993 -357.468501) (xy 31.444147 -357.484635) (xy 31.404885 -357.508183)
			(xy 31.370476 -357.538384) (xy 31.342034 -357.574261) (xy 31.32048 -357.614653) (xy 31.30651 -357.658252)
			(xy 31.300578 -357.703649) (xy 31.302873 -357.749375) (xy 31.313324 -357.793949) (xy 31.32201 -357.815134)
			(xy 31.338829 -357.855064) (xy 31.365919 -357.937371) (xy 31.385322 -358.021821) (xy 31.396873 -358.107698)
			(xy 31.400474 -358.194273) (xy 31.396094 -358.280813) (xy 31.38377 -358.366582) (xy 31.363608 -358.450854)
			(xy 31.335778 -358.532913) (xy 31.300516 -358.612064) (xy 31.258121 -358.687635) (xy 31.208953 -358.758985)
			(xy 31.153429 -358.825508) (xy 31.092021 -358.886641) (xy 31.025248 -358.941865) (xy 30.953677 -358.990711)
			(xy 30.877917 -359.032765) (xy 30.798608 -359.06767) (xy 30.716424 -359.095131) (xy 30.632062 -359.114914)
			(xy 30.546238 -359.126851) (xy 30.45968 -359.130841) (xy 30.373122 -359.126851) (xy 30.287298 -359.114914)
			(xy 30.202936 -359.095131) (xy 30.120752 -359.06767) (xy 30.041443 -359.032765) (xy 29.965683 -358.990711)
			(xy 29.894112 -358.941865) (xy 29.827339 -358.886641) (xy 29.765931 -358.825508) (xy 29.710407 -358.758985)
			(xy 29.661239 -358.687635) (xy 29.618844 -358.612064) (xy 29.583582 -358.532913) (xy 29.555752 -358.450854)
			(xy 29.53559 -358.366582) (xy 29.523266 -358.280813) (xy 29.518886 -358.194273) (xy 29.522487 -358.107698)
			(xy 29.534038 -358.021821) (xy 29.553441 -357.937371) (xy 29.580531 -357.855064) (xy 29.59735 -357.815134)
			(xy 29.606012 -357.79394) (xy 29.616459 -357.749367) (xy 29.618753 -357.703643) (xy 29.612821 -357.658248)
			(xy 29.598853 -357.61465) (xy 29.577302 -357.574259) (xy 29.548864 -357.538381) (xy 29.514461 -357.508178)
			(xy 29.475203 -357.484624) (xy 29.432362 -357.468484) (xy 29.387322 -357.460278) (xy 29.364432 -357.459788)
			(xy 27.096974 -357.459788) (xy 24.439626 -354.802694) (xy 24.40813 -354.793804) (xy 24.381776 -354.78568)
			(xy 24.331519 -354.762984) (xy 24.285052 -354.73329) (xy 24.243343 -354.697217) (xy 24.20726 -354.655516)
			(xy 24.177556 -354.609055) (xy 24.154849 -354.558803) (xy 24.146764 -354.532438) (xy 24.137874 -354.500942)
			(xy 22.705568 -353.068382) (xy 22.688988 -353.05235) (xy 22.651033 -353.026148) (xy 22.608975 -353.00722)
			(xy 22.564193 -352.996186) (xy 22.518156 -352.993409) (xy 22.472373 -352.998979) (xy 22.428345 -353.012714)
			(xy 22.387515 -353.034164) (xy 22.351223 -353.062624) (xy 22.320657 -353.097162) (xy 22.296822 -353.136646)
			(xy 22.280497 -353.179781) (xy 22.272218 -353.225153) (xy 22.271736 -353.248214) (xy 22.271736 -360.537016)
			(xy 26.776171 -360.537016) (xy 26.782271 -360.481579) (xy 26.796377 -360.427622) (xy 26.818189 -360.376293)
			(xy 26.847243 -360.328687) (xy 26.882918 -360.285819) (xy 26.924455 -360.248602) (xy 26.970968 -360.217829)
			(xy 27.021465 -360.194157) (xy 27.074872 -360.178089) (xy 27.130048 -360.169969) (xy 27.157934 -360.16946)
			(xy 27.18582 -360.169969) (xy 27.240996 -360.178089) (xy 27.294403 -360.194157) (xy 27.3449 -360.217829)
			(xy 27.391413 -360.248602) (xy 27.43295 -360.285819) (xy 27.468625 -360.328687) (xy 27.497679 -360.376293)
			(xy 27.519491 -360.427622) (xy 27.533597 -360.481579) (xy 27.539697 -360.537016) (xy 27.53766 -360.59275)
			(xy 27.52753 -360.647593) (xy 27.509523 -360.700377) (xy 27.484022 -360.749977) (xy 27.467201 -360.773488)
			(xy 29.519874 -360.773488) (xy 29.519874 -360.686588) (xy 29.527892 -360.600059) (xy 29.54386 -360.514639)
			(xy 29.567641 -360.431057) (xy 29.599033 -360.350025) (xy 29.637767 -360.272236) (xy 29.683514 -360.198352)
			(xy 29.735883 -360.129005) (xy 29.794427 -360.064785) (xy 29.858647 -360.006241) (xy 29.927994 -359.953872)
			(xy 30.001878 -359.908125) (xy 30.079667 -359.869391) (xy 30.160699 -359.837999) (xy 30.244281 -359.814218)
			(xy 30.329701 -359.79825) (xy 30.41623 -359.790232) (xy 30.45968 -359.78973) (xy 30.50313 -359.790232)
			(xy 30.589659 -359.79825) (xy 30.675079 -359.814218) (xy 30.758661 -359.837999) (xy 30.839693 -359.869391)
			(xy 30.917482 -359.908125) (xy 30.991366 -359.953872) (xy 31.060713 -360.006241) (xy 31.124933 -360.064785)
			(xy 31.183477 -360.129005) (xy 31.235846 -360.198352) (xy 31.281593 -360.272236) (xy 31.320327 -360.350025)
			(xy 31.351719 -360.431057) (xy 31.3755 -360.514639) (xy 31.391468 -360.600059) (xy 31.399486 -360.686588)
			(xy 31.399486 -360.773488) (xy 34.599874 -360.773488) (xy 34.599874 -360.686588) (xy 34.607892 -360.600059)
			(xy 34.62386 -360.514639) (xy 34.647641 -360.431057) (xy 34.679033 -360.350025) (xy 34.717767 -360.272236)
			(xy 34.763514 -360.198352) (xy 34.815883 -360.129005) (xy 34.874427 -360.064785) (xy 34.938647 -360.006241)
			(xy 35.007994 -359.953872) (xy 35.081878 -359.908125) (xy 35.159667 -359.869391) (xy 35.240699 -359.837999)
			(xy 35.324281 -359.814218) (xy 35.409701 -359.79825) (xy 35.49623 -359.790232) (xy 35.53968 -359.78973)
			(xy 35.58313 -359.790232) (xy 35.669659 -359.79825) (xy 35.755079 -359.814218) (xy 35.838661 -359.837999)
			(xy 35.919693 -359.869391) (xy 35.997482 -359.908125) (xy 36.071366 -359.953872) (xy 36.140713 -360.006241)
			(xy 36.204933 -360.064785) (xy 36.263477 -360.129005) (xy 36.315846 -360.198352) (xy 36.361593 -360.272236)
			(xy 36.400327 -360.350025) (xy 36.431719 -360.431057) (xy 36.4555 -360.514639) (xy 36.471468 -360.600059)
			(xy 36.479486 -360.686588) (xy 36.479486 -360.773488) (xy 36.471468 -360.860017) (xy 36.4555 -360.945437)
			(xy 36.431719 -361.029019) (xy 36.400327 -361.110051) (xy 36.361593 -361.18784) (xy 36.315846 -361.261724)
			(xy 36.263477 -361.331071) (xy 36.204933 -361.395291) (xy 36.140713 -361.453835) (xy 36.071366 -361.506204)
			(xy 35.997482 -361.551951) (xy 35.919693 -361.590685) (xy 35.838661 -361.622077) (xy 35.755079 -361.645858)
			(xy 35.669659 -361.661826) (xy 35.58313 -361.669844) (xy 35.49623 -361.669844) (xy 35.409701 -361.661826)
			(xy 35.324281 -361.645858) (xy 35.240699 -361.622077) (xy 35.159667 -361.590685) (xy 35.081878 -361.551951)
			(xy 35.007994 -361.506204) (xy 34.938647 -361.453835) (xy 34.874427 -361.395291) (xy 34.815883 -361.331071)
			(xy 34.763514 -361.261724) (xy 34.717767 -361.18784) (xy 34.679033 -361.110051) (xy 34.647641 -361.029019)
			(xy 34.62386 -360.945437) (xy 34.607892 -360.860017) (xy 34.599874 -360.773488) (xy 31.399486 -360.773488)
			(xy 31.391468 -360.860017) (xy 31.3755 -360.945437) (xy 31.351719 -361.029019) (xy 31.320327 -361.110051)
			(xy 31.281593 -361.18784) (xy 31.235846 -361.261724) (xy 31.183477 -361.331071) (xy 31.124933 -361.395291)
			(xy 31.060713 -361.453835) (xy 30.991366 -361.506204) (xy 30.917482 -361.551951) (xy 30.839693 -361.590685)
			(xy 30.758661 -361.622077) (xy 30.675079 -361.645858) (xy 30.589659 -361.661826) (xy 30.50313 -361.669844)
			(xy 30.41623 -361.669844) (xy 30.329701 -361.661826) (xy 30.244281 -361.645858) (xy 30.160699 -361.622077)
			(xy 30.079667 -361.590685) (xy 30.001878 -361.551951) (xy 29.927994 -361.506204) (xy 29.858647 -361.453835)
			(xy 29.794427 -361.395291) (xy 29.735883 -361.331071) (xy 29.683514 -361.261724) (xy 29.637767 -361.18784)
			(xy 29.599033 -361.110051) (xy 29.567641 -361.029019) (xy 29.54386 -360.945437) (xy 29.527892 -360.860017)
			(xy 29.519874 -360.773488) (xy 27.467201 -360.773488) (xy 27.451571 -360.795335) (xy 27.412862 -360.835484)
			(xy 27.368719 -360.86957) (xy 27.320084 -360.896866) (xy 27.267993 -360.916789) (xy 27.213556 -360.928915)
			(xy 27.157934 -360.932986) (xy 27.102312 -360.928915) (xy 27.047875 -360.916789) (xy 26.995784 -360.896866)
			(xy 26.947149 -360.86957) (xy 26.903006 -360.835484) (xy 26.864297 -360.795335) (xy 26.831846 -360.749977)
			(xy 26.806345 -360.700377) (xy 26.788338 -360.647593) (xy 26.778208 -360.59275) (xy 26.776171 -360.537016)
			(xy 22.271736 -360.537016) (xy 22.271736 -363.313488) (xy 29.519874 -363.313488) (xy 29.519874 -363.226588)
			(xy 29.527892 -363.140059) (xy 29.54386 -363.054639) (xy 29.567641 -362.971057) (xy 29.599033 -362.890025)
			(xy 29.637767 -362.812236) (xy 29.683514 -362.738352) (xy 29.735883 -362.669005) (xy 29.794427 -362.604785)
			(xy 29.858647 -362.546241) (xy 29.927994 -362.493872) (xy 30.001878 -362.448125) (xy 30.079667 -362.409391)
			(xy 30.160699 -362.377999) (xy 30.244281 -362.354218) (xy 30.329701 -362.33825) (xy 30.41623 -362.330232)
			(xy 30.45968 -362.32973) (xy 30.50313 -362.330232) (xy 30.589659 -362.33825) (xy 30.675079 -362.354218)
			(xy 30.758661 -362.377999) (xy 30.839693 -362.409391) (xy 30.917482 -362.448125) (xy 30.991366 -362.493872)
			(xy 31.060713 -362.546241) (xy 31.124933 -362.604785) (xy 31.183477 -362.669005) (xy 31.235846 -362.738352)
			(xy 31.281593 -362.812236) (xy 31.320327 -362.890025) (xy 31.351719 -362.971057) (xy 31.3755 -363.054639)
			(xy 31.391468 -363.140059) (xy 31.399486 -363.226588) (xy 31.399486 -363.313488) (xy 34.599874 -363.313488)
			(xy 34.599874 -363.226588) (xy 34.607892 -363.140059) (xy 34.62386 -363.054639) (xy 34.647641 -362.971057)
			(xy 34.679033 -362.890025) (xy 34.717767 -362.812236) (xy 34.763514 -362.738352) (xy 34.815883 -362.669005)
			(xy 34.874427 -362.604785) (xy 34.938647 -362.546241) (xy 35.007994 -362.493872) (xy 35.081878 -362.448125)
			(xy 35.159667 -362.409391) (xy 35.240699 -362.377999) (xy 35.324281 -362.354218) (xy 35.409701 -362.33825)
			(xy 35.49623 -362.330232) (xy 35.53968 -362.32973) (xy 35.58313 -362.330232) (xy 35.669659 -362.33825)
			(xy 35.755079 -362.354218) (xy 35.838661 -362.377999) (xy 35.919693 -362.409391) (xy 35.997482 -362.448125)
			(xy 36.050645 -362.481042) (xy 39.818314 -362.481042) (xy 39.824323 -362.365104) (xy 39.838316 -362.249857)
			(xy 39.860227 -362.135851) (xy 39.889952 -362.023627) (xy 39.927348 -361.913721) (xy 39.972237 -361.806658)
			(xy 40.024406 -361.702946) (xy 40.083606 -361.603081) (xy 40.149555 -361.507538) (xy 40.221938 -361.416772)
			(xy 40.300411 -361.331217) (xy 40.384599 -361.251279) (xy 40.474101 -361.17734) (xy 40.568492 -361.109752)
			(xy 40.66732 -361.048838) (xy 40.770116 -360.994886) (xy 40.876389 -360.948156) (xy 40.985633 -360.908868)
			(xy 41.097326 -360.877211) (xy 41.210938 -360.853335) (xy 41.325926 -360.837354) (xy 41.441743 -360.829345)
			(xy 41.49979 -360.828844) (xy 41.557837 -360.829345) (xy 41.673654 -360.837354) (xy 41.788642 -360.853335)
			(xy 41.902254 -360.877211) (xy 42.013947 -360.908868) (xy 42.123191 -360.948156) (xy 42.229464 -360.994886)
			(xy 42.33226 -361.048838) (xy 42.431088 -361.109752) (xy 42.474869 -361.141101) (xy 63.647829 -361.141101)
			(xy 63.653878 -361.065531) (xy 63.667925 -360.991033) (xy 63.689811 -360.91845) (xy 63.719288 -360.848604)
			(xy 63.756023 -360.782287) (xy 63.799598 -360.720251) (xy 63.84952 -360.663198) (xy 63.905224 -360.611774)
			(xy 63.966079 -360.566563) (xy 64.031394 -360.528076) (xy 64.10043 -360.49675) (xy 64.172405 -360.47294)
			(xy 64.246503 -360.456915) (xy 64.321884 -360.448856) (xy 64.35979 -360.448352) (xy 64.397696 -360.448856)
			(xy 64.473077 -360.456915) (xy 64.547175 -360.47294) (xy 64.61915 -360.49675) (xy 64.688186 -360.528076)
			(xy 64.753501 -360.566563) (xy 64.814356 -360.611774) (xy 64.87006 -360.663198) (xy 64.919982 -360.720251)
			(xy 64.963557 -360.782287) (xy 65.000292 -360.848604) (xy 65.029769 -360.91845) (xy 65.051655 -360.991033)
			(xy 65.065702 -361.065531) (xy 65.071751 -361.141101) (xy 66.187829 -361.141101) (xy 66.193878 -361.065531)
			(xy 66.207925 -360.991033) (xy 66.229811 -360.91845) (xy 66.259288 -360.848604) (xy 66.296023 -360.782287)
			(xy 66.339598 -360.720251) (xy 66.38952 -360.663198) (xy 66.445224 -360.611774) (xy 66.506079 -360.566563)
			(xy 66.571394 -360.528076) (xy 66.64043 -360.49675) (xy 66.712405 -360.47294) (xy 66.786503 -360.456915)
			(xy 66.861884 -360.448856) (xy 66.89979 -360.448352) (xy 66.937696 -360.448856) (xy 67.013077 -360.456915)
			(xy 67.087175 -360.47294) (xy 67.15915 -360.49675) (xy 67.228186 -360.528076) (xy 67.293501 -360.566563)
			(xy 67.354356 -360.611774) (xy 67.41006 -360.663198) (xy 67.459982 -360.720251) (xy 67.503557 -360.782287)
			(xy 67.540292 -360.848604) (xy 67.569769 -360.91845) (xy 67.591655 -360.991033) (xy 67.605702 -361.065531)
			(xy 67.611751 -361.141101) (xy 68.727829 -361.141101) (xy 68.733878 -361.065531) (xy 68.747925 -360.991033)
			(xy 68.769811 -360.91845) (xy 68.799288 -360.848604) (xy 68.836023 -360.782287) (xy 68.879598 -360.720251)
			(xy 68.92952 -360.663198) (xy 68.985224 -360.611774) (xy 69.046079 -360.566563) (xy 69.111394 -360.528076)
			(xy 69.18043 -360.49675) (xy 69.252405 -360.47294) (xy 69.326503 -360.456915) (xy 69.401884 -360.448856)
			(xy 69.43979 -360.448352) (xy 69.477696 -360.448856) (xy 69.553077 -360.456915) (xy 69.627175 -360.47294)
			(xy 69.69915 -360.49675) (xy 69.768186 -360.528076) (xy 69.833501 -360.566563) (xy 69.894356 -360.611774)
			(xy 69.95006 -360.663198) (xy 69.999982 -360.720251) (xy 70.043557 -360.782287) (xy 70.080292 -360.848604)
			(xy 70.109769 -360.91845) (xy 70.131655 -360.991033) (xy 70.145702 -361.065531) (xy 70.151751 -361.141101)
			(xy 71.267829 -361.141101) (xy 71.273878 -361.065531) (xy 71.287925 -360.991033) (xy 71.309811 -360.91845)
			(xy 71.339288 -360.848604) (xy 71.376023 -360.782287) (xy 71.419598 -360.720251) (xy 71.46952 -360.663198)
			(xy 71.525224 -360.611774) (xy 71.586079 -360.566563) (xy 71.651394 -360.528076) (xy 71.72043 -360.49675)
			(xy 71.792405 -360.47294) (xy 71.866503 -360.456915) (xy 71.941884 -360.448856) (xy 71.97979 -360.448352)
			(xy 72.017696 -360.448856) (xy 72.093077 -360.456915) (xy 72.167175 -360.47294) (xy 72.23915 -360.49675)
			(xy 72.308186 -360.528076) (xy 72.373501 -360.566563) (xy 72.434356 -360.611774) (xy 72.49006 -360.663198)
			(xy 72.539982 -360.720251) (xy 72.583557 -360.782287) (xy 72.620292 -360.848604) (xy 72.649769 -360.91845)
			(xy 72.671655 -360.991033) (xy 72.685702 -361.065531) (xy 72.691751 -361.141101) (xy 73.807829 -361.141101)
			(xy 73.813878 -361.065531) (xy 73.827925 -360.991033) (xy 73.849811 -360.91845) (xy 73.879288 -360.848604)
			(xy 73.916023 -360.782287) (xy 73.959598 -360.720251) (xy 74.00952 -360.663198) (xy 74.065224 -360.611774)
			(xy 74.126079 -360.566563) (xy 74.191394 -360.528076) (xy 74.26043 -360.49675) (xy 74.332405 -360.47294)
			(xy 74.406503 -360.456915) (xy 74.481884 -360.448856) (xy 74.51979 -360.448352) (xy 74.557696 -360.448856)
			(xy 74.633077 -360.456915) (xy 74.707175 -360.47294) (xy 74.77915 -360.49675) (xy 74.848186 -360.528076)
			(xy 74.913501 -360.566563) (xy 74.974356 -360.611774) (xy 75.03006 -360.663198) (xy 75.079982 -360.720251)
			(xy 75.123557 -360.782287) (xy 75.160292 -360.848604) (xy 75.189769 -360.91845) (xy 75.211655 -360.991033)
			(xy 75.225702 -361.065531) (xy 75.231751 -361.141101) (xy 76.347829 -361.141101) (xy 76.353878 -361.065531)
			(xy 76.367925 -360.991033) (xy 76.389811 -360.91845) (xy 76.419288 -360.848604) (xy 76.456023 -360.782287)
			(xy 76.499598 -360.720251) (xy 76.54952 -360.663198) (xy 76.605224 -360.611774) (xy 76.666079 -360.566563)
			(xy 76.731394 -360.528076) (xy 76.80043 -360.49675) (xy 76.872405 -360.47294) (xy 76.946503 -360.456915)
			(xy 77.021884 -360.448856) (xy 77.05979 -360.448352) (xy 77.097696 -360.448856) (xy 77.173077 -360.456915)
			(xy 77.247175 -360.47294) (xy 77.31915 -360.49675) (xy 77.388186 -360.528076) (xy 77.453501 -360.566563)
			(xy 77.514356 -360.611774) (xy 77.57006 -360.663198) (xy 77.619982 -360.720251) (xy 77.663557 -360.782287)
			(xy 77.700292 -360.848604) (xy 77.729769 -360.91845) (xy 77.751655 -360.991033) (xy 77.765702 -361.065531)
			(xy 77.771751 -361.141101) (xy 78.887829 -361.141101) (xy 78.893878 -361.065531) (xy 78.907925 -360.991033)
			(xy 78.929811 -360.91845) (xy 78.959288 -360.848604) (xy 78.996023 -360.782287) (xy 79.039598 -360.720251)
			(xy 79.08952 -360.663198) (xy 79.145224 -360.611774) (xy 79.206079 -360.566563) (xy 79.271394 -360.528076)
			(xy 79.34043 -360.49675) (xy 79.412405 -360.47294) (xy 79.486503 -360.456915) (xy 79.561884 -360.448856)
			(xy 79.59979 -360.448352) (xy 79.637696 -360.448856) (xy 79.713077 -360.456915) (xy 79.787175 -360.47294)
			(xy 79.85915 -360.49675) (xy 79.928186 -360.528076) (xy 79.993501 -360.566563) (xy 80.054356 -360.611774)
			(xy 80.11006 -360.663198) (xy 80.159982 -360.720251) (xy 80.203557 -360.782287) (xy 80.240292 -360.848604)
			(xy 80.269769 -360.91845) (xy 80.291655 -360.991033) (xy 80.305702 -361.065531) (xy 80.311751 -361.141101)
			(xy 81.427829 -361.141101) (xy 81.433878 -361.065531) (xy 81.447925 -360.991033) (xy 81.469811 -360.91845)
			(xy 81.499288 -360.848604) (xy 81.536023 -360.782287) (xy 81.579598 -360.720251) (xy 81.62952 -360.663198)
			(xy 81.685224 -360.611774) (xy 81.746079 -360.566563) (xy 81.811394 -360.528076) (xy 81.88043 -360.49675)
			(xy 81.952405 -360.47294) (xy 82.026503 -360.456915) (xy 82.101884 -360.448856) (xy 82.13979 -360.448352)
			(xy 82.177696 -360.448856) (xy 82.253077 -360.456915) (xy 82.327175 -360.47294) (xy 82.39915 -360.49675)
			(xy 82.468186 -360.528076) (xy 82.533501 -360.566563) (xy 82.594356 -360.611774) (xy 82.65006 -360.663198)
			(xy 82.699982 -360.720251) (xy 82.743557 -360.782287) (xy 82.780292 -360.848604) (xy 82.809769 -360.91845)
			(xy 82.831655 -360.991033) (xy 82.845702 -361.065531) (xy 82.851751 -361.141101) (xy 82.849732 -361.216885)
			(xy 82.83967 -361.292025) (xy 82.821678 -361.36567) (xy 82.79596 -361.436986) (xy 82.762808 -361.505163)
			(xy 82.722596 -361.569431) (xy 82.675781 -361.62906) (xy 82.622893 -361.683376) (xy 82.564531 -361.731762)
			(xy 82.501356 -361.77367) (xy 82.434085 -361.808626) (xy 82.36348 -361.836233) (xy 82.290339 -361.856179)
			(xy 82.215494 -361.868238) (xy 82.13979 -361.872273) (xy 82.064086 -361.868238) (xy 81.989241 -361.856179)
			(xy 81.9161 -361.836233) (xy 81.845495 -361.808626) (xy 81.778224 -361.77367) (xy 81.715049 -361.731762)
			(xy 81.656687 -361.683376) (xy 81.603799 -361.62906) (xy 81.556984 -361.569431) (xy 81.516772 -361.505163)
			(xy 81.48362 -361.436986) (xy 81.457902 -361.36567) (xy 81.43991 -361.292025) (xy 81.429848 -361.216885)
			(xy 81.427829 -361.141101) (xy 80.311751 -361.141101) (xy 80.309732 -361.216885) (xy 80.29967 -361.292025)
			(xy 80.281678 -361.36567) (xy 80.25596 -361.436986) (xy 80.222808 -361.505163) (xy 80.182596 -361.569431)
			(xy 80.135781 -361.62906) (xy 80.082893 -361.683376) (xy 80.024531 -361.731762) (xy 79.961356 -361.77367)
			(xy 79.894085 -361.808626) (xy 79.82348 -361.836233) (xy 79.750339 -361.856179) (xy 79.675494 -361.868238)
			(xy 79.59979 -361.872273) (xy 79.524086 -361.868238) (xy 79.449241 -361.856179) (xy 79.3761 -361.836233)
			(xy 79.305495 -361.808626) (xy 79.238224 -361.77367) (xy 79.175049 -361.731762) (xy 79.116687 -361.683376)
			(xy 79.063799 -361.62906) (xy 79.016984 -361.569431) (xy 78.976772 -361.505163) (xy 78.94362 -361.436986)
			(xy 78.917902 -361.36567) (xy 78.89991 -361.292025) (xy 78.889848 -361.216885) (xy 78.887829 -361.141101)
			(xy 77.771751 -361.141101) (xy 77.769732 -361.216885) (xy 77.75967 -361.292025) (xy 77.741678 -361.36567)
			(xy 77.71596 -361.436986) (xy 77.682808 -361.505163) (xy 77.642596 -361.569431) (xy 77.595781 -361.62906)
			(xy 77.542893 -361.683376) (xy 77.484531 -361.731762) (xy 77.421356 -361.77367) (xy 77.354085 -361.808626)
			(xy 77.28348 -361.836233) (xy 77.210339 -361.856179) (xy 77.135494 -361.868238) (xy 77.05979 -361.872273)
			(xy 76.984086 -361.868238) (xy 76.909241 -361.856179) (xy 76.8361 -361.836233) (xy 76.765495 -361.808626)
			(xy 76.698224 -361.77367) (xy 76.635049 -361.731762) (xy 76.576687 -361.683376) (xy 76.523799 -361.62906)
			(xy 76.476984 -361.569431) (xy 76.436772 -361.505163) (xy 76.40362 -361.436986) (xy 76.377902 -361.36567)
			(xy 76.35991 -361.292025) (xy 76.349848 -361.216885) (xy 76.347829 -361.141101) (xy 75.231751 -361.141101)
			(xy 75.229732 -361.216885) (xy 75.21967 -361.292025) (xy 75.201678 -361.36567) (xy 75.17596 -361.436986)
			(xy 75.142808 -361.505163) (xy 75.102596 -361.569431) (xy 75.055781 -361.62906) (xy 75.002893 -361.683376)
			(xy 74.944531 -361.731762) (xy 74.881356 -361.77367) (xy 74.814085 -361.808626) (xy 74.74348 -361.836233)
			(xy 74.670339 -361.856179) (xy 74.595494 -361.868238) (xy 74.51979 -361.872273) (xy 74.444086 -361.868238)
			(xy 74.369241 -361.856179) (xy 74.2961 -361.836233) (xy 74.225495 -361.808626) (xy 74.158224 -361.77367)
			(xy 74.095049 -361.731762) (xy 74.036687 -361.683376) (xy 73.983799 -361.62906) (xy 73.936984 -361.569431)
			(xy 73.896772 -361.505163) (xy 73.86362 -361.436986) (xy 73.837902 -361.36567) (xy 73.81991 -361.292025)
			(xy 73.809848 -361.216885) (xy 73.807829 -361.141101) (xy 72.691751 -361.141101) (xy 72.689732 -361.216885)
			(xy 72.67967 -361.292025) (xy 72.661678 -361.36567) (xy 72.63596 -361.436986) (xy 72.602808 -361.505163)
			(xy 72.562596 -361.569431) (xy 72.515781 -361.62906) (xy 72.462893 -361.683376) (xy 72.404531 -361.731762)
			(xy 72.341356 -361.77367) (xy 72.274085 -361.808626) (xy 72.20348 -361.836233) (xy 72.130339 -361.856179)
			(xy 72.055494 -361.868238) (xy 71.97979 -361.872273) (xy 71.904086 -361.868238) (xy 71.829241 -361.856179)
			(xy 71.7561 -361.836233) (xy 71.685495 -361.808626) (xy 71.618224 -361.77367) (xy 71.555049 -361.731762)
			(xy 71.496687 -361.683376) (xy 71.443799 -361.62906) (xy 71.396984 -361.569431) (xy 71.356772 -361.505163)
			(xy 71.32362 -361.436986) (xy 71.297902 -361.36567) (xy 71.27991 -361.292025) (xy 71.269848 -361.216885)
			(xy 71.267829 -361.141101) (xy 70.151751 -361.141101) (xy 70.149732 -361.216885) (xy 70.13967 -361.292025)
			(xy 70.121678 -361.36567) (xy 70.09596 -361.436986) (xy 70.062808 -361.505163) (xy 70.022596 -361.569431)
			(xy 69.975781 -361.62906) (xy 69.922893 -361.683376) (xy 69.864531 -361.731762) (xy 69.801356 -361.77367)
			(xy 69.734085 -361.808626) (xy 69.66348 -361.836233) (xy 69.590339 -361.856179) (xy 69.515494 -361.868238)
			(xy 69.43979 -361.872273) (xy 69.364086 -361.868238) (xy 69.289241 -361.856179) (xy 69.2161 -361.836233)
			(xy 69.145495 -361.808626) (xy 69.078224 -361.77367) (xy 69.015049 -361.731762) (xy 68.956687 -361.683376)
			(xy 68.903799 -361.62906) (xy 68.856984 -361.569431) (xy 68.816772 -361.505163) (xy 68.78362 -361.436986)
			(xy 68.757902 -361.36567) (xy 68.73991 -361.292025) (xy 68.729848 -361.216885) (xy 68.727829 -361.141101)
			(xy 67.611751 -361.141101) (xy 67.609732 -361.216885) (xy 67.59967 -361.292025) (xy 67.581678 -361.36567)
			(xy 67.55596 -361.436986) (xy 67.522808 -361.505163) (xy 67.482596 -361.569431) (xy 67.435781 -361.62906)
			(xy 67.382893 -361.683376) (xy 67.324531 -361.731762) (xy 67.261356 -361.77367) (xy 67.194085 -361.808626)
			(xy 67.12348 -361.836233) (xy 67.050339 -361.856179) (xy 66.975494 -361.868238) (xy 66.89979 -361.872273)
			(xy 66.824086 -361.868238) (xy 66.749241 -361.856179) (xy 66.6761 -361.836233) (xy 66.605495 -361.808626)
			(xy 66.538224 -361.77367) (xy 66.475049 -361.731762) (xy 66.416687 -361.683376) (xy 66.363799 -361.62906)
			(xy 66.316984 -361.569431) (xy 66.276772 -361.505163) (xy 66.24362 -361.436986) (xy 66.217902 -361.36567)
			(xy 66.19991 -361.292025) (xy 66.189848 -361.216885) (xy 66.187829 -361.141101) (xy 65.071751 -361.141101)
			(xy 65.069732 -361.216885) (xy 65.05967 -361.292025) (xy 65.041678 -361.36567) (xy 65.01596 -361.436986)
			(xy 64.982808 -361.505163) (xy 64.942596 -361.569431) (xy 64.895781 -361.62906) (xy 64.842893 -361.683376)
			(xy 64.784531 -361.731762) (xy 64.721356 -361.77367) (xy 64.654085 -361.808626) (xy 64.58348 -361.836233)
			(xy 64.510339 -361.856179) (xy 64.435494 -361.868238) (xy 64.35979 -361.872273) (xy 64.284086 -361.868238)
			(xy 64.209241 -361.856179) (xy 64.1361 -361.836233) (xy 64.065495 -361.808626) (xy 63.998224 -361.77367)
			(xy 63.935049 -361.731762) (xy 63.876687 -361.683376) (xy 63.823799 -361.62906) (xy 63.776984 -361.569431)
			(xy 63.736772 -361.505163) (xy 63.70362 -361.436986) (xy 63.677902 -361.36567) (xy 63.65991 -361.292025)
			(xy 63.649848 -361.216885) (xy 63.647829 -361.141101) (xy 42.474869 -361.141101) (xy 42.525479 -361.17734)
			(xy 42.614981 -361.251279) (xy 42.699169 -361.331217) (xy 42.777642 -361.416772) (xy 42.850025 -361.507538)
			(xy 42.915974 -361.603081) (xy 42.975174 -361.702946) (xy 43.027343 -361.806658) (xy 43.072232 -361.913721)
			(xy 43.109628 -362.023627) (xy 43.139353 -362.135851) (xy 43.161264 -362.249857) (xy 43.175257 -362.365104)
			(xy 43.181266 -362.481042) (xy 43.179263 -362.597118) (xy 43.169255 -362.71278) (xy 43.151292 -362.827475)
			(xy 43.125459 -362.940658) (xy 43.091879 -363.051789) (xy 43.050711 -363.160338) (xy 43.002153 -363.265788)
			(xy 42.946436 -363.367637) (xy 42.883824 -363.4654) (xy 42.814617 -363.55861) (xy 42.739144 -363.646823)
			(xy 42.657765 -363.729619) (xy 42.570868 -363.806603) (xy 42.526017 -363.841121) (xy 63.647829 -363.841121)
			(xy 63.653878 -363.765551) (xy 63.667925 -363.691053) (xy 63.689811 -363.61847) (xy 63.719288 -363.548624)
			(xy 63.756023 -363.482307) (xy 63.799598 -363.420271) (xy 63.84952 -363.363218) (xy 63.905224 -363.311794)
			(xy 63.966079 -363.266583) (xy 64.031394 -363.228096) (xy 64.10043 -363.19677) (xy 64.172405 -363.17296)
			(xy 64.246503 -363.156935) (xy 64.321884 -363.148876) (xy 64.35979 -363.148372) (xy 64.397696 -363.148876)
			(xy 64.473077 -363.156935) (xy 64.547175 -363.17296) (xy 64.61915 -363.19677) (xy 64.688186 -363.228096)
			(xy 64.753501 -363.266583) (xy 64.814356 -363.311794) (xy 64.87006 -363.363218) (xy 64.919982 -363.420271)
			(xy 64.963557 -363.482307) (xy 65.000292 -363.548624) (xy 65.029769 -363.61847) (xy 65.051655 -363.691053)
			(xy 65.065702 -363.765551) (xy 65.071751 -363.841121) (xy 66.187829 -363.841121) (xy 66.193878 -363.765551)
			(xy 66.207925 -363.691053) (xy 66.229811 -363.61847) (xy 66.259288 -363.548624) (xy 66.296023 -363.482307)
			(xy 66.339598 -363.420271) (xy 66.38952 -363.363218) (xy 66.445224 -363.311794) (xy 66.506079 -363.266583)
			(xy 66.571394 -363.228096) (xy 66.64043 -363.19677) (xy 66.712405 -363.17296) (xy 66.786503 -363.156935)
			(xy 66.861884 -363.148876) (xy 66.89979 -363.148372) (xy 66.937696 -363.148876) (xy 67.013077 -363.156935)
			(xy 67.087175 -363.17296) (xy 67.15915 -363.19677) (xy 67.228186 -363.228096) (xy 67.293501 -363.266583)
			(xy 67.354356 -363.311794) (xy 67.41006 -363.363218) (xy 67.459982 -363.420271) (xy 67.503557 -363.482307)
			(xy 67.540292 -363.548624) (xy 67.569769 -363.61847) (xy 67.591655 -363.691053) (xy 67.605702 -363.765551)
			(xy 67.611751 -363.841121) (xy 68.727829 -363.841121) (xy 68.733878 -363.765551) (xy 68.747925 -363.691053)
			(xy 68.769811 -363.61847) (xy 68.799288 -363.548624) (xy 68.836023 -363.482307) (xy 68.879598 -363.420271)
			(xy 68.92952 -363.363218) (xy 68.985224 -363.311794) (xy 69.046079 -363.266583) (xy 69.111394 -363.228096)
			(xy 69.18043 -363.19677) (xy 69.252405 -363.17296) (xy 69.326503 -363.156935) (xy 69.401884 -363.148876)
			(xy 69.43979 -363.148372) (xy 69.477696 -363.148876) (xy 69.553077 -363.156935) (xy 69.627175 -363.17296)
			(xy 69.69915 -363.19677) (xy 69.768186 -363.228096) (xy 69.833501 -363.266583) (xy 69.894356 -363.311794)
			(xy 69.95006 -363.363218) (xy 69.999982 -363.420271) (xy 70.043557 -363.482307) (xy 70.080292 -363.548624)
			(xy 70.109769 -363.61847) (xy 70.131655 -363.691053) (xy 70.145702 -363.765551) (xy 70.151751 -363.841121)
			(xy 71.267829 -363.841121) (xy 71.273878 -363.765551) (xy 71.287925 -363.691053) (xy 71.309811 -363.61847)
			(xy 71.339288 -363.548624) (xy 71.376023 -363.482307) (xy 71.419598 -363.420271) (xy 71.46952 -363.363218)
			(xy 71.525224 -363.311794) (xy 71.586079 -363.266583) (xy 71.651394 -363.228096) (xy 71.72043 -363.19677)
			(xy 71.792405 -363.17296) (xy 71.866503 -363.156935) (xy 71.941884 -363.148876) (xy 71.97979 -363.148372)
			(xy 72.017696 -363.148876) (xy 72.093077 -363.156935) (xy 72.167175 -363.17296) (xy 72.23915 -363.19677)
			(xy 72.308186 -363.228096) (xy 72.373501 -363.266583) (xy 72.434356 -363.311794) (xy 72.49006 -363.363218)
			(xy 72.539982 -363.420271) (xy 72.583557 -363.482307) (xy 72.620292 -363.548624) (xy 72.649769 -363.61847)
			(xy 72.671655 -363.691053) (xy 72.685702 -363.765551) (xy 72.691751 -363.841121) (xy 73.807829 -363.841121)
			(xy 73.813878 -363.765551) (xy 73.827925 -363.691053) (xy 73.849811 -363.61847) (xy 73.879288 -363.548624)
			(xy 73.916023 -363.482307) (xy 73.959598 -363.420271) (xy 74.00952 -363.363218) (xy 74.065224 -363.311794)
			(xy 74.126079 -363.266583) (xy 74.191394 -363.228096) (xy 74.26043 -363.19677) (xy 74.332405 -363.17296)
			(xy 74.406503 -363.156935) (xy 74.481884 -363.148876) (xy 74.51979 -363.148372) (xy 74.557696 -363.148876)
			(xy 74.633077 -363.156935) (xy 74.707175 -363.17296) (xy 74.77915 -363.19677) (xy 74.848186 -363.228096)
			(xy 74.913501 -363.266583) (xy 74.974356 -363.311794) (xy 75.03006 -363.363218) (xy 75.079982 -363.420271)
			(xy 75.123557 -363.482307) (xy 75.160292 -363.548624) (xy 75.189769 -363.61847) (xy 75.211655 -363.691053)
			(xy 75.225702 -363.765551) (xy 75.231751 -363.841121) (xy 76.347829 -363.841121) (xy 76.353878 -363.765551)
			(xy 76.367925 -363.691053) (xy 76.389811 -363.61847) (xy 76.419288 -363.548624) (xy 76.456023 -363.482307)
			(xy 76.499598 -363.420271) (xy 76.54952 -363.363218) (xy 76.605224 -363.311794) (xy 76.666079 -363.266583)
			(xy 76.731394 -363.228096) (xy 76.80043 -363.19677) (xy 76.872405 -363.17296) (xy 76.946503 -363.156935)
			(xy 77.021884 -363.148876) (xy 77.05979 -363.148372) (xy 77.097696 -363.148876) (xy 77.173077 -363.156935)
			(xy 77.247175 -363.17296) (xy 77.31915 -363.19677) (xy 77.388186 -363.228096) (xy 77.453501 -363.266583)
			(xy 77.514356 -363.311794) (xy 77.57006 -363.363218) (xy 77.619982 -363.420271) (xy 77.663557 -363.482307)
			(xy 77.700292 -363.548624) (xy 77.729769 -363.61847) (xy 77.751655 -363.691053) (xy 77.765702 -363.765551)
			(xy 77.771751 -363.841121) (xy 78.887829 -363.841121) (xy 78.893878 -363.765551) (xy 78.907925 -363.691053)
			(xy 78.929811 -363.61847) (xy 78.959288 -363.548624) (xy 78.996023 -363.482307) (xy 79.039598 -363.420271)
			(xy 79.08952 -363.363218) (xy 79.145224 -363.311794) (xy 79.206079 -363.266583) (xy 79.271394 -363.228096)
			(xy 79.34043 -363.19677) (xy 79.412405 -363.17296) (xy 79.486503 -363.156935) (xy 79.561884 -363.148876)
			(xy 79.59979 -363.148372) (xy 79.637696 -363.148876) (xy 79.713077 -363.156935) (xy 79.787175 -363.17296)
			(xy 79.85915 -363.19677) (xy 79.928186 -363.228096) (xy 79.993501 -363.266583) (xy 80.054356 -363.311794)
			(xy 80.11006 -363.363218) (xy 80.159982 -363.420271) (xy 80.203557 -363.482307) (xy 80.240292 -363.548624)
			(xy 80.269769 -363.61847) (xy 80.291655 -363.691053) (xy 80.305702 -363.765551) (xy 80.311751 -363.841121)
			(xy 81.427829 -363.841121) (xy 81.433878 -363.765551) (xy 81.447925 -363.691053) (xy 81.469811 -363.61847)
			(xy 81.499288 -363.548624) (xy 81.536023 -363.482307) (xy 81.579598 -363.420271) (xy 81.62952 -363.363218)
			(xy 81.685224 -363.311794) (xy 81.746079 -363.266583) (xy 81.811394 -363.228096) (xy 81.88043 -363.19677)
			(xy 81.952405 -363.17296) (xy 82.026503 -363.156935) (xy 82.101884 -363.148876) (xy 82.13979 -363.148372)
			(xy 82.177696 -363.148876) (xy 82.253077 -363.156935) (xy 82.327175 -363.17296) (xy 82.39915 -363.19677)
			(xy 82.468186 -363.228096) (xy 82.533501 -363.266583) (xy 82.594356 -363.311794) (xy 82.65006 -363.363218)
			(xy 82.699982 -363.420271) (xy 82.743557 -363.482307) (xy 82.780292 -363.548624) (xy 82.809769 -363.61847)
			(xy 82.831655 -363.691053) (xy 82.845702 -363.765551) (xy 82.851751 -363.841121) (xy 82.849732 -363.916905)
			(xy 82.83967 -363.992045) (xy 82.821678 -364.06569) (xy 82.79596 -364.137006) (xy 82.762808 -364.205183)
			(xy 82.722596 -364.269451) (xy 82.675781 -364.32908) (xy 82.622893 -364.383396) (xy 82.564531 -364.431782)
			(xy 82.501356 -364.47369) (xy 82.434085 -364.508646) (xy 82.36348 -364.536253) (xy 82.290339 -364.556199)
			(xy 82.215494 -364.568258) (xy 82.13979 -364.572293) (xy 82.064086 -364.568258) (xy 81.989241 -364.556199)
			(xy 81.9161 -364.536253) (xy 81.845495 -364.508646) (xy 81.778224 -364.47369) (xy 81.715049 -364.431782)
			(xy 81.656687 -364.383396) (xy 81.603799 -364.32908) (xy 81.556984 -364.269451) (xy 81.516772 -364.205183)
			(xy 81.48362 -364.137006) (xy 81.457902 -364.06569) (xy 81.43991 -363.992045) (xy 81.429848 -363.916905)
			(xy 81.427829 -363.841121) (xy 80.311751 -363.841121) (xy 80.309732 -363.916905) (xy 80.29967 -363.992045)
			(xy 80.281678 -364.06569) (xy 80.25596 -364.137006) (xy 80.222808 -364.205183) (xy 80.182596 -364.269451)
			(xy 80.135781 -364.32908) (xy 80.082893 -364.383396) (xy 80.024531 -364.431782) (xy 79.961356 -364.47369)
			(xy 79.894085 -364.508646) (xy 79.82348 -364.536253) (xy 79.750339 -364.556199) (xy 79.675494 -364.568258)
			(xy 79.59979 -364.572293) (xy 79.524086 -364.568258) (xy 79.449241 -364.556199) (xy 79.3761 -364.536253)
			(xy 79.305495 -364.508646) (xy 79.238224 -364.47369) (xy 79.175049 -364.431782) (xy 79.116687 -364.383396)
			(xy 79.063799 -364.32908) (xy 79.016984 -364.269451) (xy 78.976772 -364.205183) (xy 78.94362 -364.137006)
			(xy 78.917902 -364.06569) (xy 78.89991 -363.992045) (xy 78.889848 -363.916905) (xy 78.887829 -363.841121)
			(xy 77.771751 -363.841121) (xy 77.769732 -363.916905) (xy 77.75967 -363.992045) (xy 77.741678 -364.06569)
			(xy 77.71596 -364.137006) (xy 77.682808 -364.205183) (xy 77.642596 -364.269451) (xy 77.595781 -364.32908)
			(xy 77.542893 -364.383396) (xy 77.484531 -364.431782) (xy 77.421356 -364.47369) (xy 77.354085 -364.508646)
			(xy 77.28348 -364.536253) (xy 77.210339 -364.556199) (xy 77.135494 -364.568258) (xy 77.05979 -364.572293)
			(xy 76.984086 -364.568258) (xy 76.909241 -364.556199) (xy 76.8361 -364.536253) (xy 76.765495 -364.508646)
			(xy 76.698224 -364.47369) (xy 76.635049 -364.431782) (xy 76.576687 -364.383396) (xy 76.523799 -364.32908)
			(xy 76.476984 -364.269451) (xy 76.436772 -364.205183) (xy 76.40362 -364.137006) (xy 76.377902 -364.06569)
			(xy 76.35991 -363.992045) (xy 76.349848 -363.916905) (xy 76.347829 -363.841121) (xy 75.231751 -363.841121)
			(xy 75.229732 -363.916905) (xy 75.21967 -363.992045) (xy 75.201678 -364.06569) (xy 75.17596 -364.137006)
			(xy 75.142808 -364.205183) (xy 75.102596 -364.269451) (xy 75.055781 -364.32908) (xy 75.002893 -364.383396)
			(xy 74.944531 -364.431782) (xy 74.881356 -364.47369) (xy 74.814085 -364.508646) (xy 74.74348 -364.536253)
			(xy 74.670339 -364.556199) (xy 74.595494 -364.568258) (xy 74.51979 -364.572293) (xy 74.444086 -364.568258)
			(xy 74.369241 -364.556199) (xy 74.2961 -364.536253) (xy 74.225495 -364.508646) (xy 74.158224 -364.47369)
			(xy 74.095049 -364.431782) (xy 74.036687 -364.383396) (xy 73.983799 -364.32908) (xy 73.936984 -364.269451)
			(xy 73.896772 -364.205183) (xy 73.86362 -364.137006) (xy 73.837902 -364.06569) (xy 73.81991 -363.992045)
			(xy 73.809848 -363.916905) (xy 73.807829 -363.841121) (xy 72.691751 -363.841121) (xy 72.689732 -363.916905)
			(xy 72.67967 -363.992045) (xy 72.661678 -364.06569) (xy 72.63596 -364.137006) (xy 72.602808 -364.205183)
			(xy 72.562596 -364.269451) (xy 72.515781 -364.32908) (xy 72.462893 -364.383396) (xy 72.404531 -364.431782)
			(xy 72.341356 -364.47369) (xy 72.274085 -364.508646) (xy 72.20348 -364.536253) (xy 72.130339 -364.556199)
			(xy 72.055494 -364.568258) (xy 71.97979 -364.572293) (xy 71.904086 -364.568258) (xy 71.829241 -364.556199)
			(xy 71.7561 -364.536253) (xy 71.685495 -364.508646) (xy 71.618224 -364.47369) (xy 71.555049 -364.431782)
			(xy 71.496687 -364.383396) (xy 71.443799 -364.32908) (xy 71.396984 -364.269451) (xy 71.356772 -364.205183)
			(xy 71.32362 -364.137006) (xy 71.297902 -364.06569) (xy 71.27991 -363.992045) (xy 71.269848 -363.916905)
			(xy 71.267829 -363.841121) (xy 70.151751 -363.841121) (xy 70.149732 -363.916905) (xy 70.13967 -363.992045)
			(xy 70.121678 -364.06569) (xy 70.09596 -364.137006) (xy 70.062808 -364.205183) (xy 70.022596 -364.269451)
			(xy 69.975781 -364.32908) (xy 69.922893 -364.383396) (xy 69.864531 -364.431782) (xy 69.801356 -364.47369)
			(xy 69.734085 -364.508646) (xy 69.66348 -364.536253) (xy 69.590339 -364.556199) (xy 69.515494 -364.568258)
			(xy 69.43979 -364.572293) (xy 69.364086 -364.568258) (xy 69.289241 -364.556199) (xy 69.2161 -364.536253)
			(xy 69.145495 -364.508646) (xy 69.078224 -364.47369) (xy 69.015049 -364.431782) (xy 68.956687 -364.383396)
			(xy 68.903799 -364.32908) (xy 68.856984 -364.269451) (xy 68.816772 -364.205183) (xy 68.78362 -364.137006)
			(xy 68.757902 -364.06569) (xy 68.73991 -363.992045) (xy 68.729848 -363.916905) (xy 68.727829 -363.841121)
			(xy 67.611751 -363.841121) (xy 67.609732 -363.916905) (xy 67.59967 -363.992045) (xy 67.581678 -364.06569)
			(xy 67.55596 -364.137006) (xy 67.522808 -364.205183) (xy 67.482596 -364.269451) (xy 67.435781 -364.32908)
			(xy 67.382893 -364.383396) (xy 67.324531 -364.431782) (xy 67.261356 -364.47369) (xy 67.194085 -364.508646)
			(xy 67.12348 -364.536253) (xy 67.050339 -364.556199) (xy 66.975494 -364.568258) (xy 66.89979 -364.572293)
			(xy 66.824086 -364.568258) (xy 66.749241 -364.556199) (xy 66.6761 -364.536253) (xy 66.605495 -364.508646)
			(xy 66.538224 -364.47369) (xy 66.475049 -364.431782) (xy 66.416687 -364.383396) (xy 66.363799 -364.32908)
			(xy 66.316984 -364.269451) (xy 66.276772 -364.205183) (xy 66.24362 -364.137006) (xy 66.217902 -364.06569)
			(xy 66.19991 -363.992045) (xy 66.189848 -363.916905) (xy 66.187829 -363.841121) (xy 65.071751 -363.841121)
			(xy 65.069732 -363.916905) (xy 65.05967 -363.992045) (xy 65.041678 -364.06569) (xy 65.01596 -364.137006)
			(xy 64.982808 -364.205183) (xy 64.942596 -364.269451) (xy 64.895781 -364.32908) (xy 64.842893 -364.383396)
			(xy 64.784531 -364.431782) (xy 64.721356 -364.47369) (xy 64.654085 -364.508646) (xy 64.58348 -364.536253)
			(xy 64.510339 -364.556199) (xy 64.435494 -364.568258) (xy 64.35979 -364.572293) (xy 64.284086 -364.568258)
			(xy 64.209241 -364.556199) (xy 64.1361 -364.536253) (xy 64.065495 -364.508646) (xy 63.998224 -364.47369)
			(xy 63.935049 -364.431782) (xy 63.876687 -364.383396) (xy 63.823799 -364.32908) (xy 63.776984 -364.269451)
			(xy 63.736772 -364.205183) (xy 63.70362 -364.137006) (xy 63.677902 -364.06569) (xy 63.65991 -363.992045)
			(xy 63.649848 -363.916905) (xy 63.647829 -363.841121) (xy 42.526017 -363.841121) (xy 42.478867 -363.877408)
			(xy 42.3822 -363.941698) (xy 42.281328 -363.999165) (xy 42.176731 -364.049536) (xy 42.068908 -364.092571)
			(xy 41.958374 -364.128065) (xy 41.845654 -364.155848) (xy 41.731286 -364.175788) (xy 41.615814 -364.18779)
			(xy 41.49979 -364.191797) (xy 41.383766 -364.18779) (xy 41.268294 -364.175788) (xy 41.153926 -364.155848)
			(xy 41.041206 -364.128065) (xy 40.930672 -364.092571) (xy 40.822849 -364.049536) (xy 40.718252 -363.999165)
			(xy 40.61738 -363.941698) (xy 40.520713 -363.877408) (xy 40.428712 -363.806603) (xy 40.341815 -363.729619)
			(xy 40.260436 -363.646823) (xy 40.184963 -363.55861) (xy 40.115756 -363.4654) (xy 40.053144 -363.367637)
			(xy 39.997427 -363.265788) (xy 39.948869 -363.160338) (xy 39.907701 -363.051789) (xy 39.874121 -362.940658)
			(xy 39.848288 -362.827475) (xy 39.830325 -362.71278) (xy 39.820317 -362.597118) (xy 39.818314 -362.481042)
			(xy 36.050645 -362.481042) (xy 36.071366 -362.493872) (xy 36.140713 -362.546241) (xy 36.204933 -362.604785)
			(xy 36.263477 -362.669005) (xy 36.315846 -362.738352) (xy 36.361593 -362.812236) (xy 36.400327 -362.890025)
			(xy 36.431719 -362.971057) (xy 36.4555 -363.054639) (xy 36.471468 -363.140059) (xy 36.479486 -363.226588)
			(xy 36.479486 -363.313488) (xy 36.471468 -363.400017) (xy 36.4555 -363.485437) (xy 36.431719 -363.569019)
			(xy 36.400327 -363.650051) (xy 36.361593 -363.72784) (xy 36.315846 -363.801724) (xy 36.263477 -363.871071)
			(xy 36.204933 -363.935291) (xy 36.140713 -363.993835) (xy 36.071366 -364.046204) (xy 35.997482 -364.091951)
			(xy 35.919693 -364.130685) (xy 35.838661 -364.162077) (xy 35.755079 -364.185858) (xy 35.669659 -364.201826)
			(xy 35.58313 -364.209844) (xy 35.49623 -364.209844) (xy 35.409701 -364.201826) (xy 35.324281 -364.185858)
			(xy 35.240699 -364.162077) (xy 35.159667 -364.130685) (xy 35.081878 -364.091951) (xy 35.007994 -364.046204)
			(xy 34.938647 -363.993835) (xy 34.874427 -363.935291) (xy 34.815883 -363.871071) (xy 34.763514 -363.801724)
			(xy 34.717767 -363.72784) (xy 34.679033 -363.650051) (xy 34.647641 -363.569019) (xy 34.62386 -363.485437)
			(xy 34.607892 -363.400017) (xy 34.599874 -363.313488) (xy 31.399486 -363.313488) (xy 31.391468 -363.400017)
			(xy 31.3755 -363.485437) (xy 31.351719 -363.569019) (xy 31.320327 -363.650051) (xy 31.281593 -363.72784)
			(xy 31.235846 -363.801724) (xy 31.183477 -363.871071) (xy 31.124933 -363.935291) (xy 31.060713 -363.993835)
			(xy 30.991366 -364.046204) (xy 30.917482 -364.091951) (xy 30.839693 -364.130685) (xy 30.758661 -364.162077)
			(xy 30.675079 -364.185858) (xy 30.589659 -364.201826) (xy 30.50313 -364.209844) (xy 30.41623 -364.209844)
			(xy 30.329701 -364.201826) (xy 30.244281 -364.185858) (xy 30.160699 -364.162077) (xy 30.079667 -364.130685)
			(xy 30.001878 -364.091951) (xy 29.927994 -364.046204) (xy 29.858647 -363.993835) (xy 29.794427 -363.935291)
			(xy 29.735883 -363.871071) (xy 29.683514 -363.801724) (xy 29.637767 -363.72784) (xy 29.599033 -363.650051)
			(xy 29.567641 -363.569019) (xy 29.54386 -363.485437) (xy 29.527892 -363.400017) (xy 29.519874 -363.313488)
			(xy 22.271736 -363.313488) (xy 22.271736 -364.232462) (xy 26.786585 -364.232462) (xy 26.792685 -364.177025)
			(xy 26.806791 -364.123068) (xy 26.828603 -364.071739) (xy 26.857657 -364.024133) (xy 26.893332 -363.981265)
			(xy 26.934869 -363.944048) (xy 26.981382 -363.913275) (xy 27.031879 -363.889603) (xy 27.085286 -363.873535)
			(xy 27.140462 -363.865415) (xy 27.168348 -363.864906) (xy 27.196234 -363.865415) (xy 27.25141 -363.873535)
			(xy 27.304817 -363.889603) (xy 27.355314 -363.913275) (xy 27.401827 -363.944048) (xy 27.443364 -363.981265)
			(xy 27.479039 -364.024133) (xy 27.508093 -364.071739) (xy 27.529905 -364.123068) (xy 27.544011 -364.177025)
			(xy 27.550111 -364.232462) (xy 27.548074 -364.288196) (xy 27.537944 -364.343039) (xy 27.519937 -364.395823)
			(xy 27.494436 -364.445423) (xy 27.461985 -364.490781) (xy 27.423276 -364.53093) (xy 27.379133 -364.565016)
			(xy 27.330498 -364.592312) (xy 27.278407 -364.612235) (xy 27.22397 -364.624361) (xy 27.168348 -364.628432)
			(xy 27.112726 -364.624361) (xy 27.058289 -364.612235) (xy 27.006198 -364.592312) (xy 26.957563 -364.565016)
			(xy 26.91342 -364.53093) (xy 26.874711 -364.490781) (xy 26.84226 -364.445423) (xy 26.816759 -364.395823)
			(xy 26.798752 -364.343039) (xy 26.788622 -364.288196) (xy 26.786585 -364.232462) (xy 22.271736 -364.232462)
			(xy 22.271736 -365.853488) (xy 29.519874 -365.853488) (xy 29.519874 -365.766588) (xy 29.527892 -365.680059)
			(xy 29.54386 -365.594639) (xy 29.567641 -365.511057) (xy 29.599033 -365.430025) (xy 29.637767 -365.352236)
			(xy 29.683514 -365.278352) (xy 29.735883 -365.209005) (xy 29.794427 -365.144785) (xy 29.858647 -365.086241)
			(xy 29.927994 -365.033872) (xy 30.001878 -364.988125) (xy 30.079667 -364.949391) (xy 30.160699 -364.917999)
			(xy 30.244281 -364.894218) (xy 30.329701 -364.87825) (xy 30.41623 -364.870232) (xy 30.45968 -364.86973)
			(xy 30.50313 -364.870232) (xy 30.589659 -364.87825) (xy 30.675079 -364.894218) (xy 30.758661 -364.917999)
			(xy 30.839693 -364.949391) (xy 30.917482 -364.988125) (xy 30.991366 -365.033872) (xy 31.060713 -365.086241)
			(xy 31.124933 -365.144785) (xy 31.183477 -365.209005) (xy 31.235846 -365.278352) (xy 31.281593 -365.352236)
			(xy 31.320327 -365.430025) (xy 31.351719 -365.511057) (xy 31.3755 -365.594639) (xy 31.391468 -365.680059)
			(xy 31.399486 -365.766588) (xy 31.399486 -365.853488) (xy 34.599874 -365.853488) (xy 34.599874 -365.766588)
			(xy 34.607892 -365.680059) (xy 34.62386 -365.594639) (xy 34.647641 -365.511057) (xy 34.679033 -365.430025)
			(xy 34.717767 -365.352236) (xy 34.763514 -365.278352) (xy 34.815883 -365.209005) (xy 34.874427 -365.144785)
			(xy 34.938647 -365.086241) (xy 35.007994 -365.033872) (xy 35.081878 -364.988125) (xy 35.159667 -364.949391)
			(xy 35.240699 -364.917999) (xy 35.324281 -364.894218) (xy 35.409701 -364.87825) (xy 35.49623 -364.870232)
			(xy 35.53968 -364.86973) (xy 35.58313 -364.870232) (xy 35.669659 -364.87825) (xy 35.755079 -364.894218)
			(xy 35.838661 -364.917999) (xy 35.919693 -364.949391) (xy 35.997482 -364.988125) (xy 36.071366 -365.033872)
			(xy 36.140713 -365.086241) (xy 36.204933 -365.144785) (xy 36.263477 -365.209005) (xy 36.315846 -365.278352)
			(xy 36.361593 -365.352236) (xy 36.400327 -365.430025) (xy 36.431719 -365.511057) (xy 36.4555 -365.594639)
			(xy 36.471468 -365.680059) (xy 36.479486 -365.766588) (xy 36.479486 -365.853488) (xy 36.471468 -365.940017)
			(xy 36.4555 -366.025437) (xy 36.431719 -366.109019) (xy 36.400327 -366.190051) (xy 36.361593 -366.26784)
			(xy 36.315846 -366.341724) (xy 36.263477 -366.411071) (xy 36.204933 -366.475291) (xy 36.140713 -366.533835)
			(xy 36.071366 -366.586204) (xy 35.997482 -366.631951) (xy 35.919693 -366.670685) (xy 35.838661 -366.702077)
			(xy 35.755079 -366.725858) (xy 35.669659 -366.741826) (xy 35.58313 -366.749844) (xy 35.49623 -366.749844)
			(xy 35.409701 -366.741826) (xy 35.324281 -366.725858) (xy 35.240699 -366.702077) (xy 35.159667 -366.670685)
			(xy 35.081878 -366.631951) (xy 35.007994 -366.586204) (xy 34.938647 -366.533835) (xy 34.874427 -366.475291)
			(xy 34.815883 -366.411071) (xy 34.763514 -366.341724) (xy 34.717767 -366.26784) (xy 34.679033 -366.190051)
			(xy 34.647641 -366.109019) (xy 34.62386 -366.025437) (xy 34.607892 -365.940017) (xy 34.599874 -365.853488)
			(xy 31.399486 -365.853488) (xy 31.391468 -365.940017) (xy 31.3755 -366.025437) (xy 31.351719 -366.109019)
			(xy 31.320327 -366.190051) (xy 31.281593 -366.26784) (xy 31.235846 -366.341724) (xy 31.183477 -366.411071)
			(xy 31.124933 -366.475291) (xy 31.060713 -366.533835) (xy 30.991366 -366.586204) (xy 30.917482 -366.631951)
			(xy 30.839693 -366.670685) (xy 30.758661 -366.702077) (xy 30.675079 -366.725858) (xy 30.589659 -366.741826)
			(xy 30.50313 -366.749844) (xy 30.41623 -366.749844) (xy 30.329701 -366.741826) (xy 30.244281 -366.725858)
			(xy 30.160699 -366.702077) (xy 30.079667 -366.670685) (xy 30.001878 -366.631951) (xy 29.927994 -366.586204)
			(xy 29.858647 -366.533835) (xy 29.794427 -366.475291) (xy 29.735883 -366.411071) (xy 29.683514 -366.341724)
			(xy 29.637767 -366.26784) (xy 29.599033 -366.190051) (xy 29.567641 -366.109019) (xy 29.54386 -366.025437)
			(xy 29.527892 -365.940017) (xy 29.519874 -365.853488) (xy 22.271736 -365.853488) (xy 22.271736 -366.914194)
			(xy 26.736039 -366.914194) (xy 26.742139 -366.858757) (xy 26.756245 -366.8048) (xy 26.778057 -366.753471)
			(xy 26.807111 -366.705865) (xy 26.842786 -366.662997) (xy 26.884323 -366.62578) (xy 26.930836 -366.595007)
			(xy 26.981333 -366.571335) (xy 27.03474 -366.555267) (xy 27.089916 -366.547147) (xy 27.117802 -366.546638)
			(xy 27.145688 -366.547147) (xy 27.200864 -366.555267) (xy 27.254271 -366.571335) (xy 27.304768 -366.595007)
			(xy 27.351281 -366.62578) (xy 27.392818 -366.662997) (xy 27.428493 -366.705865) (xy 27.457547 -366.753471)
			(xy 27.479359 -366.8048) (xy 27.493465 -366.858757) (xy 27.499565 -366.914194) (xy 27.497528 -366.969928)
			(xy 27.487398 -367.024771) (xy 27.469391 -367.077555) (xy 27.44389 -367.127155) (xy 27.411439 -367.172513)
			(xy 27.37273 -367.212662) (xy 27.328587 -367.246748) (xy 27.279952 -367.274044) (xy 27.227861 -367.293967)
			(xy 27.173424 -367.306093) (xy 27.117802 -367.310164) (xy 27.06218 -367.306093) (xy 27.007743 -367.293967)
			(xy 26.955652 -367.274044) (xy 26.907017 -367.246748) (xy 26.862874 -367.212662) (xy 26.824165 -367.172513)
			(xy 26.791714 -367.127155) (xy 26.766213 -367.077555) (xy 26.748206 -367.024771) (xy 26.738076 -366.969928)
			(xy 26.736039 -366.914194) (xy 22.271736 -366.914194) (xy 22.271736 -368.393488) (xy 29.519874 -368.393488)
			(xy 29.519874 -368.306588) (xy 29.527892 -368.220059) (xy 29.54386 -368.134639) (xy 29.567641 -368.051057)
			(xy 29.599033 -367.970025) (xy 29.637767 -367.892236) (xy 29.683514 -367.818352) (xy 29.735883 -367.749005)
			(xy 29.794427 -367.684785) (xy 29.858647 -367.626241) (xy 29.927994 -367.573872) (xy 30.001878 -367.528125)
			(xy 30.079667 -367.489391) (xy 30.160699 -367.457999) (xy 30.244281 -367.434218) (xy 30.329701 -367.41825)
			(xy 30.41623 -367.410232) (xy 30.45968 -367.40973) (xy 30.50313 -367.410232) (xy 30.589659 -367.41825)
			(xy 30.675079 -367.434218) (xy 30.758661 -367.457999) (xy 30.839693 -367.489391) (xy 30.917482 -367.528125)
			(xy 30.991366 -367.573872) (xy 31.060713 -367.626241) (xy 31.124933 -367.684785) (xy 31.183477 -367.749005)
			(xy 31.235846 -367.818352) (xy 31.281593 -367.892236) (xy 31.320327 -367.970025) (xy 31.351719 -368.051057)
			(xy 31.3755 -368.134639) (xy 31.391468 -368.220059) (xy 31.399486 -368.306588) (xy 31.399486 -368.393488)
			(xy 34.599874 -368.393488) (xy 34.599874 -368.306588) (xy 34.607892 -368.220059) (xy 34.62386 -368.134639)
			(xy 34.647641 -368.051057) (xy 34.679033 -367.970025) (xy 34.717767 -367.892236) (xy 34.763514 -367.818352)
			(xy 34.815883 -367.749005) (xy 34.874427 -367.684785) (xy 34.938647 -367.626241) (xy 35.007994 -367.573872)
			(xy 35.081878 -367.528125) (xy 35.159667 -367.489391) (xy 35.240699 -367.457999) (xy 35.324281 -367.434218)
			(xy 35.409701 -367.41825) (xy 35.49623 -367.410232) (xy 35.53968 -367.40973) (xy 35.58313 -367.410232)
			(xy 35.669659 -367.41825) (xy 35.755079 -367.434218) (xy 35.838661 -367.457999) (xy 35.919693 -367.489391)
			(xy 35.997482 -367.528125) (xy 36.071366 -367.573872) (xy 36.140713 -367.626241) (xy 36.204933 -367.684785)
			(xy 36.263477 -367.749005) (xy 36.315846 -367.818352) (xy 36.361593 -367.892236) (xy 36.400327 -367.970025)
			(xy 36.431719 -368.051057) (xy 36.4555 -368.134639) (xy 36.471468 -368.220059) (xy 36.479486 -368.306588)
			(xy 36.479486 -368.393488) (xy 36.471468 -368.480017) (xy 36.4555 -368.565437) (xy 36.455136 -368.566718)
			(xy 40.053005 -368.566718) (xy 40.059105 -368.511281) (xy 40.073211 -368.457324) (xy 40.095023 -368.405995)
			(xy 40.124077 -368.358389) (xy 40.159752 -368.315521) (xy 40.201289 -368.278304) (xy 40.247802 -368.247531)
			(xy 40.298299 -368.223859) (xy 40.351706 -368.207791) (xy 40.406882 -368.199671) (xy 40.434768 -368.199162)
			(xy 40.462654 -368.199671) (xy 40.51783 -368.207791) (xy 40.571237 -368.223859) (xy 40.621734 -368.247531)
			(xy 40.668247 -368.278304) (xy 40.709784 -368.315521) (xy 40.745459 -368.358389) (xy 40.774513 -368.405995)
			(xy 40.796325 -368.457324) (xy 40.810431 -368.511281) (xy 40.816531 -368.566718) (xy 40.814494 -368.622452)
			(xy 40.804364 -368.677295) (xy 40.786357 -368.730079) (xy 40.760856 -368.779679) (xy 40.728405 -368.825037)
			(xy 40.689696 -368.865186) (xy 40.645553 -368.899272) (xy 40.596918 -368.926568) (xy 40.544827 -368.946491)
			(xy 40.49039 -368.958617) (xy 40.434768 -368.962688) (xy 40.379146 -368.958617) (xy 40.324709 -368.946491)
			(xy 40.272618 -368.926568) (xy 40.223983 -368.899272) (xy 40.17984 -368.865186) (xy 40.141131 -368.825037)
			(xy 40.10868 -368.779679) (xy 40.083179 -368.730079) (xy 40.065172 -368.677295) (xy 40.055042 -368.622452)
			(xy 40.053005 -368.566718) (xy 36.455136 -368.566718) (xy 36.431719 -368.649019) (xy 36.400327 -368.730051)
			(xy 36.361593 -368.80784) (xy 36.315846 -368.881724) (xy 36.263477 -368.951071) (xy 36.204933 -369.015291)
			(xy 36.140713 -369.073835) (xy 36.071366 -369.126204) (xy 35.997482 -369.171951) (xy 35.919693 -369.210685)
			(xy 35.838661 -369.242077) (xy 35.755079 -369.265858) (xy 35.669659 -369.281826) (xy 35.58313 -369.289844)
			(xy 35.49623 -369.289844) (xy 35.409701 -369.281826) (xy 35.324281 -369.265858) (xy 35.240699 -369.242077)
			(xy 35.159667 -369.210685) (xy 35.081878 -369.171951) (xy 35.007994 -369.126204) (xy 34.938647 -369.073835)
			(xy 34.874427 -369.015291) (xy 34.815883 -368.951071) (xy 34.763514 -368.881724) (xy 34.717767 -368.80784)
			(xy 34.679033 -368.730051) (xy 34.647641 -368.649019) (xy 34.62386 -368.565437) (xy 34.607892 -368.480017)
			(xy 34.599874 -368.393488) (xy 31.399486 -368.393488) (xy 31.391468 -368.480017) (xy 31.3755 -368.565437)
			(xy 31.351719 -368.649019) (xy 31.320327 -368.730051) (xy 31.281593 -368.80784) (xy 31.235846 -368.881724)
			(xy 31.183477 -368.951071) (xy 31.124933 -369.015291) (xy 31.060713 -369.073835) (xy 30.991366 -369.126204)
			(xy 30.917482 -369.171951) (xy 30.839693 -369.210685) (xy 30.758661 -369.242077) (xy 30.675079 -369.265858)
			(xy 30.589659 -369.281826) (xy 30.50313 -369.289844) (xy 30.41623 -369.289844) (xy 30.329701 -369.281826)
			(xy 30.244281 -369.265858) (xy 30.160699 -369.242077) (xy 30.079667 -369.210685) (xy 30.001878 -369.171951)
			(xy 29.927994 -369.126204) (xy 29.858647 -369.073835) (xy 29.794427 -369.015291) (xy 29.735883 -368.951071)
			(xy 29.683514 -368.881724) (xy 29.637767 -368.80784) (xy 29.599033 -368.730051) (xy 29.567641 -368.649019)
			(xy 29.54386 -368.565437) (xy 29.527892 -368.480017) (xy 29.519874 -368.393488) (xy 22.271736 -368.393488)
			(xy 22.271736 -369.129582) (xy 23.808181 -369.129582) (xy 23.814281 -369.074145) (xy 23.828387 -369.020188)
			(xy 23.850199 -368.968859) (xy 23.879253 -368.921253) (xy 23.914928 -368.878385) (xy 23.956465 -368.841168)
			(xy 24.002978 -368.810395) (xy 24.053475 -368.786723) (xy 24.106882 -368.770655) (xy 24.162058 -368.762535)
			(xy 24.189944 -368.762026) (xy 24.21783 -368.762535) (xy 24.273006 -368.770655) (xy 24.326413 -368.786723)
			(xy 24.37691 -368.810395) (xy 24.423423 -368.841168) (xy 24.46496 -368.878385) (xy 24.500635 -368.921253)
			(xy 24.523917 -368.959402) (xy 26.797761 -368.959402) (xy 26.803861 -368.903965) (xy 26.817967 -368.850008)
			(xy 26.839779 -368.798679) (xy 26.868833 -368.751073) (xy 26.904508 -368.708205) (xy 26.946045 -368.670988)
			(xy 26.992558 -368.640215) (xy 27.043055 -368.616543) (xy 27.096462 -368.600475) (xy 27.151638 -368.592355)
			(xy 27.179524 -368.591846) (xy 27.20741 -368.592355) (xy 27.262586 -368.600475) (xy 27.315993 -368.616543)
			(xy 27.36649 -368.640215) (xy 27.413003 -368.670988) (xy 27.45454 -368.708205) (xy 27.490215 -368.751073)
			(xy 27.519269 -368.798679) (xy 27.541081 -368.850008) (xy 27.555187 -368.903965) (xy 27.561287 -368.959402)
			(xy 27.55925 -369.015136) (xy 27.54912 -369.069979) (xy 27.531113 -369.122763) (xy 27.505612 -369.172363)
			(xy 27.473161 -369.217721) (xy 27.434452 -369.25787) (xy 27.390309 -369.291956) (xy 27.341674 -369.319252)
			(xy 27.289583 -369.339175) (xy 27.235146 -369.351301) (xy 27.179524 -369.355372) (xy 27.123902 -369.351301)
			(xy 27.069465 -369.339175) (xy 27.017374 -369.319252) (xy 26.968739 -369.291956) (xy 26.924596 -369.25787)
			(xy 26.885887 -369.217721) (xy 26.853436 -369.172363) (xy 26.827935 -369.122763) (xy 26.809928 -369.069979)
			(xy 26.799798 -369.015136) (xy 26.797761 -368.959402) (xy 24.523917 -368.959402) (xy 24.529689 -368.968859)
			(xy 24.551501 -369.020188) (xy 24.565607 -369.074145) (xy 24.571707 -369.129582) (xy 24.56967 -369.185316)
			(xy 24.55954 -369.240159) (xy 24.541533 -369.292943) (xy 24.516032 -369.342543) (xy 24.483581 -369.387901)
			(xy 24.444872 -369.42805) (xy 24.400729 -369.462136) (xy 24.352094 -369.489432) (xy 24.300003 -369.509355)
			(xy 24.245566 -369.521481) (xy 24.189944 -369.525552) (xy 24.134322 -369.521481) (xy 24.079885 -369.509355)
			(xy 24.027794 -369.489432) (xy 23.979159 -369.462136) (xy 23.935016 -369.42805) (xy 23.896307 -369.387901)
			(xy 23.863856 -369.342543) (xy 23.838355 -369.292943) (xy 23.820348 -369.240159) (xy 23.810218 -369.185316)
			(xy 23.808181 -369.129582) (xy 22.271736 -369.129582) (xy 22.271736 -370.338096) (xy 23.656312 -371.722672)
			(xy 27.094909 -371.722672) (xy 27.096185 -371.659455) (xy 27.105702 -371.596946) (xy 27.123296 -371.536214)
			(xy 27.148667 -371.478297) (xy 27.181381 -371.424188) (xy 27.220878 -371.374811) (xy 27.266481 -371.331013)
			(xy 27.317411 -371.293541) (xy 27.372797 -371.263038) (xy 27.43169 -371.240025) (xy 27.493083 -371.224895)
			(xy 27.555925 -371.217909) (xy 27.619142 -371.219185) (xy 27.681652 -371.228701) (xy 27.712162 -371.237002)
			(xy 29.034232 -371.61978) (xy 29.364178 -371.61978) (xy 29.387067 -371.619363) (xy 29.432109 -371.611187)
			(xy 29.474958 -371.595076) (xy 29.514229 -371.571552) (xy 29.548652 -371.541376) (xy 29.577115 -371.505522)
			(xy 29.598697 -371.465151) (xy 29.6127 -371.421568) (xy 29.618671 -371.376181) (xy 29.616418 -371.330459)
			(xy 29.606013 -371.28588) (xy 29.59735 -371.264688) (xy 29.580545 -371.224763) (xy 29.55348 -371.142469)
			(xy 29.534101 -371.058034) (xy 29.522571 -370.972175) (xy 29.518989 -370.885619) (xy 29.523384 -370.799101)
			(xy 29.53572 -370.713353) (xy 29.555892 -370.629104) (xy 29.583728 -370.547068) (xy 29.618993 -370.467941)
			(xy 29.661388 -370.392394) (xy 29.710553 -370.321066) (xy 29.766071 -370.254564) (xy 29.827472 -370.193452)
			(xy 29.894234 -370.138247) (xy 29.965791 -370.089417) (xy 30.041537 -370.047378) (xy 30.120829 -370.012485)
			(xy 30.202995 -369.985034) (xy 30.287338 -369.965258) (xy 30.373142 -369.953325) (xy 30.45968 -369.949336)
			(xy 30.546218 -369.953325) (xy 30.632022 -369.965258) (xy 30.716365 -369.985034) (xy 30.798531 -370.012485)
			(xy 30.877823 -370.047378) (xy 30.953569 -370.089417) (xy 31.025126 -370.138247) (xy 31.091888 -370.193452)
			(xy 31.153289 -370.254564) (xy 31.208807 -370.321066) (xy 31.257972 -370.392394) (xy 31.300367 -370.467941)
			(xy 31.335632 -370.547068) (xy 31.363468 -370.629104) (xy 31.38364 -370.713353) (xy 31.395976 -370.799101)
			(xy 31.400371 -370.885619) (xy 31.39839 -370.933488) (xy 34.599874 -370.933488) (xy 34.599874 -370.846588)
			(xy 34.607892 -370.760059) (xy 34.62386 -370.674639) (xy 34.647641 -370.591057) (xy 34.679033 -370.510025)
			(xy 34.717767 -370.432236) (xy 34.763514 -370.358352) (xy 34.815883 -370.289005) (xy 34.874427 -370.224785)
			(xy 34.938647 -370.166241) (xy 35.007994 -370.113872) (xy 35.081878 -370.068125) (xy 35.159667 -370.029391)
			(xy 35.240699 -369.997999) (xy 35.324281 -369.974218) (xy 35.409701 -369.95825) (xy 35.49623 -369.950232)
			(xy 35.53968 -369.94973) (xy 35.58313 -369.950232) (xy 35.669659 -369.95825) (xy 35.755079 -369.974218)
			(xy 35.838661 -369.997999) (xy 35.919693 -370.029391) (xy 35.997482 -370.068125) (xy 36.071366 -370.113872)
			(xy 36.140713 -370.166241) (xy 36.204933 -370.224785) (xy 36.263477 -370.289005) (xy 36.315846 -370.358352)
			(xy 36.361593 -370.432236) (xy 36.400327 -370.510025) (xy 36.431719 -370.591057) (xy 36.446425 -370.642743)
			(xy 73.760322 -370.642743) (xy 73.760322 -370.571421) (xy 73.768308 -370.500547) (xy 73.784178 -370.431012)
			(xy 73.807735 -370.363692) (xy 73.83868 -370.299433) (xy 73.876626 -370.239042) (xy 73.921095 -370.18328)
			(xy 73.971528 -370.132847) (xy 74.02729 -370.088378) (xy 74.087681 -370.050432) (xy 74.15194 -370.019487)
			(xy 74.21926 -369.99593) (xy 74.288795 -369.98006) (xy 74.359669 -369.972074) (xy 74.39533 -369.971574)
			(xy 74.430991 -369.972074) (xy 74.501865 -369.98006) (xy 74.5714 -369.99593) (xy 74.63872 -370.019487)
			(xy 74.702979 -370.050432) (xy 74.76337 -370.088378) (xy 74.819132 -370.132847) (xy 74.869565 -370.18328)
			(xy 74.914034 -370.239042) (xy 74.95198 -370.299433) (xy 74.982925 -370.363692) (xy 75.006482 -370.431012)
			(xy 75.022352 -370.500547) (xy 75.030338 -370.571421) (xy 75.030338 -370.642743) (xy 75.835756 -370.642743)
			(xy 75.835756 -370.571421) (xy 75.843742 -370.500547) (xy 75.859612 -370.431012) (xy 75.883169 -370.363692)
			(xy 75.914114 -370.299433) (xy 75.95206 -370.239042) (xy 75.996529 -370.18328) (xy 76.046962 -370.132847)
			(xy 76.102724 -370.088378) (xy 76.163115 -370.050432) (xy 76.227374 -370.019487) (xy 76.294694 -369.99593)
			(xy 76.364229 -369.98006) (xy 76.435103 -369.972074) (xy 76.470764 -369.971574) (xy 76.506425 -369.972074)
			(xy 76.577299 -369.98006) (xy 76.646834 -369.99593) (xy 76.714154 -370.019487) (xy 76.778413 -370.050432)
			(xy 76.838804 -370.088378) (xy 76.894566 -370.132847) (xy 76.944999 -370.18328) (xy 76.989468 -370.239042)
			(xy 77.027414 -370.299433) (xy 77.058359 -370.363692) (xy 77.081916 -370.431012) (xy 77.097786 -370.500547)
			(xy 77.105772 -370.571421) (xy 77.105772 -370.642743) (xy 77.105686 -370.643505) (xy 78.060034 -370.643505)
			(xy 78.060034 -370.572183) (xy 78.06802 -370.501309) (xy 78.08389 -370.431774) (xy 78.107447 -370.364454)
			(xy 78.138392 -370.300195) (xy 78.176338 -370.239804) (xy 78.220807 -370.184042) (xy 78.27124 -370.133609)
			(xy 78.327002 -370.08914) (xy 78.387393 -370.051194) (xy 78.451652 -370.020249) (xy 78.518972 -369.996692)
			(xy 78.588507 -369.980822) (xy 78.659381 -369.972836) (xy 78.695042 -369.972336) (xy 78.730703 -369.972836)
			(xy 78.801577 -369.980822) (xy 78.871112 -369.996692) (xy 78.938432 -370.020249) (xy 79.002691 -370.051194)
			(xy 79.063082 -370.08914) (xy 79.118844 -370.133609) (xy 79.169277 -370.184042) (xy 79.213746 -370.239804)
			(xy 79.251692 -370.300195) (xy 79.282637 -370.364454) (xy 79.306194 -370.431774) (xy 79.322064 -370.501309)
			(xy 79.33005 -370.572183) (xy 79.33005 -370.643505) (xy 79.322064 -370.714379) (xy 79.306194 -370.783914)
			(xy 79.282637 -370.851234) (xy 79.251692 -370.915493) (xy 79.213746 -370.975884) (xy 79.169277 -371.031646)
			(xy 79.118844 -371.082079) (xy 79.063082 -371.126548) (xy 79.002691 -371.164494) (xy 78.938432 -371.195439)
			(xy 78.871112 -371.218996) (xy 78.801577 -371.234866) (xy 78.730703 -371.242852) (xy 78.659381 -371.242852)
			(xy 78.588507 -371.234866) (xy 78.518972 -371.218996) (xy 78.451652 -371.195439) (xy 78.387393 -371.164494)
			(xy 78.327002 -371.126548) (xy 78.27124 -371.082079) (xy 78.220807 -371.031646) (xy 78.176338 -370.975884)
			(xy 78.138392 -370.915493) (xy 78.107447 -370.851234) (xy 78.08389 -370.783914) (xy 78.06802 -370.714379)
			(xy 78.060034 -370.643505) (xy 77.105686 -370.643505) (xy 77.097786 -370.713617) (xy 77.081916 -370.783152)
			(xy 77.058359 -370.850472) (xy 77.027414 -370.914731) (xy 76.989468 -370.975122) (xy 76.944999 -371.030884)
			(xy 76.894566 -371.081317) (xy 76.838804 -371.125786) (xy 76.778413 -371.163732) (xy 76.714154 -371.194677)
			(xy 76.646834 -371.218234) (xy 76.577299 -371.234104) (xy 76.506425 -371.24209) (xy 76.435103 -371.24209)
			(xy 76.364229 -371.234104) (xy 76.294694 -371.218234) (xy 76.227374 -371.194677) (xy 76.163115 -371.163732)
			(xy 76.102724 -371.125786) (xy 76.046962 -371.081317) (xy 75.996529 -371.030884) (xy 75.95206 -370.975122)
			(xy 75.914114 -370.914731) (xy 75.883169 -370.850472) (xy 75.859612 -370.783152) (xy 75.843742 -370.713617)
			(xy 75.835756 -370.642743) (xy 75.030338 -370.642743) (xy 75.022352 -370.713617) (xy 75.006482 -370.783152)
			(xy 74.982925 -370.850472) (xy 74.95198 -370.914731) (xy 74.914034 -370.975122) (xy 74.869565 -371.030884)
			(xy 74.819132 -371.081317) (xy 74.76337 -371.125786) (xy 74.702979 -371.163732) (xy 74.63872 -371.194677)
			(xy 74.5714 -371.218234) (xy 74.501865 -371.234104) (xy 74.430991 -371.24209) (xy 74.359669 -371.24209)
			(xy 74.288795 -371.234104) (xy 74.21926 -371.218234) (xy 74.15194 -371.194677) (xy 74.087681 -371.163732)
			(xy 74.02729 -371.125786) (xy 73.971528 -371.081317) (xy 73.921095 -371.030884) (xy 73.876626 -370.975122)
			(xy 73.83868 -370.914731) (xy 73.807735 -370.850472) (xy 73.784178 -370.783152) (xy 73.768308 -370.713617)
			(xy 73.760322 -370.642743) (xy 36.446425 -370.642743) (xy 36.4555 -370.674639) (xy 36.471468 -370.760059)
			(xy 36.479486 -370.846588) (xy 36.479486 -370.933488) (xy 36.471468 -371.020017) (xy 36.4555 -371.105437)
			(xy 36.431719 -371.189019) (xy 36.400327 -371.270051) (xy 36.361593 -371.34784) (xy 36.315846 -371.421724)
			(xy 36.263477 -371.491071) (xy 36.204933 -371.555291) (xy 36.140713 -371.613835) (xy 36.071366 -371.666204)
			(xy 35.997482 -371.711951) (xy 35.919693 -371.750685) (xy 35.838661 -371.782077) (xy 35.755079 -371.805858)
			(xy 35.669659 -371.821826) (xy 35.58313 -371.829844) (xy 35.49623 -371.829844) (xy 35.409701 -371.821826)
			(xy 35.324281 -371.805858) (xy 35.240699 -371.782077) (xy 35.159667 -371.750685) (xy 35.081878 -371.711951)
			(xy 35.007994 -371.666204) (xy 34.938647 -371.613835) (xy 34.874427 -371.555291) (xy 34.815883 -371.491071)
			(xy 34.763514 -371.421724) (xy 34.717767 -371.34784) (xy 34.679033 -371.270051) (xy 34.647641 -371.189019)
			(xy 34.62386 -371.105437) (xy 34.607892 -371.020017) (xy 34.599874 -370.933488) (xy 31.39839 -370.933488)
			(xy 31.396789 -370.972175) (xy 31.385259 -371.058034) (xy 31.36588 -371.142469) (xy 31.338815 -371.224763)
			(xy 31.32201 -371.264688) (xy 31.313382 -371.285895) (xy 31.302955 -371.33047) (xy 31.300684 -371.376191)
			(xy 31.306643 -371.421579) (xy 31.320639 -371.465165) (xy 31.342219 -371.505537) (xy 31.370684 -371.541388)
			(xy 31.405113 -371.571559) (xy 31.444391 -371.595071) (xy 31.487247 -371.611165) (xy 31.532293 -371.619318)
			(xy 31.555182 -371.61978) (xy 32.190436 -371.61978) (xy 32.969963 -372.399407) (xy 73.760322 -372.399407)
			(xy 73.760322 -372.328085) (xy 73.768308 -372.257211) (xy 73.784178 -372.187676) (xy 73.807735 -372.120356)
			(xy 73.83868 -372.056097) (xy 73.876626 -371.995706) (xy 73.921095 -371.939944) (xy 73.971528 -371.889511)
			(xy 74.02729 -371.845042) (xy 74.087681 -371.807096) (xy 74.15194 -371.776151) (xy 74.21926 -371.752594)
			(xy 74.288795 -371.736724) (xy 74.359669 -371.728738) (xy 74.39533 -371.728238) (xy 74.430991 -371.728738)
			(xy 74.501865 -371.736724) (xy 74.5714 -371.752594) (xy 74.63872 -371.776151) (xy 74.702979 -371.807096)
			(xy 74.76337 -371.845042) (xy 74.819132 -371.889511) (xy 74.869565 -371.939944) (xy 74.914034 -371.995706)
			(xy 74.95198 -372.056097) (xy 74.982925 -372.120356) (xy 75.006482 -372.187676) (xy 75.022352 -372.257211)
			(xy 75.030338 -372.328085) (xy 75.030338 -372.399407) (xy 75.835756 -372.399407) (xy 75.835756 -372.328085)
			(xy 75.843742 -372.257211) (xy 75.859612 -372.187676) (xy 75.883169 -372.120356) (xy 75.914114 -372.056097)
			(xy 75.95206 -371.995706) (xy 75.996529 -371.939944) (xy 76.046962 -371.889511) (xy 76.102724 -371.845042)
			(xy 76.163115 -371.807096) (xy 76.227374 -371.776151) (xy 76.294694 -371.752594) (xy 76.364229 -371.736724)
			(xy 76.435103 -371.728738) (xy 76.470764 -371.728238) (xy 76.506425 -371.728738) (xy 76.577299 -371.736724)
			(xy 76.646834 -371.752594) (xy 76.714154 -371.776151) (xy 76.778413 -371.807096) (xy 76.838804 -371.845042)
			(xy 76.894566 -371.889511) (xy 76.944999 -371.939944) (xy 76.989468 -371.995706) (xy 77.027414 -372.056097)
			(xy 77.058359 -372.120356) (xy 77.081916 -372.187676) (xy 77.097786 -372.257211) (xy 77.105772 -372.328085)
			(xy 77.105772 -372.399407) (xy 77.105686 -372.400169) (xy 78.060034 -372.400169) (xy 78.060034 -372.328847)
			(xy 78.06802 -372.257973) (xy 78.08389 -372.188438) (xy 78.107447 -372.121118) (xy 78.138392 -372.056859)
			(xy 78.176338 -371.996468) (xy 78.220807 -371.940706) (xy 78.27124 -371.890273) (xy 78.327002 -371.845804)
			(xy 78.387393 -371.807858) (xy 78.451652 -371.776913) (xy 78.518972 -371.753356) (xy 78.588507 -371.737486)
			(xy 78.659381 -371.7295) (xy 78.695042 -371.729) (xy 78.730703 -371.7295) (xy 78.801577 -371.737486)
			(xy 78.871112 -371.753356) (xy 78.938432 -371.776913) (xy 79.002691 -371.807858) (xy 79.063082 -371.845804)
			(xy 79.118844 -371.890273) (xy 79.169277 -371.940706) (xy 79.213746 -371.996468) (xy 79.251692 -372.056859)
			(xy 79.282637 -372.121118) (xy 79.306194 -372.188438) (xy 79.322064 -372.257973) (xy 79.33005 -372.328847)
			(xy 79.33005 -372.400169) (xy 79.322064 -372.471043) (xy 79.306194 -372.540578) (xy 79.282637 -372.607898)
			(xy 79.251692 -372.672157) (xy 79.213746 -372.732548) (xy 79.169277 -372.78831) (xy 79.118844 -372.838743)
			(xy 79.063082 -372.883212) (xy 79.002691 -372.921158) (xy 78.938432 -372.952103) (xy 78.871112 -372.97566)
			(xy 78.801577 -372.99153) (xy 78.730703 -372.999516) (xy 78.659381 -372.999516) (xy 78.588507 -372.99153)
			(xy 78.518972 -372.97566) (xy 78.451652 -372.952103) (xy 78.387393 -372.921158) (xy 78.327002 -372.883212)
			(xy 78.27124 -372.838743) (xy 78.220807 -372.78831) (xy 78.176338 -372.732548) (xy 78.138392 -372.672157)
			(xy 78.107447 -372.607898) (xy 78.08389 -372.540578) (xy 78.06802 -372.471043) (xy 78.060034 -372.400169)
			(xy 77.105686 -372.400169) (xy 77.097786 -372.470281) (xy 77.081916 -372.539816) (xy 77.058359 -372.607136)
			(xy 77.027414 -372.671395) (xy 76.989468 -372.731786) (xy 76.944999 -372.787548) (xy 76.894566 -372.837981)
			(xy 76.838804 -372.88245) (xy 76.778413 -372.920396) (xy 76.714154 -372.951341) (xy 76.646834 -372.974898)
			(xy 76.577299 -372.990768) (xy 76.506425 -372.998754) (xy 76.435103 -372.998754) (xy 76.364229 -372.990768)
			(xy 76.294694 -372.974898) (xy 76.227374 -372.951341) (xy 76.163115 -372.920396) (xy 76.102724 -372.88245)
			(xy 76.046962 -372.837981) (xy 75.996529 -372.787548) (xy 75.95206 -372.731786) (xy 75.914114 -372.671395)
			(xy 75.883169 -372.607136) (xy 75.859612 -372.539816) (xy 75.843742 -372.470281) (xy 75.835756 -372.399407)
			(xy 75.030338 -372.399407) (xy 75.022352 -372.470281) (xy 75.006482 -372.539816) (xy 74.982925 -372.607136)
			(xy 74.95198 -372.671395) (xy 74.914034 -372.731786) (xy 74.869565 -372.787548) (xy 74.819132 -372.837981)
			(xy 74.76337 -372.88245) (xy 74.702979 -372.920396) (xy 74.63872 -372.951341) (xy 74.5714 -372.974898)
			(xy 74.501865 -372.990768) (xy 74.430991 -372.998754) (xy 74.359669 -372.998754) (xy 74.288795 -372.990768)
			(xy 74.21926 -372.974898) (xy 74.15194 -372.951341) (xy 74.087681 -372.920396) (xy 74.02729 -372.88245)
			(xy 73.971528 -372.837981) (xy 73.921095 -372.787548) (xy 73.876626 -372.731786) (xy 73.83868 -372.671395)
			(xy 73.807735 -372.607136) (xy 73.784178 -372.539816) (xy 73.768308 -372.470281) (xy 73.760322 -372.399407)
			(xy 32.969963 -372.399407) (xy 34.165794 -373.595392) (xy 34.182346 -373.611251) (xy 34.220043 -373.637325)
			(xy 34.261805 -373.656216) (xy 34.306278 -373.66731) (xy 34.352019 -373.670248) (xy 34.397546 -373.664936)
			(xy 34.441382 -373.651544) (xy 34.482106 -373.630508) (xy 34.518396 -373.602509) (xy 34.549077 -373.568455)
			(xy 34.573152 -373.529452) (xy 34.589842 -373.486763) (xy 34.598606 -373.441772) (xy 34.599372 -373.418862)
			(xy 34.600387 -373.37527) (xy 34.609496 -373.288545) (xy 34.626596 -373.203035) (xy 34.65154 -373.119477)
			(xy 34.684114 -373.038587) (xy 34.724037 -372.96106) (xy 34.770967 -372.887563) (xy 34.8245 -372.818727)
			(xy 34.884177 -372.755143) (xy 34.949485 -372.697358) (xy 35.019862 -372.645867) (xy 35.094705 -372.601115)
			(xy 35.17337 -372.563484) (xy 35.255181 -372.533298) (xy 35.339435 -372.510817) (xy 35.42541 -372.496233)
			(xy 35.512365 -372.489673) (xy 35.599554 -372.491192) (xy 35.686228 -372.500777) (xy 35.771642 -372.518346)
			(xy 35.855062 -372.543748) (xy 35.935772 -372.576765) (xy 36.013079 -372.617113) (xy 36.086317 -372.664446)
			(xy 36.154859 -372.718356) (xy 36.218114 -372.778381) (xy 36.27554 -372.844005) (xy 36.326643 -372.914664)
			(xy 36.370985 -372.989751) (xy 36.408183 -373.068621) (xy 36.437919 -373.150597) (xy 36.459938 -373.234973)
			(xy 36.474049 -373.321026) (xy 36.480132 -373.408016) (xy 36.478135 -373.495196) (xy 36.468074 -373.581816)
			(xy 36.450037 -373.667132) (xy 36.424177 -373.750412) (xy 36.390718 -373.830939) (xy 36.370768 -373.869712)
			(xy 36.360914 -373.889158) (xy 36.347402 -373.930604) (xy 36.341158 -373.973747) (xy 36.342368 -374.017324)
			(xy 36.350994 -374.060055) (xy 36.366784 -374.100688) (xy 36.389275 -374.138031) (xy 36.417808 -374.170989)
			(xy 36.451545 -374.198596) (xy 36.489498 -374.220042) (xy 36.530553 -374.234698) (xy 36.573507 -374.242135)
			(xy 36.595304 -374.242584) (xy 38.019736 -374.242584) (xy 38.03637 -374.242014) (xy 38.068487 -374.233331)
			(xy 38.097269 -374.216644) (xy 38.109398 -374.205246) (xy 38.419024 -373.89562) (xy 42.417746 -373.89562)
			(xy 42.999829 -374.477703) (xy 50.798212 -374.477703) (xy 50.798212 -374.396593) (xy 50.806162 -374.315874)
			(xy 50.821985 -374.236323) (xy 50.84553 -374.158707) (xy 50.876569 -374.083771) (xy 50.914804 -374.012239)
			(xy 50.959866 -373.944799) (xy 51.011321 -373.8821) (xy 51.068674 -373.824747) (xy 51.131373 -373.773292)
			(xy 51.198813 -373.72823) (xy 51.270345 -373.689995) (xy 51.345281 -373.658956) (xy 51.422897 -373.635411)
			(xy 51.502448 -373.619588) (xy 51.583167 -373.611638) (xy 51.623722 -373.61114) (xy 51.664277 -373.611638)
			(xy 51.744996 -373.619588) (xy 51.824547 -373.635411) (xy 51.902163 -373.658956) (xy 51.977099 -373.689995)
			(xy 52.048631 -373.72823) (xy 52.116071 -373.773292) (xy 52.17877 -373.824747) (xy 52.236123 -373.8821)
			(xy 52.287578 -373.944799) (xy 52.33264 -374.012239) (xy 52.370875 -374.083771) (xy 52.401914 -374.158707)
			(xy 52.404119 -374.165977) (xy 73.760322 -374.165977) (xy 73.760322 -374.094655) (xy 73.768308 -374.023781)
			(xy 73.784178 -373.954246) (xy 73.807735 -373.886926) (xy 73.83868 -373.822667) (xy 73.876626 -373.762276)
			(xy 73.921095 -373.706514) (xy 73.971528 -373.656081) (xy 74.02729 -373.611612) (xy 74.087681 -373.573666)
			(xy 74.15194 -373.542721) (xy 74.21926 -373.519164) (xy 74.288795 -373.503294) (xy 74.359669 -373.495308)
			(xy 74.39533 -373.494808) (xy 74.430991 -373.495308) (xy 74.501865 -373.503294) (xy 74.5714 -373.519164)
			(xy 74.63872 -373.542721) (xy 74.702979 -373.573666) (xy 74.76337 -373.611612) (xy 74.819132 -373.656081)
			(xy 74.869565 -373.706514) (xy 74.914034 -373.762276) (xy 74.95198 -373.822667) (xy 74.982925 -373.886926)
			(xy 75.006482 -373.954246) (xy 75.022352 -374.023781) (xy 75.030338 -374.094655) (xy 75.030338 -374.165977)
			(xy 75.835756 -374.165977) (xy 75.835756 -374.094655) (xy 75.843742 -374.023781) (xy 75.859612 -373.954246)
			(xy 75.883169 -373.886926) (xy 75.914114 -373.822667) (xy 75.95206 -373.762276) (xy 75.996529 -373.706514)
			(xy 76.046962 -373.656081) (xy 76.102724 -373.611612) (xy 76.163115 -373.573666) (xy 76.227374 -373.542721)
			(xy 76.294694 -373.519164) (xy 76.364229 -373.503294) (xy 76.435103 -373.495308) (xy 76.470764 -373.494808)
			(xy 76.506425 -373.495308) (xy 76.577299 -373.503294) (xy 76.646834 -373.519164) (xy 76.714154 -373.542721)
			(xy 76.778413 -373.573666) (xy 76.838804 -373.611612) (xy 76.894566 -373.656081) (xy 76.944999 -373.706514)
			(xy 76.989468 -373.762276) (xy 77.027414 -373.822667) (xy 77.058359 -373.886926) (xy 77.081916 -373.954246)
			(xy 77.097786 -374.023781) (xy 77.105772 -374.094655) (xy 77.105772 -374.165977) (xy 77.105686 -374.166739)
			(xy 78.060034 -374.166739) (xy 78.060034 -374.095417) (xy 78.06802 -374.024543) (xy 78.08389 -373.955008)
			(xy 78.107447 -373.887688) (xy 78.138392 -373.823429) (xy 78.176338 -373.763038) (xy 78.220807 -373.707276)
			(xy 78.27124 -373.656843) (xy 78.327002 -373.612374) (xy 78.387393 -373.574428) (xy 78.451652 -373.543483)
			(xy 78.518972 -373.519926) (xy 78.588507 -373.504056) (xy 78.659381 -373.49607) (xy 78.695042 -373.49557)
			(xy 78.730703 -373.49607) (xy 78.801577 -373.504056) (xy 78.871112 -373.519926) (xy 78.938432 -373.543483)
			(xy 79.002691 -373.574428) (xy 79.063082 -373.612374) (xy 79.118844 -373.656843) (xy 79.169277 -373.707276)
			(xy 79.213746 -373.763038) (xy 79.251692 -373.823429) (xy 79.282637 -373.887688) (xy 79.306194 -373.955008)
			(xy 79.322064 -374.024543) (xy 79.33005 -374.095417) (xy 79.33005 -374.166739) (xy 79.322064 -374.237613)
			(xy 79.306194 -374.307148) (xy 79.282637 -374.374468) (xy 79.251692 -374.438727) (xy 79.213746 -374.499118)
			(xy 79.169277 -374.55488) (xy 79.118844 -374.605313) (xy 79.063082 -374.649782) (xy 79.002691 -374.687728)
			(xy 78.938432 -374.718673) (xy 78.871112 -374.74223) (xy 78.801577 -374.7581) (xy 78.730703 -374.766086)
			(xy 78.659381 -374.766086) (xy 78.588507 -374.7581) (xy 78.518972 -374.74223) (xy 78.451652 -374.718673)
			(xy 78.387393 -374.687728) (xy 78.327002 -374.649782) (xy 78.27124 -374.605313) (xy 78.220807 -374.55488)
			(xy 78.176338 -374.499118) (xy 78.138392 -374.438727) (xy 78.107447 -374.374468) (xy 78.08389 -374.307148)
			(xy 78.06802 -374.237613) (xy 78.060034 -374.166739) (xy 77.105686 -374.166739) (xy 77.097786 -374.236851)
			(xy 77.081916 -374.306386) (xy 77.058359 -374.373706) (xy 77.027414 -374.437965) (xy 76.989468 -374.498356)
			(xy 76.944999 -374.554118) (xy 76.894566 -374.604551) (xy 76.838804 -374.64902) (xy 76.778413 -374.686966)
			(xy 76.714154 -374.717911) (xy 76.646834 -374.741468) (xy 76.577299 -374.757338) (xy 76.506425 -374.765324)
			(xy 76.435103 -374.765324) (xy 76.364229 -374.757338) (xy 76.294694 -374.741468) (xy 76.227374 -374.717911)
			(xy 76.163115 -374.686966) (xy 76.102724 -374.64902) (xy 76.046962 -374.604551) (xy 75.996529 -374.554118)
			(xy 75.95206 -374.498356) (xy 75.914114 -374.437965) (xy 75.883169 -374.373706) (xy 75.859612 -374.306386)
			(xy 75.843742 -374.236851) (xy 75.835756 -374.165977) (xy 75.030338 -374.165977) (xy 75.022352 -374.236851)
			(xy 75.006482 -374.306386) (xy 74.982925 -374.373706) (xy 74.95198 -374.437965) (xy 74.914034 -374.498356)
			(xy 74.869565 -374.554118) (xy 74.819132 -374.604551) (xy 74.76337 -374.64902) (xy 74.702979 -374.686966)
			(xy 74.63872 -374.717911) (xy 74.5714 -374.741468) (xy 74.501865 -374.757338) (xy 74.430991 -374.765324)
			(xy 74.359669 -374.765324) (xy 74.288795 -374.757338) (xy 74.21926 -374.741468) (xy 74.15194 -374.717911)
			(xy 74.087681 -374.686966) (xy 74.02729 -374.64902) (xy 73.971528 -374.604551) (xy 73.921095 -374.554118)
			(xy 73.876626 -374.498356) (xy 73.83868 -374.437965) (xy 73.807735 -374.373706) (xy 73.784178 -374.306386)
			(xy 73.768308 -374.236851) (xy 73.760322 -374.165977) (xy 52.404119 -374.165977) (xy 52.425459 -374.236323)
			(xy 52.441282 -374.315874) (xy 52.449232 -374.396593) (xy 52.449232 -374.477703) (xy 52.441282 -374.558422)
			(xy 52.425459 -374.637973) (xy 52.401914 -374.715589) (xy 52.370875 -374.790525) (xy 52.33264 -374.862057)
			(xy 52.287578 -374.929497) (xy 52.236123 -374.992196) (xy 52.17877 -375.049549) (xy 52.116071 -375.101004)
			(xy 52.048631 -375.146066) (xy 51.977099 -375.184301) (xy 51.902163 -375.21534) (xy 51.824547 -375.238885)
			(xy 51.744996 -375.254708) (xy 51.664277 -375.262658) (xy 51.583167 -375.262658) (xy 51.502448 -375.254708)
			(xy 51.422897 -375.238885) (xy 51.345281 -375.21534) (xy 51.270345 -375.184301) (xy 51.198813 -375.146066)
			(xy 51.131373 -375.101004) (xy 51.068674 -375.049549) (xy 51.011321 -374.992196) (xy 50.959866 -374.929497)
			(xy 50.914804 -374.862057) (xy 50.876569 -374.790525) (xy 50.84553 -374.715589) (xy 50.821985 -374.637973)
			(xy 50.806162 -374.558422) (xy 50.798212 -374.477703) (xy 42.999829 -374.477703) (xy 44.502933 -375.980807)
			(xy 73.714602 -375.980807) (xy 73.714602 -375.909485) (xy 73.722588 -375.838611) (xy 73.738458 -375.769076)
			(xy 73.762015 -375.701756) (xy 73.79296 -375.637497) (xy 73.830906 -375.577106) (xy 73.875375 -375.521344)
			(xy 73.925808 -375.470911) (xy 73.98157 -375.426442) (xy 74.041961 -375.388496) (xy 74.10622 -375.357551)
			(xy 74.17354 -375.333994) (xy 74.243075 -375.318124) (xy 74.313949 -375.310138) (xy 74.34961 -375.309638)
			(xy 74.385271 -375.310138) (xy 74.456145 -375.318124) (xy 74.52568 -375.333994) (xy 74.593 -375.357551)
			(xy 74.657259 -375.388496) (xy 74.71765 -375.426442) (xy 74.773412 -375.470911) (xy 74.823845 -375.521344)
			(xy 74.868314 -375.577106) (xy 74.90626 -375.637497) (xy 74.937205 -375.701756) (xy 74.960762 -375.769076)
			(xy 74.976632 -375.838611) (xy 74.984618 -375.909485) (xy 74.984618 -375.980807) (xy 75.790036 -375.980807)
			(xy 75.790036 -375.909485) (xy 75.798022 -375.838611) (xy 75.813892 -375.769076) (xy 75.837449 -375.701756)
			(xy 75.868394 -375.637497) (xy 75.90634 -375.577106) (xy 75.950809 -375.521344) (xy 76.001242 -375.470911)
			(xy 76.057004 -375.426442) (xy 76.117395 -375.388496) (xy 76.181654 -375.357551) (xy 76.248974 -375.333994)
			(xy 76.318509 -375.318124) (xy 76.389383 -375.310138) (xy 76.425044 -375.309638) (xy 76.460705 -375.310138)
			(xy 76.531579 -375.318124) (xy 76.601114 -375.333994) (xy 76.668434 -375.357551) (xy 76.732693 -375.388496)
			(xy 76.793084 -375.426442) (xy 76.848846 -375.470911) (xy 76.899279 -375.521344) (xy 76.943748 -375.577106)
			(xy 76.981694 -375.637497) (xy 77.012639 -375.701756) (xy 77.036196 -375.769076) (xy 77.052066 -375.838611)
			(xy 77.060052 -375.909485) (xy 77.060052 -375.980807) (xy 77.059966 -375.981569) (xy 77.968848 -375.981569)
			(xy 77.968848 -375.910247) (xy 77.976834 -375.839373) (xy 77.992704 -375.769838) (xy 78.016261 -375.702518)
			(xy 78.047206 -375.638259) (xy 78.085152 -375.577868) (xy 78.129621 -375.522106) (xy 78.180054 -375.471673)
			(xy 78.235816 -375.427204) (xy 78.296207 -375.389258) (xy 78.360466 -375.358313) (xy 78.427786 -375.334756)
			(xy 78.497321 -375.318886) (xy 78.568195 -375.3109) (xy 78.603856 -375.3104) (xy 78.639517 -375.3109)
			(xy 78.710391 -375.318886) (xy 78.779926 -375.334756) (xy 78.847246 -375.358313) (xy 78.911505 -375.389258)
			(xy 78.971896 -375.427204) (xy 79.027658 -375.471673) (xy 79.078091 -375.522106) (xy 79.12256 -375.577868)
			(xy 79.160506 -375.638259) (xy 79.169914 -375.657796) (xy 86.877655 -375.657796) (xy 86.879665 -375.467113)
			(xy 86.889712 -375.276684) (xy 86.907778 -375.086848) (xy 86.933831 -374.897942) (xy 86.967824 -374.710303)
			(xy 87.009697 -374.524263) (xy 87.059376 -374.340154) (xy 87.116772 -374.158303) (xy 87.181783 -373.979033)
			(xy 87.254294 -373.802663) (xy 87.334175 -373.629507) (xy 87.421285 -373.459872) (xy 87.515469 -373.29406)
			(xy 87.61656 -373.132366) (xy 87.724376 -372.975078) (xy 87.838728 -372.822475) (xy 87.959411 -372.674827)
			(xy 88.086212 -372.532399) (xy 88.218903 -372.395443) (xy 88.357251 -372.264202) (xy 88.501008 -372.13891)
			(xy 88.649919 -372.01979) (xy 88.80372 -371.907054) (xy 88.962136 -371.800901) (xy 89.124887 -371.701521)
			(xy 89.291682 -371.609091) (xy 89.462226 -371.523774) (xy 89.636214 -371.445722) (xy 89.813339 -371.375075)
			(xy 89.993284 -371.311957) (xy 90.17573 -371.256481) (xy 90.360353 -371.208746) (xy 90.546823 -371.168836)
			(xy 90.734811 -371.136823) (xy 90.923981 -371.112763) (xy 91.113997 -371.0967) (xy 91.304521 -371.088661)
			(xy 91.399868 -371.088158) (xy 91.495215 -371.088661) (xy 91.685739 -371.0967) (xy 91.875755 -371.112763)
			(xy 92.064925 -371.136823) (xy 92.252913 -371.168836) (xy 92.439383 -371.208746) (xy 92.624006 -371.256481)
			(xy 92.806452 -371.311957) (xy 92.986397 -371.375075) (xy 93.163522 -371.445722) (xy 93.33751 -371.523774)
			(xy 93.508054 -371.609091) (xy 93.674849 -371.701521) (xy 93.8376 -371.800901) (xy 93.996016 -371.907054)
			(xy 94.149817 -372.01979) (xy 94.298728 -372.13891) (xy 94.442485 -372.264202) (xy 94.580833 -372.395443)
			(xy 94.713524 -372.532399) (xy 94.840325 -372.674827) (xy 94.961008 -372.822475) (xy 95.07536 -372.975078)
			(xy 95.183176 -373.132366) (xy 95.284267 -373.29406) (xy 95.378451 -373.459872) (xy 95.465561 -373.629507)
			(xy 95.545442 -373.802663) (xy 95.617953 -373.979033) (xy 95.682964 -374.158303) (xy 95.74036 -374.340154)
			(xy 95.790039 -374.524263) (xy 95.831912 -374.710303) (xy 95.865905 -374.897942) (xy 95.891958 -375.086848)
			(xy 95.910024 -375.276684) (xy 95.920071 -375.467113) (xy 95.922081 -375.657796) (xy 95.916051 -375.848395)
			(xy 95.901992 -376.038569) (xy 95.879927 -376.227982) (xy 95.849898 -376.416297) (xy 95.811956 -376.603178)
			(xy 95.76617 -376.788294) (xy 95.712621 -376.971314) (xy 95.651403 -377.151915) (xy 95.582627 -377.329774)
			(xy 95.506414 -377.504576) (xy 95.4229 -377.67601) (xy 95.332233 -377.84377) (xy 95.234574 -378.007559)
			(xy 95.130097 -378.167086) (xy 95.018988 -378.322067) (xy 94.901445 -378.472225) (xy 94.777675 -378.617295)
			(xy 94.6479 -378.757019) (xy 94.512351 -378.891147) (xy 94.371267 -379.019441) (xy 94.2249 -379.141675)
			(xy 94.073511 -379.257629) (xy 93.917368 -379.367098) (xy 93.756749 -379.469887) (xy 93.591939 -379.565813)
			(xy 93.423232 -379.654707) (xy 93.250927 -379.736409) (xy 93.075332 -379.810775) (xy 92.896757 -379.877673)
			(xy 92.715521 -379.936983) (xy 92.531946 -379.9886) (xy 92.346358 -380.032432) (xy 92.159088 -380.068401)
			(xy 91.970467 -380.096444) (xy 91.780832 -380.11651) (xy 91.590519 -380.128564) (xy 91.399868 -380.132585)
			(xy 91.209217 -380.128564) (xy 91.018904 -380.11651) (xy 90.829269 -380.096444) (xy 90.640648 -380.068401)
			(xy 90.453378 -380.032432) (xy 90.26779 -379.9886) (xy 90.084215 -379.936983) (xy 89.902979 -379.877673)
			(xy 89.724404 -379.810775) (xy 89.548809 -379.736409) (xy 89.376504 -379.654707) (xy 89.207797 -379.565813)
			(xy 89.042987 -379.469887) (xy 88.882368 -379.367098) (xy 88.726225 -379.257629) (xy 88.574836 -379.141675)
			(xy 88.428469 -379.019441) (xy 88.287385 -378.891147) (xy 88.151836 -378.757019) (xy 88.022061 -378.617295)
			(xy 87.898291 -378.472225) (xy 87.780748 -378.322067) (xy 87.669639 -378.167086) (xy 87.565162 -378.007559)
			(xy 87.467503 -377.84377) (xy 87.376836 -377.67601) (xy 87.293322 -377.504576) (xy 87.217109 -377.329774)
			(xy 87.148333 -377.151915) (xy 87.087115 -376.971314) (xy 87.033566 -376.788294) (xy 86.98778 -376.603178)
			(xy 86.949838 -376.416297) (xy 86.919809 -376.227982) (xy 86.897744 -376.038569) (xy 86.883685 -375.848395)
			(xy 86.877655 -375.657796) (xy 79.169914 -375.657796) (xy 79.191451 -375.702518) (xy 79.215008 -375.769838)
			(xy 79.230878 -375.839373) (xy 79.238864 -375.910247) (xy 79.238864 -375.981569) (xy 79.230878 -376.052443)
			(xy 79.215008 -376.121978) (xy 79.191451 -376.189298) (xy 79.160506 -376.253557) (xy 79.12256 -376.313948)
			(xy 79.078091 -376.36971) (xy 79.027658 -376.420143) (xy 78.971896 -376.464612) (xy 78.911505 -376.502558)
			(xy 78.847246 -376.533503) (xy 78.779926 -376.55706) (xy 78.710391 -376.57293) (xy 78.639517 -376.580916)
			(xy 78.568195 -376.580916) (xy 78.497321 -376.57293) (xy 78.427786 -376.55706) (xy 78.360466 -376.533503)
			(xy 78.296207 -376.502558) (xy 78.235816 -376.464612) (xy 78.180054 -376.420143) (xy 78.129621 -376.36971)
			(xy 78.085152 -376.313948) (xy 78.047206 -376.253557) (xy 78.016261 -376.189298) (xy 77.992704 -376.121978)
			(xy 77.976834 -376.052443) (xy 77.968848 -375.981569) (xy 77.059966 -375.981569) (xy 77.052066 -376.051681)
			(xy 77.036196 -376.121216) (xy 77.012639 -376.188536) (xy 76.981694 -376.252795) (xy 76.943748 -376.313186)
			(xy 76.899279 -376.368948) (xy 76.848846 -376.419381) (xy 76.793084 -376.46385) (xy 76.732693 -376.501796)
			(xy 76.668434 -376.532741) (xy 76.601114 -376.556298) (xy 76.531579 -376.572168) (xy 76.460705 -376.580154)
			(xy 76.389383 -376.580154) (xy 76.318509 -376.572168) (xy 76.248974 -376.556298) (xy 76.181654 -376.532741)
			(xy 76.117395 -376.501796) (xy 76.057004 -376.46385) (xy 76.001242 -376.419381) (xy 75.950809 -376.368948)
			(xy 75.90634 -376.313186) (xy 75.868394 -376.252795) (xy 75.837449 -376.188536) (xy 75.813892 -376.121216)
			(xy 75.798022 -376.051681) (xy 75.790036 -375.980807) (xy 74.984618 -375.980807) (xy 74.976632 -376.051681)
			(xy 74.960762 -376.121216) (xy 74.937205 -376.188536) (xy 74.90626 -376.252795) (xy 74.868314 -376.313186)
			(xy 74.823845 -376.368948) (xy 74.773412 -376.419381) (xy 74.71765 -376.46385) (xy 74.657259 -376.501796)
			(xy 74.593 -376.532741) (xy 74.52568 -376.556298) (xy 74.456145 -376.572168) (xy 74.385271 -376.580154)
			(xy 74.313949 -376.580154) (xy 74.243075 -376.572168) (xy 74.17354 -376.556298) (xy 74.10622 -376.532741)
			(xy 74.041961 -376.501796) (xy 73.98157 -376.46385) (xy 73.925808 -376.419381) (xy 73.875375 -376.368948)
			(xy 73.830906 -376.313186) (xy 73.79296 -376.252795) (xy 73.762015 -376.188536) (xy 73.738458 -376.121216)
			(xy 73.722588 -376.051681) (xy 73.714602 -375.980807) (xy 44.502933 -375.980807) (xy 46.259597 -377.737471)
			(xy 73.714602 -377.737471) (xy 73.714602 -377.666149) (xy 73.722588 -377.595275) (xy 73.738458 -377.52574)
			(xy 73.762015 -377.45842) (xy 73.79296 -377.394161) (xy 73.830906 -377.33377) (xy 73.875375 -377.278008)
			(xy 73.925808 -377.227575) (xy 73.98157 -377.183106) (xy 74.041961 -377.14516) (xy 74.10622 -377.114215)
			(xy 74.17354 -377.090658) (xy 74.243075 -377.074788) (xy 74.313949 -377.066802) (xy 74.34961 -377.066302)
			(xy 74.385271 -377.066802) (xy 74.456145 -377.074788) (xy 74.52568 -377.090658) (xy 74.593 -377.114215)
			(xy 74.657259 -377.14516) (xy 74.71765 -377.183106) (xy 74.773412 -377.227575) (xy 74.823845 -377.278008)
			(xy 74.868314 -377.33377) (xy 74.90626 -377.394161) (xy 74.937205 -377.45842) (xy 74.960762 -377.52574)
			(xy 74.976632 -377.595275) (xy 74.984618 -377.666149) (xy 74.984618 -377.737471) (xy 75.790036 -377.737471)
			(xy 75.790036 -377.666149) (xy 75.798022 -377.595275) (xy 75.813892 -377.52574) (xy 75.837449 -377.45842)
			(xy 75.868394 -377.394161) (xy 75.90634 -377.33377) (xy 75.950809 -377.278008) (xy 76.001242 -377.227575)
			(xy 76.057004 -377.183106) (xy 76.117395 -377.14516) (xy 76.181654 -377.114215) (xy 76.248974 -377.090658)
			(xy 76.318509 -377.074788) (xy 76.389383 -377.066802) (xy 76.425044 -377.066302) (xy 76.460705 -377.066802)
			(xy 76.531579 -377.074788) (xy 76.601114 -377.090658) (xy 76.668434 -377.114215) (xy 76.732693 -377.14516)
			(xy 76.793084 -377.183106) (xy 76.848846 -377.227575) (xy 76.899279 -377.278008) (xy 76.943748 -377.33377)
			(xy 76.981694 -377.394161) (xy 77.012639 -377.45842) (xy 77.036196 -377.52574) (xy 77.052066 -377.595275)
			(xy 77.060052 -377.666149) (xy 77.060052 -377.737471) (xy 77.059966 -377.738233) (xy 77.968848 -377.738233)
			(xy 77.968848 -377.666911) (xy 77.976834 -377.596037) (xy 77.992704 -377.526502) (xy 78.016261 -377.459182)
			(xy 78.047206 -377.394923) (xy 78.085152 -377.334532) (xy 78.129621 -377.27877) (xy 78.180054 -377.228337)
			(xy 78.235816 -377.183868) (xy 78.296207 -377.145922) (xy 78.360466 -377.114977) (xy 78.427786 -377.09142)
			(xy 78.497321 -377.07555) (xy 78.568195 -377.067564) (xy 78.603856 -377.067064) (xy 78.639517 -377.067564)
			(xy 78.710391 -377.07555) (xy 78.779926 -377.09142) (xy 78.847246 -377.114977) (xy 78.911505 -377.145922)
			(xy 78.971896 -377.183868) (xy 79.027658 -377.228337) (xy 79.078091 -377.27877) (xy 79.12256 -377.334532)
			(xy 79.160506 -377.394923) (xy 79.191451 -377.459182) (xy 79.215008 -377.526502) (xy 79.230878 -377.596037)
			(xy 79.238864 -377.666911) (xy 79.238864 -377.738233) (xy 79.230878 -377.809107) (xy 79.215008 -377.878642)
			(xy 79.191451 -377.945962) (xy 79.160506 -378.010221) (xy 79.12256 -378.070612) (xy 79.078091 -378.126374)
			(xy 79.027658 -378.176807) (xy 78.971896 -378.221276) (xy 78.911505 -378.259222) (xy 78.847246 -378.290167)
			(xy 78.779926 -378.313724) (xy 78.710391 -378.329594) (xy 78.639517 -378.33758) (xy 78.568195 -378.33758)
			(xy 78.497321 -378.329594) (xy 78.427786 -378.313724) (xy 78.360466 -378.290167) (xy 78.296207 -378.259222)
			(xy 78.235816 -378.221276) (xy 78.180054 -378.176807) (xy 78.129621 -378.126374) (xy 78.085152 -378.070612)
			(xy 78.047206 -378.010221) (xy 78.016261 -377.945962) (xy 77.992704 -377.878642) (xy 77.976834 -377.809107)
			(xy 77.968848 -377.738233) (xy 77.059966 -377.738233) (xy 77.052066 -377.808345) (xy 77.036196 -377.87788)
			(xy 77.012639 -377.9452) (xy 76.981694 -378.009459) (xy 76.943748 -378.06985) (xy 76.899279 -378.125612)
			(xy 76.848846 -378.176045) (xy 76.793084 -378.220514) (xy 76.732693 -378.25846) (xy 76.668434 -378.289405)
			(xy 76.601114 -378.312962) (xy 76.531579 -378.328832) (xy 76.460705 -378.336818) (xy 76.389383 -378.336818)
			(xy 76.318509 -378.328832) (xy 76.248974 -378.312962) (xy 76.181654 -378.289405) (xy 76.117395 -378.25846)
			(xy 76.057004 -378.220514) (xy 76.001242 -378.176045) (xy 75.950809 -378.125612) (xy 75.90634 -378.06985)
			(xy 75.868394 -378.009459) (xy 75.837449 -377.9452) (xy 75.813892 -377.87788) (xy 75.798022 -377.808345)
			(xy 75.790036 -377.737471) (xy 74.984618 -377.737471) (xy 74.976632 -377.808345) (xy 74.960762 -377.87788)
			(xy 74.937205 -377.9452) (xy 74.90626 -378.009459) (xy 74.868314 -378.06985) (xy 74.823845 -378.125612)
			(xy 74.773412 -378.176045) (xy 74.71765 -378.220514) (xy 74.657259 -378.25846) (xy 74.593 -378.289405)
			(xy 74.52568 -378.312962) (xy 74.456145 -378.328832) (xy 74.385271 -378.336818) (xy 74.313949 -378.336818)
			(xy 74.243075 -378.328832) (xy 74.17354 -378.312962) (xy 74.10622 -378.289405) (xy 74.041961 -378.25846)
			(xy 73.98157 -378.220514) (xy 73.925808 -378.176045) (xy 73.875375 -378.125612) (xy 73.830906 -378.06985)
			(xy 73.79296 -378.009459) (xy 73.762015 -377.9452) (xy 73.738458 -377.87788) (xy 73.722588 -377.808345)
			(xy 73.714602 -377.737471) (xy 46.259597 -377.737471) (xy 46.748954 -378.226828) (xy 56.579516 -378.226828)
			(xy 57.856681 -379.504041) (xy 73.714602 -379.504041) (xy 73.714602 -379.432719) (xy 73.722588 -379.361845)
			(xy 73.738458 -379.29231) (xy 73.762015 -379.22499) (xy 73.79296 -379.160731) (xy 73.830906 -379.10034)
			(xy 73.875375 -379.044578) (xy 73.925808 -378.994145) (xy 73.98157 -378.949676) (xy 74.041961 -378.91173)
			(xy 74.10622 -378.880785) (xy 74.17354 -378.857228) (xy 74.243075 -378.841358) (xy 74.313949 -378.833372)
			(xy 74.34961 -378.832872) (xy 74.385271 -378.833372) (xy 74.456145 -378.841358) (xy 74.52568 -378.857228)
			(xy 74.593 -378.880785) (xy 74.657259 -378.91173) (xy 74.71765 -378.949676) (xy 74.773412 -378.994145)
			(xy 74.823845 -379.044578) (xy 74.868314 -379.10034) (xy 74.90626 -379.160731) (xy 74.937205 -379.22499)
			(xy 74.960762 -379.29231) (xy 74.976632 -379.361845) (xy 74.984618 -379.432719) (xy 74.984618 -379.504041)
			(xy 75.790036 -379.504041) (xy 75.790036 -379.432719) (xy 75.798022 -379.361845) (xy 75.813892 -379.29231)
			(xy 75.837449 -379.22499) (xy 75.868394 -379.160731) (xy 75.90634 -379.10034) (xy 75.950809 -379.044578)
			(xy 76.001242 -378.994145) (xy 76.057004 -378.949676) (xy 76.117395 -378.91173) (xy 76.181654 -378.880785)
			(xy 76.248974 -378.857228) (xy 76.318509 -378.841358) (xy 76.389383 -378.833372) (xy 76.425044 -378.832872)
			(xy 76.460705 -378.833372) (xy 76.531579 -378.841358) (xy 76.601114 -378.857228) (xy 76.668434 -378.880785)
			(xy 76.732693 -378.91173) (xy 76.793084 -378.949676) (xy 76.848846 -378.994145) (xy 76.899279 -379.044578)
			(xy 76.943748 -379.10034) (xy 76.981694 -379.160731) (xy 77.012639 -379.22499) (xy 77.036196 -379.29231)
			(xy 77.052066 -379.361845) (xy 77.060052 -379.432719) (xy 77.060052 -379.504041) (xy 77.059966 -379.504803)
			(xy 77.968848 -379.504803) (xy 77.968848 -379.433481) (xy 77.976834 -379.362607) (xy 77.992704 -379.293072)
			(xy 78.016261 -379.225752) (xy 78.047206 -379.161493) (xy 78.085152 -379.101102) (xy 78.129621 -379.04534)
			(xy 78.180054 -378.994907) (xy 78.235816 -378.950438) (xy 78.296207 -378.912492) (xy 78.360466 -378.881547)
			(xy 78.427786 -378.85799) (xy 78.497321 -378.84212) (xy 78.568195 -378.834134) (xy 78.603856 -378.833634)
			(xy 78.639517 -378.834134) (xy 78.710391 -378.84212) (xy 78.779926 -378.85799) (xy 78.847246 -378.881547)
			(xy 78.911505 -378.912492) (xy 78.971896 -378.950438) (xy 79.027658 -378.994907) (xy 79.078091 -379.04534)
			(xy 79.12256 -379.101102) (xy 79.160506 -379.161493) (xy 79.191451 -379.225752) (xy 79.215008 -379.293072)
			(xy 79.230878 -379.362607) (xy 79.238864 -379.433481) (xy 79.238864 -379.504803) (xy 79.230878 -379.575677)
			(xy 79.215008 -379.645212) (xy 79.191451 -379.712532) (xy 79.160506 -379.776791) (xy 79.12256 -379.837182)
			(xy 79.078091 -379.892944) (xy 79.027658 -379.943377) (xy 78.971896 -379.987846) (xy 78.911505 -380.025792)
			(xy 78.847246 -380.056737) (xy 78.779926 -380.080294) (xy 78.710391 -380.096164) (xy 78.639517 -380.10415)
			(xy 78.568195 -380.10415) (xy 78.497321 -380.096164) (xy 78.427786 -380.080294) (xy 78.360466 -380.056737)
			(xy 78.296207 -380.025792) (xy 78.235816 -379.987846) (xy 78.180054 -379.943377) (xy 78.129621 -379.892944)
			(xy 78.085152 -379.837182) (xy 78.047206 -379.776791) (xy 78.016261 -379.712532) (xy 77.992704 -379.645212)
			(xy 77.976834 -379.575677) (xy 77.968848 -379.504803) (xy 77.059966 -379.504803) (xy 77.052066 -379.574915)
			(xy 77.036196 -379.64445) (xy 77.012639 -379.71177) (xy 76.981694 -379.776029) (xy 76.943748 -379.83642)
			(xy 76.899279 -379.892182) (xy 76.848846 -379.942615) (xy 76.793084 -379.987084) (xy 76.732693 -380.02503)
			(xy 76.668434 -380.055975) (xy 76.601114 -380.079532) (xy 76.531579 -380.095402) (xy 76.460705 -380.103388)
			(xy 76.389383 -380.103388) (xy 76.318509 -380.095402) (xy 76.248974 -380.079532) (xy 76.181654 -380.055975)
			(xy 76.117395 -380.02503) (xy 76.057004 -379.987084) (xy 76.001242 -379.942615) (xy 75.950809 -379.892182)
			(xy 75.90634 -379.83642) (xy 75.868394 -379.776029) (xy 75.837449 -379.71177) (xy 75.813892 -379.64445)
			(xy 75.798022 -379.574915) (xy 75.790036 -379.504041) (xy 74.984618 -379.504041) (xy 74.976632 -379.574915)
			(xy 74.960762 -379.64445) (xy 74.937205 -379.71177) (xy 74.90626 -379.776029) (xy 74.868314 -379.83642)
			(xy 74.823845 -379.892182) (xy 74.773412 -379.942615) (xy 74.71765 -379.987084) (xy 74.657259 -380.02503)
			(xy 74.593 -380.055975) (xy 74.52568 -380.079532) (xy 74.456145 -380.095402) (xy 74.385271 -380.103388)
			(xy 74.313949 -380.103388) (xy 74.243075 -380.095402) (xy 74.17354 -380.079532) (xy 74.10622 -380.055975)
			(xy 74.041961 -380.02503) (xy 73.98157 -379.987084) (xy 73.925808 -379.942615) (xy 73.875375 -379.892182)
			(xy 73.830906 -379.83642) (xy 73.79296 -379.776029) (xy 73.762015 -379.71177) (xy 73.738458 -379.64445)
			(xy 73.722588 -379.574915) (xy 73.714602 -379.504041) (xy 57.856681 -379.504041) (xy 63.30823 -384.955796)
			(xy 63.320385 -384.96714) (xy 63.349173 -384.983743) (xy 63.381276 -384.992338) (xy 63.397892 -384.99288)
			(xy 75.438254 -384.99288) (xy 75.454888 -384.992321) (xy 75.487006 -384.983634) (xy 75.515788 -384.966942)
			(xy 75.527916 -384.955542) (xy 76.298806 -384.184652) (xy 76.321539 -384.16265) (xy 76.371731 -384.124137)
			(xy 76.42652 -384.092504) (xy 76.48497 -384.068293) (xy 76.546079 -384.051919) (xy 76.608803 -384.043661)
			(xy 76.672069 -384.043661) (xy 76.734793 -384.051919) (xy 76.795902 -384.068293) (xy 76.854352 -384.092504)
			(xy 76.909141 -384.124137) (xy 76.959333 -384.16265) (xy 77.004068 -384.207385) (xy 77.042581 -384.257577)
			(xy 77.074214 -384.312366) (xy 77.098425 -384.370816) (xy 77.114799 -384.431925) (xy 77.123057 -384.494649)
			(xy 77.123057 -384.557915) (xy 77.114799 -384.620639) (xy 77.098425 -384.681748) (xy 77.074214 -384.740198)
			(xy 77.042581 -384.794987) (xy 77.004068 -384.845179) (xy 76.982066 -384.867912) (xy 76.14539 -385.704588)
			(xy 76.133929 -385.716719) (xy 76.117226 -385.745599) (xy 76.10858 -385.777822) (xy 76.108581 -385.811184)
			(xy 76.117229 -385.843406) (xy 76.133932 -385.872286) (xy 76.14539 -385.88442) (xy 77.117448 -386.856224)
			(xy 77.13945 -386.878957) (xy 77.177963 -386.929149) (xy 77.209596 -386.983938) (xy 77.233807 -387.042388)
			(xy 77.250181 -387.103497) (xy 77.258439 -387.166221) (xy 77.258439 -387.229487) (xy 77.250181 -387.292211)
			(xy 77.233807 -387.35332) (xy 77.209596 -387.41177) (xy 77.177963 -387.466559) (xy 77.13945 -387.516751)
			(xy 77.094715 -387.561486) (xy 77.044523 -387.599999) (xy 76.989734 -387.631632) (xy 76.931284 -387.655843)
			(xy 76.870175 -387.672217) (xy 76.807451 -387.680475) (xy 76.744185 -387.680475) (xy 76.681461 -387.672217)
			(xy 76.620352 -387.655843) (xy 76.561902 -387.631632) (xy 76.507113 -387.599999) (xy 76.456921 -387.561486)
			(xy 76.434188 -387.539484) (xy 75.66406 -386.769356) (xy 62.608968 -386.769356) (xy 56.001158 -380.161292)
			(xy 55.989009 -380.149941) (xy 55.960218 -380.13334) (xy 55.928113 -380.124748) (xy 55.911496 -380.124208)
			(xy 45.97781 -380.124208) (xy 41.525952 -375.672604) (xy 40.440864 -375.672604) (xy 40.409813 -375.672116)
			(xy 40.348225 -375.664129) (xy 40.288168 -375.648318) (xy 40.230632 -375.624942) (xy 40.176565 -375.594387)
			(xy 40.126858 -375.557158) (xy 40.082331 -375.513866) (xy 40.043717 -375.465227) (xy 40.011653 -375.412041)
			(xy 39.986668 -375.355185) (xy 39.969172 -375.295597) (xy 39.959456 -375.234259) (xy 39.957678 -375.172181)
			(xy 39.960296 -375.141236) (xy 39.962134 -375.117702) (xy 39.95811 -375.070675) (xy 39.945472 -375.025199)
			(xy 39.924655 -374.982839) (xy 39.896375 -374.94505) (xy 39.861604 -374.913132) (xy 39.821538 -374.888183)
			(xy 39.777554 -374.87106) (xy 39.731166 -374.862352) (xy 39.707566 -374.861836) (xy 38.819328 -374.861836)
			(xy 38.472618 -375.208292) (xy 36.620704 -375.208292) (xy 36.597468 -375.208843) (xy 36.551768 -375.217274)
			(xy 36.508363 -375.233874) (xy 36.4687 -375.25809) (xy 36.434101 -375.289114) (xy 36.405719 -375.325912)
			(xy 36.384502 -375.367257) (xy 36.371156 -375.41177) (xy 36.366127 -375.457969) (xy 36.369581 -375.504311)
			(xy 36.381404 -375.549253) (xy 36.390834 -375.570496) (xy 36.408653 -375.609583) (xy 36.437911 -375.690355)
			(xy 36.459679 -375.773459) (xy 36.473775 -375.858203) (xy 36.480083 -375.943879) (xy 36.478548 -376.029774)
			(xy 36.469184 -376.11517) (xy 36.452069 -376.199356) (xy 36.427346 -376.28163) (xy 36.395221 -376.361305)
			(xy 36.355962 -376.437718) (xy 36.309896 -376.510231) (xy 36.257407 -376.578239) (xy 36.198934 -376.641176)
			(xy 36.134962 -376.698516) (xy 36.066027 -376.749781) (xy 36.019339 -376.778284) (xy 40.137841 -376.778284)
			(xy 40.143941 -376.722847) (xy 40.158047 -376.66889) (xy 40.179859 -376.617561) (xy 40.208913 -376.569955)
			(xy 40.244588 -376.527087) (xy 40.286125 -376.48987) (xy 40.332638 -376.459097) (xy 40.383135 -376.435425)
			(xy 40.436542 -376.419357) (xy 40.491718 -376.411237) (xy 40.519604 -376.410728) (xy 40.54749 -376.411237)
			(xy 40.602666 -376.419357) (xy 40.656073 -376.435425) (xy 40.70657 -376.459097) (xy 40.753083 -376.48987)
			(xy 40.79462 -376.527087) (xy 40.830295 -376.569955) (xy 40.859349 -376.617561) (xy 40.881161 -376.66889)
			(xy 40.895267 -376.722847) (xy 40.901367 -376.778284) (xy 40.89933 -376.834018) (xy 40.8892 -376.888861)
			(xy 40.871193 -376.941645) (xy 40.845692 -376.991245) (xy 40.813241 -377.036603) (xy 40.774532 -377.076752)
			(xy 40.730389 -377.110838) (xy 40.681754 -377.138134) (xy 40.629663 -377.158057) (xy 40.575226 -377.170183)
			(xy 40.519604 -377.174254) (xy 40.463982 -377.170183) (xy 40.409545 -377.158057) (xy 40.357454 -377.138134)
			(xy 40.308819 -377.110838) (xy 40.264676 -377.076752) (xy 40.225967 -377.036603) (xy 40.193516 -376.991245)
			(xy 40.168015 -376.941645) (xy 40.150008 -376.888861) (xy 40.139878 -376.834018) (xy 40.137841 -376.778284)
			(xy 36.019339 -376.778284) (xy 35.992703 -376.794545) (xy 35.915601 -376.832433) (xy 35.835365 -376.863129)
			(xy 35.752662 -376.886378) (xy 35.668184 -376.901986) (xy 35.582634 -376.909823) (xy 35.496726 -376.909823)
			(xy 35.411176 -376.901986) (xy 35.326698 -376.886378) (xy 35.243995 -376.863129) (xy 35.163759 -376.832433)
			(xy 35.086657 -376.794545) (xy 35.013333 -376.749781) (xy 34.944398 -376.698516) (xy 34.880426 -376.641176)
			(xy 34.821953 -376.578239) (xy 34.769464 -376.510231) (xy 34.723398 -376.437718) (xy 34.684139 -376.361305)
			(xy 34.652014 -376.28163) (xy 34.627291 -376.199356) (xy 34.610176 -376.11517) (xy 34.600812 -376.029774)
			(xy 34.599277 -375.943879) (xy 34.605585 -375.858203) (xy 34.619681 -375.773459) (xy 34.641449 -375.690355)
			(xy 34.670707 -375.609583) (xy 34.688526 -375.570496) (xy 34.697979 -375.549266) (xy 34.709778 -375.504321)
			(xy 34.713214 -375.45798) (xy 34.708172 -375.411786) (xy 34.694819 -375.367277) (xy 34.673601 -375.325936)
			(xy 34.645224 -375.289139) (xy 34.610633 -375.258111) (xy 34.570979 -375.233885) (xy 34.527583 -375.217269)
			(xy 34.48189 -375.208815) (xy 34.458656 -375.208292) (xy 34.412682 -375.208292) (xy 31.790132 -372.585996)
			(xy 31.498032 -372.585996) (xy 31.47592 -372.586464) (xy 31.432359 -372.594097) (xy 31.390778 -372.609157)
			(xy 31.352431 -372.631188) (xy 31.318478 -372.659525) (xy 31.289943 -372.693312) (xy 31.267688 -372.731528)
			(xy 31.252385 -372.773021) (xy 31.244497 -372.816536) (xy 31.244261 -372.86076) (xy 31.251685 -372.904357)
			(xy 31.266544 -372.94601) (xy 31.277052 -372.965472) (xy 31.298178 -373.003643) (xy 31.334077 -373.083165)
			(xy 31.362454 -373.16567) (xy 31.383064 -373.250449) (xy 31.395732 -373.336774) (xy 31.400346 -373.423901)
			(xy 31.396869 -373.51108) (xy 31.385329 -373.597563) (xy 31.365826 -373.682604) (xy 31.338528 -373.765473)
			(xy 31.30367 -373.845456) (xy 31.261551 -373.921865) (xy 31.212534 -373.994043) (xy 31.15704 -374.061369)
			(xy 31.095548 -374.123265) (xy 31.028585 -374.179196) (xy 30.956728 -374.228683) (xy 30.880595 -374.2713)
			(xy 30.800841 -374.306679) (xy 30.718153 -374.334517) (xy 30.63324 -374.354575) (xy 30.546835 -374.366678)
			(xy 30.45968 -374.370724) (xy 30.372525 -374.366678) (xy 30.28612 -374.354575) (xy 30.201207 -374.334517)
			(xy 30.118519 -374.306679) (xy 30.038765 -374.2713) (xy 29.962632 -374.228683) (xy 29.890775 -374.179196)
			(xy 29.823812 -374.123265) (xy 29.76232 -374.061369) (xy 29.706826 -373.994043) (xy 29.657809 -373.921865)
			(xy 29.61569 -373.845456) (xy 29.580832 -373.765473) (xy 29.553534 -373.682604) (xy 29.534031 -373.597563)
			(xy 29.522491 -373.51108) (xy 29.519014 -373.423901) (xy 29.523628 -373.336774) (xy 29.536296 -373.250449)
			(xy 29.556906 -373.16567) (xy 29.585283 -373.083165) (xy 29.621182 -373.003643) (xy 29.642308 -372.965472)
			(xy 29.652807 -372.946) (xy 29.66769 -372.904347) (xy 29.675134 -372.860746) (xy 29.674912 -372.816515)
			(xy 29.667032 -372.77299) (xy 29.651732 -372.731489) (xy 29.629475 -372.693264) (xy 29.600933 -372.659474)
			(xy 29.566969 -372.631138) (xy 29.52861 -372.609113) (xy 29.487016 -372.594066) (xy 29.443445 -372.58645)
			(xy 29.421328 -372.585996) (xy 28.897072 -372.585996) (xy 27.44343 -372.16461) (xy 27.413211 -372.155303)
			(xy 27.355295 -372.129932) (xy 27.301186 -372.097218) (xy 27.25181 -372.057721) (xy 27.208011 -372.012117)
			(xy 27.17054 -371.961187) (xy 27.140037 -371.905801) (xy 27.117024 -371.846908) (xy 27.101895 -371.785515)
			(xy 27.094909 -371.722672) (xy 23.656312 -371.722672) (xy 27.947128 -376.013488) (xy 29.519874 -376.013488)
			(xy 29.519874 -375.926588) (xy 29.527892 -375.840059) (xy 29.54386 -375.754639) (xy 29.567641 -375.671057)
			(xy 29.599033 -375.590025) (xy 29.637767 -375.512236) (xy 29.683514 -375.438352) (xy 29.735883 -375.369005)
			(xy 29.794427 -375.304785) (xy 29.858647 -375.246241) (xy 29.927994 -375.193872) (xy 30.001878 -375.148125)
			(xy 30.079667 -375.109391) (xy 30.160699 -375.077999) (xy 30.244281 -375.054218) (xy 30.329701 -375.03825)
			(xy 30.41623 -375.030232) (xy 30.45968 -375.02973) (xy 30.50313 -375.030232) (xy 30.589659 -375.03825)
			(xy 30.675079 -375.054218) (xy 30.758661 -375.077999) (xy 30.839693 -375.109391) (xy 30.917482 -375.148125)
			(xy 30.991366 -375.193872) (xy 31.060713 -375.246241) (xy 31.124933 -375.304785) (xy 31.183477 -375.369005)
			(xy 31.235846 -375.438352) (xy 31.281593 -375.512236) (xy 31.320327 -375.590025) (xy 31.351719 -375.671057)
			(xy 31.3755 -375.754639) (xy 31.391468 -375.840059) (xy 31.399486 -375.926588) (xy 31.399486 -376.013488)
			(xy 31.391468 -376.100017) (xy 31.3755 -376.185437) (xy 31.351719 -376.269019) (xy 31.320327 -376.350051)
			(xy 31.281593 -376.42784) (xy 31.235846 -376.501724) (xy 31.183477 -376.571071) (xy 31.124933 -376.635291)
			(xy 31.060713 -376.693835) (xy 30.991366 -376.746204) (xy 30.917482 -376.791951) (xy 30.839693 -376.830685)
			(xy 30.758661 -376.862077) (xy 30.675079 -376.885858) (xy 30.589659 -376.901826) (xy 30.50313 -376.909844)
			(xy 30.41623 -376.909844) (xy 30.329701 -376.901826) (xy 30.244281 -376.885858) (xy 30.160699 -376.862077)
			(xy 30.079667 -376.830685) (xy 30.001878 -376.791951) (xy 29.927994 -376.746204) (xy 29.858647 -376.693835)
			(xy 29.794427 -376.635291) (xy 29.735883 -376.571071) (xy 29.683514 -376.501724) (xy 29.637767 -376.42784)
			(xy 29.599033 -376.350051) (xy 29.567641 -376.269019) (xy 29.54386 -376.185437) (xy 29.527892 -376.100017)
			(xy 29.519874 -376.013488) (xy 27.947128 -376.013488) (xy 29.59608 -377.66244) (xy 29.59608 -389.706967)
			(xy 66.405498 -389.706967) (xy 66.405498 -389.635645) (xy 66.413484 -389.564771) (xy 66.429354 -389.495236)
			(xy 66.452911 -389.427916) (xy 66.483856 -389.363657) (xy 66.521802 -389.303266) (xy 66.566271 -389.247504)
			(xy 66.616704 -389.197071) (xy 66.672466 -389.152602) (xy 66.732857 -389.114656) (xy 66.797116 -389.083711)
			(xy 66.864436 -389.060154) (xy 66.933971 -389.044284) (xy 67.004845 -389.036298) (xy 67.040506 -389.035798)
			(xy 67.076167 -389.036298) (xy 67.147041 -389.044284) (xy 67.216576 -389.060154) (xy 67.283896 -389.083711)
			(xy 67.348155 -389.114656) (xy 67.408546 -389.152602) (xy 67.464308 -389.197071) (xy 67.514741 -389.247504)
			(xy 67.55921 -389.303266) (xy 67.597156 -389.363657) (xy 67.628101 -389.427916) (xy 67.651658 -389.495236)
			(xy 67.667528 -389.564771) (xy 67.675514 -389.635645) (xy 67.675514 -389.706967) (xy 68.334628 -389.706967)
			(xy 68.334628 -389.635645) (xy 68.342614 -389.564771) (xy 68.358484 -389.495236) (xy 68.382041 -389.427916)
			(xy 68.412986 -389.363657) (xy 68.450932 -389.303266) (xy 68.495401 -389.247504) (xy 68.545834 -389.197071)
			(xy 68.601596 -389.152602) (xy 68.661987 -389.114656) (xy 68.726246 -389.083711) (xy 68.793566 -389.060154)
			(xy 68.863101 -389.044284) (xy 68.933975 -389.036298) (xy 68.969636 -389.035798) (xy 69.005297 -389.036298)
			(xy 69.076171 -389.044284) (xy 69.145706 -389.060154) (xy 69.213026 -389.083711) (xy 69.277285 -389.114656)
			(xy 69.337676 -389.152602) (xy 69.393438 -389.197071) (xy 69.443871 -389.247504) (xy 69.48834 -389.303266)
			(xy 69.526286 -389.363657) (xy 69.557231 -389.427916) (xy 69.580788 -389.495236) (xy 69.596658 -389.564771)
			(xy 69.604644 -389.635645) (xy 69.604644 -389.706967) (xy 69.599492 -389.752687) (xy 70.078592 -389.752687)
			(xy 70.078592 -389.681365) (xy 70.086578 -389.610491) (xy 70.102448 -389.540956) (xy 70.126005 -389.473636)
			(xy 70.15695 -389.409377) (xy 70.194896 -389.348986) (xy 70.239365 -389.293224) (xy 70.289798 -389.242791)
			(xy 70.34556 -389.198322) (xy 70.405951 -389.160376) (xy 70.47021 -389.129431) (xy 70.53753 -389.105874)
			(xy 70.607065 -389.090004) (xy 70.677939 -389.082018) (xy 70.7136 -389.081518) (xy 70.749261 -389.082018)
			(xy 70.820135 -389.090004) (xy 70.88967 -389.105874) (xy 70.95699 -389.129431) (xy 71.021249 -389.160376)
			(xy 71.08164 -389.198322) (xy 71.137402 -389.242791) (xy 71.187835 -389.293224) (xy 71.232304 -389.348986)
			(xy 71.27025 -389.409377) (xy 71.301195 -389.473636) (xy 71.324752 -389.540956) (xy 71.340622 -389.610491)
			(xy 71.348608 -389.681365) (xy 71.348608 -389.752687) (xy 72.007722 -389.752687) (xy 72.007722 -389.681365)
			(xy 72.015708 -389.610491) (xy 72.031578 -389.540956) (xy 72.055135 -389.473636) (xy 72.08608 -389.409377)
			(xy 72.124026 -389.348986) (xy 72.168495 -389.293224) (xy 72.218928 -389.242791) (xy 72.27469 -389.198322)
			(xy 72.335081 -389.160376) (xy 72.39934 -389.129431) (xy 72.46666 -389.105874) (xy 72.536195 -389.090004)
			(xy 72.607069 -389.082018) (xy 72.64273 -389.081518) (xy 72.678391 -389.082018) (xy 72.749265 -389.090004)
			(xy 72.8188 -389.105874) (xy 72.88612 -389.129431) (xy 72.950379 -389.160376) (xy 73.01077 -389.198322)
			(xy 73.066532 -389.242791) (xy 73.116965 -389.293224) (xy 73.161434 -389.348986) (xy 73.19938 -389.409377)
			(xy 73.230325 -389.473636) (xy 73.253882 -389.540956) (xy 73.269752 -389.610491) (xy 73.277738 -389.681365)
			(xy 73.277738 -389.752687) (xy 73.269752 -389.823561) (xy 73.253882 -389.893096) (xy 73.230325 -389.960416)
			(xy 73.19938 -390.024675) (xy 73.161434 -390.085066) (xy 73.116965 -390.140828) (xy 73.066532 -390.191261)
			(xy 73.01077 -390.23573) (xy 72.950379 -390.273676) (xy 72.88612 -390.304621) (xy 72.8188 -390.328178)
			(xy 72.749265 -390.344048) (xy 72.678391 -390.352034) (xy 72.607069 -390.352034) (xy 72.536195 -390.344048)
			(xy 72.46666 -390.328178) (xy 72.39934 -390.304621) (xy 72.335081 -390.273676) (xy 72.27469 -390.23573)
			(xy 72.218928 -390.191261) (xy 72.168495 -390.140828) (xy 72.124026 -390.085066) (xy 72.08608 -390.024675)
			(xy 72.055135 -389.960416) (xy 72.031578 -389.893096) (xy 72.015708 -389.823561) (xy 72.007722 -389.752687)
			(xy 71.348608 -389.752687) (xy 71.340622 -389.823561) (xy 71.324752 -389.893096) (xy 71.301195 -389.960416)
			(xy 71.27025 -390.024675) (xy 71.232304 -390.085066) (xy 71.187835 -390.140828) (xy 71.137402 -390.191261)
			(xy 71.08164 -390.23573) (xy 71.021249 -390.273676) (xy 70.95699 -390.304621) (xy 70.88967 -390.328178)
			(xy 70.820135 -390.344048) (xy 70.749261 -390.352034) (xy 70.677939 -390.352034) (xy 70.607065 -390.344048)
			(xy 70.53753 -390.328178) (xy 70.47021 -390.304621) (xy 70.405951 -390.273676) (xy 70.34556 -390.23573)
			(xy 70.289798 -390.191261) (xy 70.239365 -390.140828) (xy 70.194896 -390.085066) (xy 70.15695 -390.024675)
			(xy 70.126005 -389.960416) (xy 70.102448 -389.893096) (xy 70.086578 -389.823561) (xy 70.078592 -389.752687)
			(xy 69.599492 -389.752687) (xy 69.596658 -389.777841) (xy 69.580788 -389.847376) (xy 69.557231 -389.914696)
			(xy 69.526286 -389.978955) (xy 69.48834 -390.039346) (xy 69.443871 -390.095108) (xy 69.393438 -390.145541)
			(xy 69.337676 -390.19001) (xy 69.277285 -390.227956) (xy 69.213026 -390.258901) (xy 69.145706 -390.282458)
			(xy 69.076171 -390.298328) (xy 69.005297 -390.306314) (xy 68.933975 -390.306314) (xy 68.863101 -390.298328)
			(xy 68.793566 -390.282458) (xy 68.726246 -390.258901) (xy 68.661987 -390.227956) (xy 68.601596 -390.19001)
			(xy 68.545834 -390.145541) (xy 68.495401 -390.095108) (xy 68.450932 -390.039346) (xy 68.412986 -389.978955)
			(xy 68.382041 -389.914696) (xy 68.358484 -389.847376) (xy 68.342614 -389.777841) (xy 68.334628 -389.706967)
			(xy 67.675514 -389.706967) (xy 67.667528 -389.777841) (xy 67.651658 -389.847376) (xy 67.628101 -389.914696)
			(xy 67.597156 -389.978955) (xy 67.55921 -390.039346) (xy 67.514741 -390.095108) (xy 67.464308 -390.145541)
			(xy 67.408546 -390.19001) (xy 67.348155 -390.227956) (xy 67.283896 -390.258901) (xy 67.216576 -390.282458)
			(xy 67.147041 -390.298328) (xy 67.076167 -390.306314) (xy 67.004845 -390.306314) (xy 66.933971 -390.298328)
			(xy 66.864436 -390.282458) (xy 66.797116 -390.258901) (xy 66.732857 -390.227956) (xy 66.672466 -390.19001)
			(xy 66.616704 -390.145541) (xy 66.566271 -390.095108) (xy 66.521802 -390.039346) (xy 66.483856 -389.978955)
			(xy 66.452911 -389.914696) (xy 66.429354 -389.847376) (xy 66.413484 -389.777841) (xy 66.405498 -389.706967)
			(xy 29.59608 -389.706967) (xy 29.59608 -391.463631) (xy 66.405498 -391.463631) (xy 66.405498 -391.392309)
			(xy 66.413484 -391.321435) (xy 66.429354 -391.2519) (xy 66.452911 -391.18458) (xy 66.483856 -391.120321)
			(xy 66.521802 -391.05993) (xy 66.566271 -391.004168) (xy 66.616704 -390.953735) (xy 66.672466 -390.909266)
			(xy 66.732857 -390.87132) (xy 66.797116 -390.840375) (xy 66.864436 -390.816818) (xy 66.933971 -390.800948)
			(xy 67.004845 -390.792962) (xy 67.040506 -390.792462) (xy 67.076167 -390.792962) (xy 67.147041 -390.800948)
			(xy 67.216576 -390.816818) (xy 67.283896 -390.840375) (xy 67.348155 -390.87132) (xy 67.408546 -390.909266)
			(xy 67.464308 -390.953735) (xy 67.514741 -391.004168) (xy 67.55921 -391.05993) (xy 67.597156 -391.120321)
			(xy 67.628101 -391.18458) (xy 67.651658 -391.2519) (xy 67.667528 -391.321435) (xy 67.675514 -391.392309)
			(xy 67.675514 -391.463631) (xy 68.334628 -391.463631) (xy 68.334628 -391.392309) (xy 68.342614 -391.321435)
			(xy 68.358484 -391.2519) (xy 68.382041 -391.18458) (xy 68.412986 -391.120321) (xy 68.450932 -391.05993)
			(xy 68.495401 -391.004168) (xy 68.545834 -390.953735) (xy 68.601596 -390.909266) (xy 68.661987 -390.87132)
			(xy 68.726246 -390.840375) (xy 68.793566 -390.816818) (xy 68.863101 -390.800948) (xy 68.933975 -390.792962)
			(xy 68.969636 -390.792462) (xy 69.005297 -390.792962) (xy 69.076171 -390.800948) (xy 69.145706 -390.816818)
			(xy 69.213026 -390.840375) (xy 69.277285 -390.87132) (xy 69.337676 -390.909266) (xy 69.393438 -390.953735)
			(xy 69.443871 -391.004168) (xy 69.48834 -391.05993) (xy 69.526286 -391.120321) (xy 69.557231 -391.18458)
			(xy 69.580788 -391.2519) (xy 69.596658 -391.321435) (xy 69.604644 -391.392309) (xy 69.604644 -391.463631)
			(xy 69.599492 -391.509351) (xy 70.078592 -391.509351) (xy 70.078592 -391.438029) (xy 70.086578 -391.367155)
			(xy 70.102448 -391.29762) (xy 70.126005 -391.2303) (xy 70.15695 -391.166041) (xy 70.194896 -391.10565)
			(xy 70.239365 -391.049888) (xy 70.289798 -390.999455) (xy 70.34556 -390.954986) (xy 70.405951 -390.91704)
			(xy 70.47021 -390.886095) (xy 70.53753 -390.862538) (xy 70.607065 -390.846668) (xy 70.677939 -390.838682)
			(xy 70.7136 -390.838182) (xy 70.749261 -390.838682) (xy 70.820135 -390.846668) (xy 70.88967 -390.862538)
			(xy 70.95699 -390.886095) (xy 71.021249 -390.91704) (xy 71.08164 -390.954986) (xy 71.137402 -390.999455)
			(xy 71.187835 -391.049888) (xy 71.232304 -391.10565) (xy 71.27025 -391.166041) (xy 71.301195 -391.2303)
			(xy 71.324752 -391.29762) (xy 71.340622 -391.367155) (xy 71.348608 -391.438029) (xy 71.348608 -391.509351)
			(xy 72.007722 -391.509351) (xy 72.007722 -391.438029) (xy 72.015708 -391.367155) (xy 72.031578 -391.29762)
			(xy 72.055135 -391.2303) (xy 72.08608 -391.166041) (xy 72.124026 -391.10565) (xy 72.168495 -391.049888)
			(xy 72.218928 -390.999455) (xy 72.27469 -390.954986) (xy 72.335081 -390.91704) (xy 72.39934 -390.886095)
			(xy 72.46666 -390.862538) (xy 72.536195 -390.846668) (xy 72.607069 -390.838682) (xy 72.64273 -390.838182)
			(xy 72.678391 -390.838682) (xy 72.749265 -390.846668) (xy 72.8188 -390.862538) (xy 72.88612 -390.886095)
			(xy 72.950379 -390.91704) (xy 73.01077 -390.954986) (xy 73.066532 -390.999455) (xy 73.116965 -391.049888)
			(xy 73.161434 -391.10565) (xy 73.19938 -391.166041) (xy 73.230325 -391.2303) (xy 73.253882 -391.29762)
			(xy 73.269752 -391.367155) (xy 73.277738 -391.438029) (xy 73.277738 -391.509351) (xy 73.269752 -391.580225)
			(xy 73.253882 -391.64976) (xy 73.230325 -391.71708) (xy 73.19938 -391.781339) (xy 73.161434 -391.84173)
			(xy 73.116965 -391.897492) (xy 73.066532 -391.947925) (xy 73.01077 -391.992394) (xy 72.950379 -392.03034)
			(xy 72.88612 -392.061285) (xy 72.8188 -392.084842) (xy 72.749265 -392.100712) (xy 72.678391 -392.108698)
			(xy 72.607069 -392.108698) (xy 72.536195 -392.100712) (xy 72.46666 -392.084842) (xy 72.39934 -392.061285)
			(xy 72.335081 -392.03034) (xy 72.27469 -391.992394) (xy 72.218928 -391.947925) (xy 72.168495 -391.897492)
			(xy 72.124026 -391.84173) (xy 72.08608 -391.781339) (xy 72.055135 -391.71708) (xy 72.031578 -391.64976)
			(xy 72.015708 -391.580225) (xy 72.007722 -391.509351) (xy 71.348608 -391.509351) (xy 71.340622 -391.580225)
			(xy 71.324752 -391.64976) (xy 71.301195 -391.71708) (xy 71.27025 -391.781339) (xy 71.232304 -391.84173)
			(xy 71.187835 -391.897492) (xy 71.137402 -391.947925) (xy 71.08164 -391.992394) (xy 71.021249 -392.03034)
			(xy 70.95699 -392.061285) (xy 70.88967 -392.084842) (xy 70.820135 -392.100712) (xy 70.749261 -392.108698)
			(xy 70.677939 -392.108698) (xy 70.607065 -392.100712) (xy 70.53753 -392.084842) (xy 70.47021 -392.061285)
			(xy 70.405951 -392.03034) (xy 70.34556 -391.992394) (xy 70.289798 -391.947925) (xy 70.239365 -391.897492)
			(xy 70.194896 -391.84173) (xy 70.15695 -391.781339) (xy 70.126005 -391.71708) (xy 70.102448 -391.64976)
			(xy 70.086578 -391.580225) (xy 70.078592 -391.509351) (xy 69.599492 -391.509351) (xy 69.596658 -391.534505)
			(xy 69.580788 -391.60404) (xy 69.557231 -391.67136) (xy 69.526286 -391.735619) (xy 69.48834 -391.79601)
			(xy 69.443871 -391.851772) (xy 69.393438 -391.902205) (xy 69.337676 -391.946674) (xy 69.277285 -391.98462)
			(xy 69.213026 -392.015565) (xy 69.145706 -392.039122) (xy 69.076171 -392.054992) (xy 69.005297 -392.062978)
			(xy 68.933975 -392.062978) (xy 68.863101 -392.054992) (xy 68.793566 -392.039122) (xy 68.726246 -392.015565)
			(xy 68.661987 -391.98462) (xy 68.601596 -391.946674) (xy 68.545834 -391.902205) (xy 68.495401 -391.851772)
			(xy 68.450932 -391.79601) (xy 68.412986 -391.735619) (xy 68.382041 -391.67136) (xy 68.358484 -391.60404)
			(xy 68.342614 -391.534505) (xy 68.334628 -391.463631) (xy 67.675514 -391.463631) (xy 67.667528 -391.534505)
			(xy 67.651658 -391.60404) (xy 67.628101 -391.67136) (xy 67.597156 -391.735619) (xy 67.55921 -391.79601)
			(xy 67.514741 -391.851772) (xy 67.464308 -391.902205) (xy 67.408546 -391.946674) (xy 67.348155 -391.98462)
			(xy 67.283896 -392.015565) (xy 67.216576 -392.039122) (xy 67.147041 -392.054992) (xy 67.076167 -392.062978)
			(xy 67.004845 -392.062978) (xy 66.933971 -392.054992) (xy 66.864436 -392.039122) (xy 66.797116 -392.015565)
			(xy 66.732857 -391.98462) (xy 66.672466 -391.946674) (xy 66.616704 -391.902205) (xy 66.566271 -391.851772)
			(xy 66.521802 -391.79601) (xy 66.483856 -391.735619) (xy 66.452911 -391.67136) (xy 66.429354 -391.60404)
			(xy 66.413484 -391.534505) (xy 66.405498 -391.463631) (xy 29.59608 -391.463631) (xy 29.59608 -393.230201)
			(xy 66.405498 -393.230201) (xy 66.405498 -393.158879) (xy 66.413484 -393.088005) (xy 66.429354 -393.01847)
			(xy 66.452911 -392.95115) (xy 66.483856 -392.886891) (xy 66.521802 -392.8265) (xy 66.566271 -392.770738)
			(xy 66.616704 -392.720305) (xy 66.672466 -392.675836) (xy 66.732857 -392.63789) (xy 66.797116 -392.606945)
			(xy 66.864436 -392.583388) (xy 66.933971 -392.567518) (xy 67.004845 -392.559532) (xy 67.040506 -392.559032)
			(xy 67.076167 -392.559532) (xy 67.147041 -392.567518) (xy 67.216576 -392.583388) (xy 67.283896 -392.606945)
			(xy 67.348155 -392.63789) (xy 67.408546 -392.675836) (xy 67.464308 -392.720305) (xy 67.514741 -392.770738)
			(xy 67.55921 -392.8265) (xy 67.597156 -392.886891) (xy 67.628101 -392.95115) (xy 67.651658 -393.01847)
			(xy 67.667528 -393.088005) (xy 67.675514 -393.158879) (xy 67.675514 -393.230201) (xy 68.334628 -393.230201)
			(xy 68.334628 -393.158879) (xy 68.342614 -393.088005) (xy 68.358484 -393.01847) (xy 68.382041 -392.95115)
			(xy 68.412986 -392.886891) (xy 68.450932 -392.8265) (xy 68.495401 -392.770738) (xy 68.545834 -392.720305)
			(xy 68.601596 -392.675836) (xy 68.661987 -392.63789) (xy 68.726246 -392.606945) (xy 68.793566 -392.583388)
			(xy 68.863101 -392.567518) (xy 68.933975 -392.559532) (xy 68.969636 -392.559032) (xy 69.005297 -392.559532)
			(xy 69.076171 -392.567518) (xy 69.145706 -392.583388) (xy 69.213026 -392.606945) (xy 69.277285 -392.63789)
			(xy 69.337676 -392.675836) (xy 69.393438 -392.720305) (xy 69.443871 -392.770738) (xy 69.48834 -392.8265)
			(xy 69.526286 -392.886891) (xy 69.557231 -392.95115) (xy 69.580788 -393.01847) (xy 69.596658 -393.088005)
			(xy 69.604644 -393.158879) (xy 69.604644 -393.230201) (xy 69.599492 -393.275921) (xy 70.078592 -393.275921)
			(xy 70.078592 -393.204599) (xy 70.086578 -393.133725) (xy 70.102448 -393.06419) (xy 70.126005 -392.99687)
			(xy 70.15695 -392.932611) (xy 70.194896 -392.87222) (xy 70.239365 -392.816458) (xy 70.289798 -392.766025)
			(xy 70.34556 -392.721556) (xy 70.405951 -392.68361) (xy 70.47021 -392.652665) (xy 70.53753 -392.629108)
			(xy 70.607065 -392.613238) (xy 70.677939 -392.605252) (xy 70.7136 -392.604752) (xy 70.749261 -392.605252)
			(xy 70.820135 -392.613238) (xy 70.88967 -392.629108) (xy 70.95699 -392.652665) (xy 71.021249 -392.68361)
			(xy 71.08164 -392.721556) (xy 71.137402 -392.766025) (xy 71.187835 -392.816458) (xy 71.232304 -392.87222)
			(xy 71.27025 -392.932611) (xy 71.301195 -392.99687) (xy 71.324752 -393.06419) (xy 71.340622 -393.133725)
			(xy 71.348608 -393.204599) (xy 71.348608 -393.275921) (xy 72.007722 -393.275921) (xy 72.007722 -393.204599)
			(xy 72.015708 -393.133725) (xy 72.031578 -393.06419) (xy 72.055135 -392.99687) (xy 72.08608 -392.932611)
			(xy 72.124026 -392.87222) (xy 72.168495 -392.816458) (xy 72.218928 -392.766025) (xy 72.27469 -392.721556)
			(xy 72.335081 -392.68361) (xy 72.39934 -392.652665) (xy 72.46666 -392.629108) (xy 72.536195 -392.613238)
			(xy 72.607069 -392.605252) (xy 72.64273 -392.604752) (xy 72.678391 -392.605252) (xy 72.749265 -392.613238)
			(xy 72.8188 -392.629108) (xy 72.88612 -392.652665) (xy 72.950379 -392.68361) (xy 73.01077 -392.721556)
			(xy 73.066532 -392.766025) (xy 73.116965 -392.816458) (xy 73.161434 -392.87222) (xy 73.19938 -392.932611)
			(xy 73.230325 -392.99687) (xy 73.253882 -393.06419) (xy 73.269752 -393.133725) (xy 73.277738 -393.204599)
			(xy 73.277738 -393.275921) (xy 73.269752 -393.346795) (xy 73.253882 -393.41633) (xy 73.230325 -393.48365)
			(xy 73.19938 -393.547909) (xy 73.161434 -393.6083) (xy 73.116965 -393.664062) (xy 73.066532 -393.714495)
			(xy 73.01077 -393.758964) (xy 72.950379 -393.79691) (xy 72.88612 -393.827855) (xy 72.8188 -393.851412)
			(xy 72.749265 -393.867282) (xy 72.678391 -393.875268) (xy 72.607069 -393.875268) (xy 72.536195 -393.867282)
			(xy 72.46666 -393.851412) (xy 72.39934 -393.827855) (xy 72.335081 -393.79691) (xy 72.27469 -393.758964)
			(xy 72.218928 -393.714495) (xy 72.168495 -393.664062) (xy 72.124026 -393.6083) (xy 72.08608 -393.547909)
			(xy 72.055135 -393.48365) (xy 72.031578 -393.41633) (xy 72.015708 -393.346795) (xy 72.007722 -393.275921)
			(xy 71.348608 -393.275921) (xy 71.340622 -393.346795) (xy 71.324752 -393.41633) (xy 71.301195 -393.48365)
			(xy 71.27025 -393.547909) (xy 71.232304 -393.6083) (xy 71.187835 -393.664062) (xy 71.137402 -393.714495)
			(xy 71.08164 -393.758964) (xy 71.021249 -393.79691) (xy 70.95699 -393.827855) (xy 70.88967 -393.851412)
			(xy 70.820135 -393.867282) (xy 70.749261 -393.875268) (xy 70.677939 -393.875268) (xy 70.607065 -393.867282)
			(xy 70.53753 -393.851412) (xy 70.47021 -393.827855) (xy 70.405951 -393.79691) (xy 70.34556 -393.758964)
			(xy 70.289798 -393.714495) (xy 70.239365 -393.664062) (xy 70.194896 -393.6083) (xy 70.15695 -393.547909)
			(xy 70.126005 -393.48365) (xy 70.102448 -393.41633) (xy 70.086578 -393.346795) (xy 70.078592 -393.275921)
			(xy 69.599492 -393.275921) (xy 69.596658 -393.301075) (xy 69.580788 -393.37061) (xy 69.557231 -393.43793)
			(xy 69.526286 -393.502189) (xy 69.48834 -393.56258) (xy 69.443871 -393.618342) (xy 69.393438 -393.668775)
			(xy 69.337676 -393.713244) (xy 69.277285 -393.75119) (xy 69.213026 -393.782135) (xy 69.145706 -393.805692)
			(xy 69.076171 -393.821562) (xy 69.005297 -393.829548) (xy 68.933975 -393.829548) (xy 68.863101 -393.821562)
			(xy 68.793566 -393.805692) (xy 68.726246 -393.782135) (xy 68.661987 -393.75119) (xy 68.601596 -393.713244)
			(xy 68.545834 -393.668775) (xy 68.495401 -393.618342) (xy 68.450932 -393.56258) (xy 68.412986 -393.502189)
			(xy 68.382041 -393.43793) (xy 68.358484 -393.37061) (xy 68.342614 -393.301075) (xy 68.334628 -393.230201)
			(xy 67.675514 -393.230201) (xy 67.667528 -393.301075) (xy 67.651658 -393.37061) (xy 67.628101 -393.43793)
			(xy 67.597156 -393.502189) (xy 67.55921 -393.56258) (xy 67.514741 -393.618342) (xy 67.464308 -393.668775)
			(xy 67.408546 -393.713244) (xy 67.348155 -393.75119) (xy 67.283896 -393.782135) (xy 67.216576 -393.805692)
			(xy 67.147041 -393.821562) (xy 67.076167 -393.829548) (xy 67.004845 -393.829548) (xy 66.933971 -393.821562)
			(xy 66.864436 -393.805692) (xy 66.797116 -393.782135) (xy 66.732857 -393.75119) (xy 66.672466 -393.713244)
			(xy 66.616704 -393.668775) (xy 66.566271 -393.618342) (xy 66.521802 -393.56258) (xy 66.483856 -393.502189)
			(xy 66.452911 -393.43793) (xy 66.429354 -393.37061) (xy 66.413484 -393.301075) (xy 66.405498 -393.230201)
			(xy 29.59608 -393.230201) (xy 29.59608 -395.588913) (xy 51.208676 -395.588913) (xy 51.208676 -395.507803)
			(xy 51.216626 -395.427084) (xy 51.232449 -395.347533) (xy 51.255994 -395.269917) (xy 51.287033 -395.194981)
			(xy 51.325268 -395.123449) (xy 51.37033 -395.056009) (xy 51.421785 -394.99331) (xy 51.479138 -394.935957)
			(xy 51.541837 -394.884502) (xy 51.609277 -394.83944) (xy 51.680809 -394.801205) (xy 51.755745 -394.770166)
			(xy 51.833361 -394.746621) (xy 51.912912 -394.730798) (xy 51.993631 -394.722848) (xy 52.034186 -394.72235)
			(xy 52.074741 -394.722848) (xy 52.15546 -394.730798) (xy 52.235011 -394.746621) (xy 52.312627 -394.770166)
			(xy 52.387563 -394.801205) (xy 52.459095 -394.83944) (xy 52.526535 -394.884502) (xy 52.589234 -394.935957)
			(xy 52.646587 -394.99331) (xy 52.698042 -395.056009) (xy 52.743104 -395.123449) (xy 52.781339 -395.194981)
			(xy 52.812378 -395.269917) (xy 52.835923 -395.347533) (xy 52.851746 -395.427084) (xy 52.859696 -395.507803)
			(xy 52.859696 -395.588913) (xy 52.851746 -395.669632) (xy 52.835923 -395.749183) (xy 52.812378 -395.826799)
			(xy 52.781339 -395.901735) (xy 52.743104 -395.973267) (xy 52.698042 -396.040707) (xy 52.646587 -396.103406)
			(xy 52.589234 -396.160759) (xy 52.526535 -396.212214) (xy 52.459095 -396.257276) (xy 52.387563 -396.295511)
			(xy 52.312627 -396.32655) (xy 52.235011 -396.350095) (xy 52.15546 -396.365918) (xy 52.074741 -396.373868)
			(xy 51.993631 -396.373868) (xy 51.912912 -396.365918) (xy 51.833361 -396.350095) (xy 51.755745 -396.32655)
			(xy 51.680809 -396.295511) (xy 51.609277 -396.257276) (xy 51.541837 -396.212214) (xy 51.479138 -396.160759)
			(xy 51.421785 -396.103406) (xy 51.37033 -396.040707) (xy 51.325268 -395.973267) (xy 51.287033 -395.901735)
			(xy 51.255994 -395.826799) (xy 51.232449 -395.749183) (xy 51.216626 -395.669632) (xy 51.208676 -395.588913)
			(xy 29.59608 -395.588913) (xy 29.59608 -397.924292) (xy 84.320633 -397.924292) (xy 84.326733 -397.868855)
			(xy 84.340839 -397.814898) (xy 84.362651 -397.763569) (xy 84.391705 -397.715963) (xy 84.42738 -397.673095)
			(xy 84.468917 -397.635878) (xy 84.51543 -397.605105) (xy 84.565927 -397.581433) (xy 84.619334 -397.565365)
			(xy 84.67451 -397.557245) (xy 84.702396 -397.556736) (xy 84.730282 -397.557245) (xy 84.785458 -397.565365)
			(xy 84.838865 -397.581433) (xy 84.889362 -397.605105) (xy 84.935875 -397.635878) (xy 84.977412 -397.673095)
			(xy 85.013087 -397.715963) (xy 85.042141 -397.763569) (xy 85.063953 -397.814898) (xy 85.078059 -397.868855)
			(xy 85.084159 -397.924292) (xy 85.082122 -397.980026) (xy 85.071992 -398.034869) (xy 85.053985 -398.087653)
			(xy 85.028484 -398.137253) (xy 84.996033 -398.182611) (xy 84.957324 -398.22276) (xy 84.913181 -398.256846)
			(xy 84.864546 -398.284142) (xy 84.812455 -398.304065) (xy 84.758018 -398.316191) (xy 84.702396 -398.320262)
			(xy 84.646774 -398.316191) (xy 84.592337 -398.304065) (xy 84.540246 -398.284142) (xy 84.491611 -398.256846)
			(xy 84.447468 -398.22276) (xy 84.408759 -398.182611) (xy 84.376308 -398.137253) (xy 84.350807 -398.087653)
			(xy 84.3328 -398.034869) (xy 84.32267 -397.980026) (xy 84.320633 -397.924292) (xy 29.59608 -397.924292)
			(xy 29.59608 -399.000744) (xy 81.843117 -399.000744) (xy 81.849217 -398.945307) (xy 81.863323 -398.89135)
			(xy 81.885135 -398.840021) (xy 81.914189 -398.792415) (xy 81.949864 -398.749547) (xy 81.991401 -398.71233)
			(xy 82.037914 -398.681557) (xy 82.088411 -398.657885) (xy 82.141818 -398.641817) (xy 82.196994 -398.633697)
			(xy 82.22488 -398.633188) (xy 82.252766 -398.633697) (xy 82.307942 -398.641817) (xy 82.361349 -398.657885)
			(xy 82.411846 -398.681557) (xy 82.458359 -398.71233) (xy 82.499896 -398.749547) (xy 82.535571 -398.792415)
			(xy 82.564625 -398.840021) (xy 82.586437 -398.89135) (xy 82.600543 -398.945307) (xy 82.606643 -399.000744)
			(xy 82.604606 -399.056478) (xy 82.594476 -399.111321) (xy 82.576469 -399.164105) (xy 82.550968 -399.213705)
			(xy 82.518881 -399.258554) (xy 83.285583 -399.258554) (xy 83.291683 -399.203117) (xy 83.305789 -399.14916)
			(xy 83.327601 -399.097831) (xy 83.356655 -399.050225) (xy 83.39233 -399.007357) (xy 83.433867 -398.97014)
			(xy 83.48038 -398.939367) (xy 83.530877 -398.915695) (xy 83.584284 -398.899627) (xy 83.63946 -398.891507)
			(xy 83.667346 -398.890998) (xy 83.695232 -398.891507) (xy 83.750408 -398.899627) (xy 83.803815 -398.915695)
			(xy 83.854312 -398.939367) (xy 83.900825 -398.97014) (xy 83.942362 -399.007357) (xy 83.978037 -399.050225)
			(xy 84.007091 -399.097831) (xy 84.028903 -399.14916) (xy 84.043009 -399.203117) (xy 84.049109 -399.258554)
			(xy 84.047072 -399.314288) (xy 84.036942 -399.369131) (xy 84.018935 -399.421915) (xy 83.993434 -399.471515)
			(xy 83.960983 -399.516873) (xy 83.922274 -399.557022) (xy 83.878131 -399.591108) (xy 83.829496 -399.618404)
			(xy 83.777405 -399.638327) (xy 83.722968 -399.650453) (xy 83.667346 -399.654524) (xy 83.611724 -399.650453)
			(xy 83.557287 -399.638327) (xy 83.505196 -399.618404) (xy 83.456561 -399.591108) (xy 83.412418 -399.557022)
			(xy 83.373709 -399.516873) (xy 83.341258 -399.471515) (xy 83.315757 -399.421915) (xy 83.29775 -399.369131)
			(xy 83.28762 -399.314288) (xy 83.285583 -399.258554) (xy 82.518881 -399.258554) (xy 82.518517 -399.259063)
			(xy 82.479808 -399.299212) (xy 82.435665 -399.333298) (xy 82.38703 -399.360594) (xy 82.334939 -399.380517)
			(xy 82.280502 -399.392643) (xy 82.22488 -399.396714) (xy 82.169258 -399.392643) (xy 82.114821 -399.380517)
			(xy 82.06273 -399.360594) (xy 82.014095 -399.333298) (xy 81.969952 -399.299212) (xy 81.931243 -399.259063)
			(xy 81.898792 -399.213705) (xy 81.873291 -399.164105) (xy 81.855284 -399.111321) (xy 81.845154 -399.056478)
			(xy 81.843117 -399.000744) (xy 29.59608 -399.000744) (xy 29.59608 -400.257282) (xy 78.885795 -400.257282)
			(xy 78.891895 -400.201845) (xy 78.906001 -400.147888) (xy 78.927813 -400.096559) (xy 78.956867 -400.048953)
			(xy 78.992542 -400.006085) (xy 79.034079 -399.968868) (xy 79.080592 -399.938095) (xy 79.131089 -399.914423)
			(xy 79.184496 -399.898355) (xy 79.239672 -399.890235) (xy 79.267558 -399.889726) (xy 79.295444 -399.890235)
			(xy 79.35062 -399.898355) (xy 79.404027 -399.914423) (xy 79.454524 -399.938095) (xy 79.501037 -399.968868)
			(xy 79.52839 -399.993376) (xy 80.197959 -399.993376) (xy 80.204059 -399.937939) (xy 80.218165 -399.883982)
			(xy 80.239977 -399.832653) (xy 80.269031 -399.785047) (xy 80.304706 -399.742179) (xy 80.346243 -399.704962)
			(xy 80.392756 -399.674189) (xy 80.443253 -399.650517) (xy 80.49666 -399.634449) (xy 80.551836 -399.626329)
			(xy 80.579722 -399.62582) (xy 80.607608 -399.626329) (xy 80.662784 -399.634449) (xy 80.716191 -399.650517)
			(xy 80.766688 -399.674189) (xy 80.813201 -399.704962) (xy 80.841688 -399.730486) (xy 84.952839 -399.730486)
			(xy 84.958939 -399.675049) (xy 84.973045 -399.621092) (xy 84.994857 -399.569763) (xy 85.023911 -399.522157)
			(xy 85.059586 -399.479289) (xy 85.101123 -399.442072) (xy 85.147636 -399.411299) (xy 85.198133 -399.387627)
			(xy 85.25154 -399.371559) (xy 85.306716 -399.363439) (xy 85.334602 -399.36293) (xy 85.362488 -399.363439)
			(xy 85.417664 -399.371559) (xy 85.471071 -399.387627) (xy 85.521568 -399.411299) (xy 85.568081 -399.442072)
			(xy 85.609618 -399.479289) (xy 85.645293 -399.522157) (xy 85.674347 -399.569763) (xy 85.696159 -399.621092)
			(xy 85.710265 -399.675049) (xy 85.716365 -399.730486) (xy 85.714328 -399.78622) (xy 85.704198 -399.841063)
			(xy 85.686191 -399.893847) (xy 85.66069 -399.943447) (xy 85.628239 -399.988805) (xy 85.58953 -400.028954)
			(xy 85.545387 -400.06304) (xy 85.496752 -400.090336) (xy 85.444661 -400.110259) (xy 85.390224 -400.122385)
			(xy 85.334602 -400.126456) (xy 85.27898 -400.122385) (xy 85.224543 -400.110259) (xy 85.172452 -400.090336)
			(xy 85.123817 -400.06304) (xy 85.079674 -400.028954) (xy 85.040965 -399.988805) (xy 85.008514 -399.943447)
			(xy 84.983013 -399.893847) (xy 84.965006 -399.841063) (xy 84.954876 -399.78622) (xy 84.952839 -399.730486)
			(xy 80.841688 -399.730486) (xy 80.854738 -399.742179) (xy 80.890413 -399.785047) (xy 80.919467 -399.832653)
			(xy 80.941279 -399.883982) (xy 80.955385 -399.937939) (xy 80.961485 -399.993376) (xy 80.959448 -400.04911)
			(xy 80.949318 -400.103953) (xy 80.931311 -400.156737) (xy 80.90581 -400.206337) (xy 80.873359 -400.251695)
			(xy 80.83465 -400.291844) (xy 80.790507 -400.32593) (xy 80.741872 -400.353226) (xy 80.689781 -400.373149)
			(xy 80.635344 -400.385275) (xy 80.579722 -400.389346) (xy 80.5241 -400.385275) (xy 80.469663 -400.373149)
			(xy 80.417572 -400.353226) (xy 80.368937 -400.32593) (xy 80.324794 -400.291844) (xy 80.286085 -400.251695)
			(xy 80.253634 -400.206337) (xy 80.228133 -400.156737) (xy 80.210126 -400.103953) (xy 80.199996 -400.04911)
			(xy 80.197959 -399.993376) (xy 79.52839 -399.993376) (xy 79.542574 -400.006085) (xy 79.578249 -400.048953)
			(xy 79.607303 -400.096559) (xy 79.629115 -400.147888) (xy 79.643221 -400.201845) (xy 79.649321 -400.257282)
			(xy 79.647284 -400.313016) (xy 79.637154 -400.367859) (xy 79.619147 -400.420643) (xy 79.593646 -400.470243)
			(xy 79.561195 -400.515601) (xy 79.522486 -400.55575) (xy 79.478343 -400.589836) (xy 79.429708 -400.617132)
			(xy 79.377617 -400.637055) (xy 79.32318 -400.649181) (xy 79.267558 -400.653252) (xy 79.211936 -400.649181)
			(xy 79.157499 -400.637055) (xy 79.105408 -400.617132) (xy 79.056773 -400.589836) (xy 79.01263 -400.55575)
			(xy 78.973921 -400.515601) (xy 78.94147 -400.470243) (xy 78.915969 -400.420643) (xy 78.897962 -400.367859)
			(xy 78.887832 -400.313016) (xy 78.885795 -400.257282) (xy 29.59608 -400.257282) (xy 29.59608 -406.931042)
			(xy 39.818314 -406.931042) (xy 39.824323 -406.815104) (xy 39.838316 -406.699857) (xy 39.860227 -406.585851)
			(xy 39.889952 -406.473627) (xy 39.927348 -406.363721) (xy 39.972237 -406.256658) (xy 40.024406 -406.152946)
			(xy 40.083606 -406.053081) (xy 40.149555 -405.957538) (xy 40.221938 -405.866772) (xy 40.300411 -405.781217)
			(xy 40.384599 -405.701279) (xy 40.474101 -405.62734) (xy 40.568492 -405.559752) (xy 40.66732 -405.498838)
			(xy 40.770116 -405.444886) (xy 40.876389 -405.398156) (xy 40.985633 -405.358868) (xy 41.097326 -405.327211)
			(xy 41.210938 -405.303335) (xy 41.325926 -405.287354) (xy 41.441743 -405.279345) (xy 41.49979 -405.278844)
			(xy 41.557837 -405.279345) (xy 41.673654 -405.287354) (xy 41.788642 -405.303335) (xy 41.902254 -405.327211)
			(xy 42.013947 -405.358868) (xy 42.123191 -405.398156) (xy 42.229464 -405.444886) (xy 42.33226 -405.498838)
			(xy 42.431088 -405.559752) (xy 42.474869 -405.591101) (xy 63.647829 -405.591101) (xy 63.653878 -405.515531)
			(xy 63.667925 -405.441033) (xy 63.689811 -405.36845) (xy 63.719288 -405.298604) (xy 63.756023 -405.232287)
			(xy 63.799598 -405.170251) (xy 63.84952 -405.113198) (xy 63.905224 -405.061774) (xy 63.966079 -405.016563)
			(xy 64.031394 -404.978076) (xy 64.10043 -404.94675) (xy 64.172405 -404.92294) (xy 64.246503 -404.906915)
			(xy 64.321884 -404.898856) (xy 64.35979 -404.898352) (xy 64.397696 -404.898856) (xy 64.473077 -404.906915)
			(xy 64.547175 -404.92294) (xy 64.61915 -404.94675) (xy 64.688186 -404.978076) (xy 64.753501 -405.016563)
			(xy 64.814356 -405.061774) (xy 64.87006 -405.113198) (xy 64.919982 -405.170251) (xy 64.963557 -405.232287)
			(xy 65.000292 -405.298604) (xy 65.029769 -405.36845) (xy 65.051655 -405.441033) (xy 65.065702 -405.515531)
			(xy 65.071751 -405.591101) (xy 66.187829 -405.591101) (xy 66.193878 -405.515531) (xy 66.207925 -405.441033)
			(xy 66.229811 -405.36845) (xy 66.259288 -405.298604) (xy 66.296023 -405.232287) (xy 66.339598 -405.170251)
			(xy 66.38952 -405.113198) (xy 66.445224 -405.061774) (xy 66.506079 -405.016563) (xy 66.571394 -404.978076)
			(xy 66.64043 -404.94675) (xy 66.712405 -404.92294) (xy 66.786503 -404.906915) (xy 66.861884 -404.898856)
			(xy 66.89979 -404.898352) (xy 66.937696 -404.898856) (xy 67.013077 -404.906915) (xy 67.087175 -404.92294)
			(xy 67.15915 -404.94675) (xy 67.228186 -404.978076) (xy 67.293501 -405.016563) (xy 67.354356 -405.061774)
			(xy 67.41006 -405.113198) (xy 67.459982 -405.170251) (xy 67.503557 -405.232287) (xy 67.540292 -405.298604)
			(xy 67.569769 -405.36845) (xy 67.591655 -405.441033) (xy 67.605702 -405.515531) (xy 67.611751 -405.591101)
			(xy 68.727829 -405.591101) (xy 68.733878 -405.515531) (xy 68.747925 -405.441033) (xy 68.769811 -405.36845)
			(xy 68.799288 -405.298604) (xy 68.836023 -405.232287) (xy 68.879598 -405.170251) (xy 68.92952 -405.113198)
			(xy 68.985224 -405.061774) (xy 69.046079 -405.016563) (xy 69.111394 -404.978076) (xy 69.18043 -404.94675)
			(xy 69.252405 -404.92294) (xy 69.326503 -404.906915) (xy 69.401884 -404.898856) (xy 69.43979 -404.898352)
			(xy 69.477696 -404.898856) (xy 69.553077 -404.906915) (xy 69.627175 -404.92294) (xy 69.69915 -404.94675)
			(xy 69.768186 -404.978076) (xy 69.833501 -405.016563) (xy 69.894356 -405.061774) (xy 69.95006 -405.113198)
			(xy 69.999982 -405.170251) (xy 70.043557 -405.232287) (xy 70.080292 -405.298604) (xy 70.109769 -405.36845)
			(xy 70.131655 -405.441033) (xy 70.145702 -405.515531) (xy 70.151751 -405.591101) (xy 71.267829 -405.591101)
			(xy 71.273878 -405.515531) (xy 71.287925 -405.441033) (xy 71.309811 -405.36845) (xy 71.339288 -405.298604)
			(xy 71.376023 -405.232287) (xy 71.419598 -405.170251) (xy 71.46952 -405.113198) (xy 71.525224 -405.061774)
			(xy 71.586079 -405.016563) (xy 71.651394 -404.978076) (xy 71.72043 -404.94675) (xy 71.792405 -404.92294)
			(xy 71.866503 -404.906915) (xy 71.941884 -404.898856) (xy 71.97979 -404.898352) (xy 72.017696 -404.898856)
			(xy 72.093077 -404.906915) (xy 72.167175 -404.92294) (xy 72.23915 -404.94675) (xy 72.308186 -404.978076)
			(xy 72.373501 -405.016563) (xy 72.434356 -405.061774) (xy 72.49006 -405.113198) (xy 72.539982 -405.170251)
			(xy 72.583557 -405.232287) (xy 72.620292 -405.298604) (xy 72.649769 -405.36845) (xy 72.671655 -405.441033)
			(xy 72.685702 -405.515531) (xy 72.691751 -405.591101) (xy 73.807829 -405.591101) (xy 73.813878 -405.515531)
			(xy 73.827925 -405.441033) (xy 73.849811 -405.36845) (xy 73.879288 -405.298604) (xy 73.916023 -405.232287)
			(xy 73.959598 -405.170251) (xy 74.00952 -405.113198) (xy 74.065224 -405.061774) (xy 74.126079 -405.016563)
			(xy 74.191394 -404.978076) (xy 74.26043 -404.94675) (xy 74.332405 -404.92294) (xy 74.406503 -404.906915)
			(xy 74.481884 -404.898856) (xy 74.51979 -404.898352) (xy 74.557696 -404.898856) (xy 74.633077 -404.906915)
			(xy 74.707175 -404.92294) (xy 74.77915 -404.94675) (xy 74.848186 -404.978076) (xy 74.913501 -405.016563)
			(xy 74.974356 -405.061774) (xy 75.03006 -405.113198) (xy 75.079982 -405.170251) (xy 75.123557 -405.232287)
			(xy 75.160292 -405.298604) (xy 75.189769 -405.36845) (xy 75.211655 -405.441033) (xy 75.225702 -405.515531)
			(xy 75.231751 -405.591101) (xy 76.347829 -405.591101) (xy 76.353878 -405.515531) (xy 76.367925 -405.441033)
			(xy 76.389811 -405.36845) (xy 76.419288 -405.298604) (xy 76.456023 -405.232287) (xy 76.499598 -405.170251)
			(xy 76.54952 -405.113198) (xy 76.605224 -405.061774) (xy 76.666079 -405.016563) (xy 76.731394 -404.978076)
			(xy 76.80043 -404.94675) (xy 76.872405 -404.92294) (xy 76.946503 -404.906915) (xy 77.021884 -404.898856)
			(xy 77.05979 -404.898352) (xy 77.097696 -404.898856) (xy 77.173077 -404.906915) (xy 77.247175 -404.92294)
			(xy 77.31915 -404.94675) (xy 77.388186 -404.978076) (xy 77.453501 -405.016563) (xy 77.514356 -405.061774)
			(xy 77.57006 -405.113198) (xy 77.619982 -405.170251) (xy 77.663557 -405.232287) (xy 77.700292 -405.298604)
			(xy 77.729769 -405.36845) (xy 77.751655 -405.441033) (xy 77.765702 -405.515531) (xy 77.771751 -405.591101)
			(xy 78.887829 -405.591101) (xy 78.893878 -405.515531) (xy 78.907925 -405.441033) (xy 78.929811 -405.36845)
			(xy 78.959288 -405.298604) (xy 78.996023 -405.232287) (xy 79.039598 -405.170251) (xy 79.08952 -405.113198)
			(xy 79.145224 -405.061774) (xy 79.206079 -405.016563) (xy 79.271394 -404.978076) (xy 79.34043 -404.94675)
			(xy 79.412405 -404.92294) (xy 79.486503 -404.906915) (xy 79.561884 -404.898856) (xy 79.59979 -404.898352)
			(xy 79.637696 -404.898856) (xy 79.713077 -404.906915) (xy 79.787175 -404.92294) (xy 79.85915 -404.94675)
			(xy 79.928186 -404.978076) (xy 79.993501 -405.016563) (xy 80.054356 -405.061774) (xy 80.11006 -405.113198)
			(xy 80.159982 -405.170251) (xy 80.203557 -405.232287) (xy 80.240292 -405.298604) (xy 80.269769 -405.36845)
			(xy 80.291655 -405.441033) (xy 80.305702 -405.515531) (xy 80.311751 -405.591101) (xy 81.427829 -405.591101)
			(xy 81.433878 -405.515531) (xy 81.447925 -405.441033) (xy 81.469811 -405.36845) (xy 81.499288 -405.298604)
			(xy 81.536023 -405.232287) (xy 81.579598 -405.170251) (xy 81.62952 -405.113198) (xy 81.685224 -405.061774)
			(xy 81.746079 -405.016563) (xy 81.811394 -404.978076) (xy 81.88043 -404.94675) (xy 81.952405 -404.92294)
			(xy 82.026503 -404.906915) (xy 82.101884 -404.898856) (xy 82.13979 -404.898352) (xy 82.177696 -404.898856)
			(xy 82.253077 -404.906915) (xy 82.327175 -404.92294) (xy 82.39915 -404.94675) (xy 82.468186 -404.978076)
			(xy 82.533501 -405.016563) (xy 82.594356 -405.061774) (xy 82.65006 -405.113198) (xy 82.699982 -405.170251)
			(xy 82.743557 -405.232287) (xy 82.780292 -405.298604) (xy 82.809769 -405.36845) (xy 82.831655 -405.441033)
			(xy 82.845702 -405.515531) (xy 82.851751 -405.591101) (xy 82.849732 -405.666885) (xy 82.83967 -405.742025)
			(xy 82.821678 -405.81567) (xy 82.79596 -405.886986) (xy 82.762808 -405.955163) (xy 82.722596 -406.019431)
			(xy 82.675781 -406.07906) (xy 82.622893 -406.133376) (xy 82.564531 -406.181762) (xy 82.501356 -406.22367)
			(xy 82.434085 -406.258626) (xy 82.36348 -406.286233) (xy 82.290339 -406.306179) (xy 82.215494 -406.318238)
			(xy 82.13979 -406.322273) (xy 82.064086 -406.318238) (xy 81.989241 -406.306179) (xy 81.9161 -406.286233)
			(xy 81.845495 -406.258626) (xy 81.778224 -406.22367) (xy 81.715049 -406.181762) (xy 81.656687 -406.133376)
			(xy 81.603799 -406.07906) (xy 81.556984 -406.019431) (xy 81.516772 -405.955163) (xy 81.48362 -405.886986)
			(xy 81.457902 -405.81567) (xy 81.43991 -405.742025) (xy 81.429848 -405.666885) (xy 81.427829 -405.591101)
			(xy 80.311751 -405.591101) (xy 80.309732 -405.666885) (xy 80.29967 -405.742025) (xy 80.281678 -405.81567)
			(xy 80.25596 -405.886986) (xy 80.222808 -405.955163) (xy 80.182596 -406.019431) (xy 80.135781 -406.07906)
			(xy 80.082893 -406.133376) (xy 80.024531 -406.181762) (xy 79.961356 -406.22367) (xy 79.894085 -406.258626)
			(xy 79.82348 -406.286233) (xy 79.750339 -406.306179) (xy 79.675494 -406.318238) (xy 79.59979 -406.322273)
			(xy 79.524086 -406.318238) (xy 79.449241 -406.306179) (xy 79.3761 -406.286233) (xy 79.305495 -406.258626)
			(xy 79.238224 -406.22367) (xy 79.175049 -406.181762) (xy 79.116687 -406.133376) (xy 79.063799 -406.07906)
			(xy 79.016984 -406.019431) (xy 78.976772 -405.955163) (xy 78.94362 -405.886986) (xy 78.917902 -405.81567)
			(xy 78.89991 -405.742025) (xy 78.889848 -405.666885) (xy 78.887829 -405.591101) (xy 77.771751 -405.591101)
			(xy 77.769732 -405.666885) (xy 77.75967 -405.742025) (xy 77.741678 -405.81567) (xy 77.71596 -405.886986)
			(xy 77.682808 -405.955163) (xy 77.642596 -406.019431) (xy 77.595781 -406.07906) (xy 77.542893 -406.133376)
			(xy 77.484531 -406.181762) (xy 77.421356 -406.22367) (xy 77.354085 -406.258626) (xy 77.28348 -406.286233)
			(xy 77.210339 -406.306179) (xy 77.135494 -406.318238) (xy 77.05979 -406.322273) (xy 76.984086 -406.318238)
			(xy 76.909241 -406.306179) (xy 76.8361 -406.286233) (xy 76.765495 -406.258626) (xy 76.698224 -406.22367)
			(xy 76.635049 -406.181762) (xy 76.576687 -406.133376) (xy 76.523799 -406.07906) (xy 76.476984 -406.019431)
			(xy 76.436772 -405.955163) (xy 76.40362 -405.886986) (xy 76.377902 -405.81567) (xy 76.35991 -405.742025)
			(xy 76.349848 -405.666885) (xy 76.347829 -405.591101) (xy 75.231751 -405.591101) (xy 75.229732 -405.666885)
			(xy 75.21967 -405.742025) (xy 75.201678 -405.81567) (xy 75.17596 -405.886986) (xy 75.142808 -405.955163)
			(xy 75.102596 -406.019431) (xy 75.055781 -406.07906) (xy 75.002893 -406.133376) (xy 74.944531 -406.181762)
			(xy 74.881356 -406.22367) (xy 74.814085 -406.258626) (xy 74.74348 -406.286233) (xy 74.670339 -406.306179)
			(xy 74.595494 -406.318238) (xy 74.51979 -406.322273) (xy 74.444086 -406.318238) (xy 74.369241 -406.306179)
			(xy 74.2961 -406.286233) (xy 74.225495 -406.258626) (xy 74.158224 -406.22367) (xy 74.095049 -406.181762)
			(xy 74.036687 -406.133376) (xy 73.983799 -406.07906) (xy 73.936984 -406.019431) (xy 73.896772 -405.955163)
			(xy 73.86362 -405.886986) (xy 73.837902 -405.81567) (xy 73.81991 -405.742025) (xy 73.809848 -405.666885)
			(xy 73.807829 -405.591101) (xy 72.691751 -405.591101) (xy 72.689732 -405.666885) (xy 72.67967 -405.742025)
			(xy 72.661678 -405.81567) (xy 72.63596 -405.886986) (xy 72.602808 -405.955163) (xy 72.562596 -406.019431)
			(xy 72.515781 -406.07906) (xy 72.462893 -406.133376) (xy 72.404531 -406.181762) (xy 72.341356 -406.22367)
			(xy 72.274085 -406.258626) (xy 72.20348 -406.286233) (xy 72.130339 -406.306179) (xy 72.055494 -406.318238)
			(xy 71.97979 -406.322273) (xy 71.904086 -406.318238) (xy 71.829241 -406.306179) (xy 71.7561 -406.286233)
			(xy 71.685495 -406.258626) (xy 71.618224 -406.22367) (xy 71.555049 -406.181762) (xy 71.496687 -406.133376)
			(xy 71.443799 -406.07906) (xy 71.396984 -406.019431) (xy 71.356772 -405.955163) (xy 71.32362 -405.886986)
			(xy 71.297902 -405.81567) (xy 71.27991 -405.742025) (xy 71.269848 -405.666885) (xy 71.267829 -405.591101)
			(xy 70.151751 -405.591101) (xy 70.149732 -405.666885) (xy 70.13967 -405.742025) (xy 70.121678 -405.81567)
			(xy 70.09596 -405.886986) (xy 70.062808 -405.955163) (xy 70.022596 -406.019431) (xy 69.975781 -406.07906)
			(xy 69.922893 -406.133376) (xy 69.864531 -406.181762) (xy 69.801356 -406.22367) (xy 69.734085 -406.258626)
			(xy 69.66348 -406.286233) (xy 69.590339 -406.306179) (xy 69.515494 -406.318238) (xy 69.43979 -406.322273)
			(xy 69.364086 -406.318238) (xy 69.289241 -406.306179) (xy 69.2161 -406.286233) (xy 69.145495 -406.258626)
			(xy 69.078224 -406.22367) (xy 69.015049 -406.181762) (xy 68.956687 -406.133376) (xy 68.903799 -406.07906)
			(xy 68.856984 -406.019431) (xy 68.816772 -405.955163) (xy 68.78362 -405.886986) (xy 68.757902 -405.81567)
			(xy 68.73991 -405.742025) (xy 68.729848 -405.666885) (xy 68.727829 -405.591101) (xy 67.611751 -405.591101)
			(xy 67.609732 -405.666885) (xy 67.59967 -405.742025) (xy 67.581678 -405.81567) (xy 67.55596 -405.886986)
			(xy 67.522808 -405.955163) (xy 67.482596 -406.019431) (xy 67.435781 -406.07906) (xy 67.382893 -406.133376)
			(xy 67.324531 -406.181762) (xy 67.261356 -406.22367) (xy 67.194085 -406.258626) (xy 67.12348 -406.286233)
			(xy 67.050339 -406.306179) (xy 66.975494 -406.318238) (xy 66.89979 -406.322273) (xy 66.824086 -406.318238)
			(xy 66.749241 -406.306179) (xy 66.6761 -406.286233) (xy 66.605495 -406.258626) (xy 66.538224 -406.22367)
			(xy 66.475049 -406.181762) (xy 66.416687 -406.133376) (xy 66.363799 -406.07906) (xy 66.316984 -406.019431)
			(xy 66.276772 -405.955163) (xy 66.24362 -405.886986) (xy 66.217902 -405.81567) (xy 66.19991 -405.742025)
			(xy 66.189848 -405.666885) (xy 66.187829 -405.591101) (xy 65.071751 -405.591101) (xy 65.069732 -405.666885)
			(xy 65.05967 -405.742025) (xy 65.041678 -405.81567) (xy 65.01596 -405.886986) (xy 64.982808 -405.955163)
			(xy 64.942596 -406.019431) (xy 64.895781 -406.07906) (xy 64.842893 -406.133376) (xy 64.784531 -406.181762)
			(xy 64.721356 -406.22367) (xy 64.654085 -406.258626) (xy 64.58348 -406.286233) (xy 64.510339 -406.306179)
			(xy 64.435494 -406.318238) (xy 64.35979 -406.322273) (xy 64.284086 -406.318238) (xy 64.209241 -406.306179)
			(xy 64.1361 -406.286233) (xy 64.065495 -406.258626) (xy 63.998224 -406.22367) (xy 63.935049 -406.181762)
			(xy 63.876687 -406.133376) (xy 63.823799 -406.07906) (xy 63.776984 -406.019431) (xy 63.736772 -405.955163)
			(xy 63.70362 -405.886986) (xy 63.677902 -405.81567) (xy 63.65991 -405.742025) (xy 63.649848 -405.666885)
			(xy 63.647829 -405.591101) (xy 42.474869 -405.591101) (xy 42.525479 -405.62734) (xy 42.614981 -405.701279)
			(xy 42.699169 -405.781217) (xy 42.777642 -405.866772) (xy 42.850025 -405.957538) (xy 42.915974 -406.053081)
			(xy 42.975174 -406.152946) (xy 43.027343 -406.256658) (xy 43.072232 -406.363721) (xy 43.109628 -406.473627)
			(xy 43.139353 -406.585851) (xy 43.161264 -406.699857) (xy 43.175257 -406.815104) (xy 43.181266 -406.931042)
			(xy 43.179263 -407.047118) (xy 43.169255 -407.16278) (xy 43.151292 -407.277475) (xy 43.125459 -407.390658)
			(xy 43.091879 -407.501789) (xy 43.050711 -407.610338) (xy 43.002153 -407.715788) (xy 42.946436 -407.817637)
			(xy 42.883824 -407.9154) (xy 42.814617 -408.00861) (xy 42.739144 -408.096823) (xy 42.657765 -408.179619)
			(xy 42.570868 -408.256603) (xy 42.526017 -408.291121) (xy 63.647829 -408.291121) (xy 63.653878 -408.215551)
			(xy 63.667925 -408.141053) (xy 63.689811 -408.06847) (xy 63.719288 -407.998624) (xy 63.756023 -407.932307)
			(xy 63.799598 -407.870271) (xy 63.84952 -407.813218) (xy 63.905224 -407.761794) (xy 63.966079 -407.716583)
			(xy 64.031394 -407.678096) (xy 64.10043 -407.64677) (xy 64.172405 -407.62296) (xy 64.246503 -407.606935)
			(xy 64.321884 -407.598876) (xy 64.35979 -407.598372) (xy 64.397696 -407.598876) (xy 64.473077 -407.606935)
			(xy 64.547175 -407.62296) (xy 64.61915 -407.64677) (xy 64.688186 -407.678096) (xy 64.753501 -407.716583)
			(xy 64.814356 -407.761794) (xy 64.87006 -407.813218) (xy 64.919982 -407.870271) (xy 64.963557 -407.932307)
			(xy 65.000292 -407.998624) (xy 65.029769 -408.06847) (xy 65.051655 -408.141053) (xy 65.065702 -408.215551)
			(xy 65.071751 -408.291121) (xy 66.187829 -408.291121) (xy 66.193878 -408.215551) (xy 66.207925 -408.141053)
			(xy 66.229811 -408.06847) (xy 66.259288 -407.998624) (xy 66.296023 -407.932307) (xy 66.339598 -407.870271)
			(xy 66.38952 -407.813218) (xy 66.445224 -407.761794) (xy 66.506079 -407.716583) (xy 66.571394 -407.678096)
			(xy 66.64043 -407.64677) (xy 66.712405 -407.62296) (xy 66.786503 -407.606935) (xy 66.861884 -407.598876)
			(xy 66.89979 -407.598372) (xy 66.937696 -407.598876) (xy 67.013077 -407.606935) (xy 67.087175 -407.62296)
			(xy 67.15915 -407.64677) (xy 67.228186 -407.678096) (xy 67.293501 -407.716583) (xy 67.354356 -407.761794)
			(xy 67.41006 -407.813218) (xy 67.459982 -407.870271) (xy 67.503557 -407.932307) (xy 67.540292 -407.998624)
			(xy 67.569769 -408.06847) (xy 67.591655 -408.141053) (xy 67.605702 -408.215551) (xy 67.611751 -408.291121)
			(xy 68.727829 -408.291121) (xy 68.733878 -408.215551) (xy 68.747925 -408.141053) (xy 68.769811 -408.06847)
			(xy 68.799288 -407.998624) (xy 68.836023 -407.932307) (xy 68.879598 -407.870271) (xy 68.92952 -407.813218)
			(xy 68.985224 -407.761794) (xy 69.046079 -407.716583) (xy 69.111394 -407.678096) (xy 69.18043 -407.64677)
			(xy 69.252405 -407.62296) (xy 69.326503 -407.606935) (xy 69.401884 -407.598876) (xy 69.43979 -407.598372)
			(xy 69.477696 -407.598876) (xy 69.553077 -407.606935) (xy 69.627175 -407.62296) (xy 69.69915 -407.64677)
			(xy 69.768186 -407.678096) (xy 69.833501 -407.716583) (xy 69.894356 -407.761794) (xy 69.95006 -407.813218)
			(xy 69.999982 -407.870271) (xy 70.043557 -407.932307) (xy 70.080292 -407.998624) (xy 70.109769 -408.06847)
			(xy 70.131655 -408.141053) (xy 70.145702 -408.215551) (xy 70.151751 -408.291121) (xy 71.267829 -408.291121)
			(xy 71.273878 -408.215551) (xy 71.287925 -408.141053) (xy 71.309811 -408.06847) (xy 71.339288 -407.998624)
			(xy 71.376023 -407.932307) (xy 71.419598 -407.870271) (xy 71.46952 -407.813218) (xy 71.525224 -407.761794)
			(xy 71.586079 -407.716583) (xy 71.651394 -407.678096) (xy 71.72043 -407.64677) (xy 71.792405 -407.62296)
			(xy 71.866503 -407.606935) (xy 71.941884 -407.598876) (xy 71.97979 -407.598372) (xy 72.017696 -407.598876)
			(xy 72.093077 -407.606935) (xy 72.167175 -407.62296) (xy 72.23915 -407.64677) (xy 72.308186 -407.678096)
			(xy 72.373501 -407.716583) (xy 72.434356 -407.761794) (xy 72.49006 -407.813218) (xy 72.539982 -407.870271)
			(xy 72.583557 -407.932307) (xy 72.620292 -407.998624) (xy 72.649769 -408.06847) (xy 72.671655 -408.141053)
			(xy 72.685702 -408.215551) (xy 72.691751 -408.291121) (xy 73.807829 -408.291121) (xy 73.813878 -408.215551)
			(xy 73.827925 -408.141053) (xy 73.849811 -408.06847) (xy 73.879288 -407.998624) (xy 73.916023 -407.932307)
			(xy 73.959598 -407.870271) (xy 74.00952 -407.813218) (xy 74.065224 -407.761794) (xy 74.126079 -407.716583)
			(xy 74.191394 -407.678096) (xy 74.26043 -407.64677) (xy 74.332405 -407.62296) (xy 74.406503 -407.606935)
			(xy 74.481884 -407.598876) (xy 74.51979 -407.598372) (xy 74.557696 -407.598876) (xy 74.633077 -407.606935)
			(xy 74.707175 -407.62296) (xy 74.77915 -407.64677) (xy 74.848186 -407.678096) (xy 74.913501 -407.716583)
			(xy 74.974356 -407.761794) (xy 75.03006 -407.813218) (xy 75.079982 -407.870271) (xy 75.123557 -407.932307)
			(xy 75.160292 -407.998624) (xy 75.189769 -408.06847) (xy 75.211655 -408.141053) (xy 75.225702 -408.215551)
			(xy 75.231751 -408.291121) (xy 76.347829 -408.291121) (xy 76.353878 -408.215551) (xy 76.367925 -408.141053)
			(xy 76.389811 -408.06847) (xy 76.419288 -407.998624) (xy 76.456023 -407.932307) (xy 76.499598 -407.870271)
			(xy 76.54952 -407.813218) (xy 76.605224 -407.761794) (xy 76.666079 -407.716583) (xy 76.731394 -407.678096)
			(xy 76.80043 -407.64677) (xy 76.872405 -407.62296) (xy 76.946503 -407.606935) (xy 77.021884 -407.598876)
			(xy 77.05979 -407.598372) (xy 77.097696 -407.598876) (xy 77.173077 -407.606935) (xy 77.247175 -407.62296)
			(xy 77.31915 -407.64677) (xy 77.388186 -407.678096) (xy 77.453501 -407.716583) (xy 77.514356 -407.761794)
			(xy 77.57006 -407.813218) (xy 77.619982 -407.870271) (xy 77.663557 -407.932307) (xy 77.700292 -407.998624)
			(xy 77.729769 -408.06847) (xy 77.751655 -408.141053) (xy 77.765702 -408.215551) (xy 77.771751 -408.291121)
			(xy 78.887829 -408.291121) (xy 78.893878 -408.215551) (xy 78.907925 -408.141053) (xy 78.929811 -408.06847)
			(xy 78.959288 -407.998624) (xy 78.996023 -407.932307) (xy 79.039598 -407.870271) (xy 79.08952 -407.813218)
			(xy 79.145224 -407.761794) (xy 79.206079 -407.716583) (xy 79.271394 -407.678096) (xy 79.34043 -407.64677)
			(xy 79.412405 -407.62296) (xy 79.486503 -407.606935) (xy 79.561884 -407.598876) (xy 79.59979 -407.598372)
			(xy 79.637696 -407.598876) (xy 79.713077 -407.606935) (xy 79.787175 -407.62296) (xy 79.85915 -407.64677)
			(xy 79.928186 -407.678096) (xy 79.993501 -407.716583) (xy 80.054356 -407.761794) (xy 80.11006 -407.813218)
			(xy 80.159982 -407.870271) (xy 80.203557 -407.932307) (xy 80.240292 -407.998624) (xy 80.269769 -408.06847)
			(xy 80.291655 -408.141053) (xy 80.305702 -408.215551) (xy 80.311751 -408.291121) (xy 81.427829 -408.291121)
			(xy 81.433878 -408.215551) (xy 81.447925 -408.141053) (xy 81.469811 -408.06847) (xy 81.499288 -407.998624)
			(xy 81.536023 -407.932307) (xy 81.579598 -407.870271) (xy 81.62952 -407.813218) (xy 81.685224 -407.761794)
			(xy 81.746079 -407.716583) (xy 81.811394 -407.678096) (xy 81.88043 -407.64677) (xy 81.952405 -407.62296)
			(xy 82.026503 -407.606935) (xy 82.101884 -407.598876) (xy 82.13979 -407.598372) (xy 82.177696 -407.598876)
			(xy 82.253077 -407.606935) (xy 82.327175 -407.62296) (xy 82.39915 -407.64677) (xy 82.468186 -407.678096)
			(xy 82.533501 -407.716583) (xy 82.594356 -407.761794) (xy 82.65006 -407.813218) (xy 82.699982 -407.870271)
			(xy 82.743557 -407.932307) (xy 82.780292 -407.998624) (xy 82.809769 -408.06847) (xy 82.831655 -408.141053)
			(xy 82.845702 -408.215551) (xy 82.851751 -408.291121) (xy 82.849732 -408.366905) (xy 82.83967 -408.442045)
			(xy 82.821678 -408.51569) (xy 82.79596 -408.587006) (xy 82.762808 -408.655183) (xy 82.722596 -408.719451)
			(xy 82.675781 -408.77908) (xy 82.622893 -408.833396) (xy 82.564531 -408.881782) (xy 82.501356 -408.92369)
			(xy 82.434085 -408.958646) (xy 82.36348 -408.986253) (xy 82.290339 -409.006199) (xy 82.215494 -409.018258)
			(xy 82.13979 -409.022293) (xy 82.064086 -409.018258) (xy 81.989241 -409.006199) (xy 81.9161 -408.986253)
			(xy 81.845495 -408.958646) (xy 81.778224 -408.92369) (xy 81.715049 -408.881782) (xy 81.656687 -408.833396)
			(xy 81.603799 -408.77908) (xy 81.556984 -408.719451) (xy 81.516772 -408.655183) (xy 81.48362 -408.587006)
			(xy 81.457902 -408.51569) (xy 81.43991 -408.442045) (xy 81.429848 -408.366905) (xy 81.427829 -408.291121)
			(xy 80.311751 -408.291121) (xy 80.309732 -408.366905) (xy 80.29967 -408.442045) (xy 80.281678 -408.51569)
			(xy 80.25596 -408.587006) (xy 80.222808 -408.655183) (xy 80.182596 -408.719451) (xy 80.135781 -408.77908)
			(xy 80.082893 -408.833396) (xy 80.024531 -408.881782) (xy 79.961356 -408.92369) (xy 79.894085 -408.958646)
			(xy 79.82348 -408.986253) (xy 79.750339 -409.006199) (xy 79.675494 -409.018258) (xy 79.59979 -409.022293)
			(xy 79.524086 -409.018258) (xy 79.449241 -409.006199) (xy 79.3761 -408.986253) (xy 79.305495 -408.958646)
			(xy 79.238224 -408.92369) (xy 79.175049 -408.881782) (xy 79.116687 -408.833396) (xy 79.063799 -408.77908)
			(xy 79.016984 -408.719451) (xy 78.976772 -408.655183) (xy 78.94362 -408.587006) (xy 78.917902 -408.51569)
			(xy 78.89991 -408.442045) (xy 78.889848 -408.366905) (xy 78.887829 -408.291121) (xy 77.771751 -408.291121)
			(xy 77.769732 -408.366905) (xy 77.75967 -408.442045) (xy 77.741678 -408.51569) (xy 77.71596 -408.587006)
			(xy 77.682808 -408.655183) (xy 77.642596 -408.719451) (xy 77.595781 -408.77908) (xy 77.542893 -408.833396)
			(xy 77.484531 -408.881782) (xy 77.421356 -408.92369) (xy 77.354085 -408.958646) (xy 77.28348 -408.986253)
			(xy 77.210339 -409.006199) (xy 77.135494 -409.018258) (xy 77.05979 -409.022293) (xy 76.984086 -409.018258)
			(xy 76.909241 -409.006199) (xy 76.8361 -408.986253) (xy 76.765495 -408.958646) (xy 76.698224 -408.92369)
			(xy 76.635049 -408.881782) (xy 76.576687 -408.833396) (xy 76.523799 -408.77908) (xy 76.476984 -408.719451)
			(xy 76.436772 -408.655183) (xy 76.40362 -408.587006) (xy 76.377902 -408.51569) (xy 76.35991 -408.442045)
			(xy 76.349848 -408.366905) (xy 76.347829 -408.291121) (xy 75.231751 -408.291121) (xy 75.229732 -408.366905)
			(xy 75.21967 -408.442045) (xy 75.201678 -408.51569) (xy 75.17596 -408.587006) (xy 75.142808 -408.655183)
			(xy 75.102596 -408.719451) (xy 75.055781 -408.77908) (xy 75.002893 -408.833396) (xy 74.944531 -408.881782)
			(xy 74.881356 -408.92369) (xy 74.814085 -408.958646) (xy 74.74348 -408.986253) (xy 74.670339 -409.006199)
			(xy 74.595494 -409.018258) (xy 74.51979 -409.022293) (xy 74.444086 -409.018258) (xy 74.369241 -409.006199)
			(xy 74.2961 -408.986253) (xy 74.225495 -408.958646) (xy 74.158224 -408.92369) (xy 74.095049 -408.881782)
			(xy 74.036687 -408.833396) (xy 73.983799 -408.77908) (xy 73.936984 -408.719451) (xy 73.896772 -408.655183)
			(xy 73.86362 -408.587006) (xy 73.837902 -408.51569) (xy 73.81991 -408.442045) (xy 73.809848 -408.366905)
			(xy 73.807829 -408.291121) (xy 72.691751 -408.291121) (xy 72.689732 -408.366905) (xy 72.67967 -408.442045)
			(xy 72.661678 -408.51569) (xy 72.63596 -408.587006) (xy 72.602808 -408.655183) (xy 72.562596 -408.719451)
			(xy 72.515781 -408.77908) (xy 72.462893 -408.833396) (xy 72.404531 -408.881782) (xy 72.341356 -408.92369)
			(xy 72.274085 -408.958646) (xy 72.20348 -408.986253) (xy 72.130339 -409.006199) (xy 72.055494 -409.018258)
			(xy 71.97979 -409.022293) (xy 71.904086 -409.018258) (xy 71.829241 -409.006199) (xy 71.7561 -408.986253)
			(xy 71.685495 -408.958646) (xy 71.618224 -408.92369) (xy 71.555049 -408.881782) (xy 71.496687 -408.833396)
			(xy 71.443799 -408.77908) (xy 71.396984 -408.719451) (xy 71.356772 -408.655183) (xy 71.32362 -408.587006)
			(xy 71.297902 -408.51569) (xy 71.27991 -408.442045) (xy 71.269848 -408.366905) (xy 71.267829 -408.291121)
			(xy 70.151751 -408.291121) (xy 70.149732 -408.366905) (xy 70.13967 -408.442045) (xy 70.121678 -408.51569)
			(xy 70.09596 -408.587006) (xy 70.062808 -408.655183) (xy 70.022596 -408.719451) (xy 69.975781 -408.77908)
			(xy 69.922893 -408.833396) (xy 69.864531 -408.881782) (xy 69.801356 -408.92369) (xy 69.734085 -408.958646)
			(xy 69.66348 -408.986253) (xy 69.590339 -409.006199) (xy 69.515494 -409.018258) (xy 69.43979 -409.022293)
			(xy 69.364086 -409.018258) (xy 69.289241 -409.006199) (xy 69.2161 -408.986253) (xy 69.145495 -408.958646)
			(xy 69.078224 -408.92369) (xy 69.015049 -408.881782) (xy 68.956687 -408.833396) (xy 68.903799 -408.77908)
			(xy 68.856984 -408.719451) (xy 68.816772 -408.655183) (xy 68.78362 -408.587006) (xy 68.757902 -408.51569)
			(xy 68.73991 -408.442045) (xy 68.729848 -408.366905) (xy 68.727829 -408.291121) (xy 67.611751 -408.291121)
			(xy 67.609732 -408.366905) (xy 67.59967 -408.442045) (xy 67.581678 -408.51569) (xy 67.55596 -408.587006)
			(xy 67.522808 -408.655183) (xy 67.482596 -408.719451) (xy 67.435781 -408.77908) (xy 67.382893 -408.833396)
			(xy 67.324531 -408.881782) (xy 67.261356 -408.92369) (xy 67.194085 -408.958646) (xy 67.12348 -408.986253)
			(xy 67.050339 -409.006199) (xy 66.975494 -409.018258) (xy 66.89979 -409.022293) (xy 66.824086 -409.018258)
			(xy 66.749241 -409.006199) (xy 66.6761 -408.986253) (xy 66.605495 -408.958646) (xy 66.538224 -408.92369)
			(xy 66.475049 -408.881782) (xy 66.416687 -408.833396) (xy 66.363799 -408.77908) (xy 66.316984 -408.719451)
			(xy 66.276772 -408.655183) (xy 66.24362 -408.587006) (xy 66.217902 -408.51569) (xy 66.19991 -408.442045)
			(xy 66.189848 -408.366905) (xy 66.187829 -408.291121) (xy 65.071751 -408.291121) (xy 65.069732 -408.366905)
			(xy 65.05967 -408.442045) (xy 65.041678 -408.51569) (xy 65.01596 -408.587006) (xy 64.982808 -408.655183)
			(xy 64.942596 -408.719451) (xy 64.895781 -408.77908) (xy 64.842893 -408.833396) (xy 64.784531 -408.881782)
			(xy 64.721356 -408.92369) (xy 64.654085 -408.958646) (xy 64.58348 -408.986253) (xy 64.510339 -409.006199)
			(xy 64.435494 -409.018258) (xy 64.35979 -409.022293) (xy 64.284086 -409.018258) (xy 64.209241 -409.006199)
			(xy 64.1361 -408.986253) (xy 64.065495 -408.958646) (xy 63.998224 -408.92369) (xy 63.935049 -408.881782)
			(xy 63.876687 -408.833396) (xy 63.823799 -408.77908) (xy 63.776984 -408.719451) (xy 63.736772 -408.655183)
			(xy 63.70362 -408.587006) (xy 63.677902 -408.51569) (xy 63.65991 -408.442045) (xy 63.649848 -408.366905)
			(xy 63.647829 -408.291121) (xy 42.526017 -408.291121) (xy 42.478867 -408.327408) (xy 42.3822 -408.391698)
			(xy 42.281328 -408.449165) (xy 42.176731 -408.499536) (xy 42.068908 -408.542571) (xy 41.958374 -408.578065)
			(xy 41.845654 -408.605848) (xy 41.731286 -408.625788) (xy 41.615814 -408.63779) (xy 41.49979 -408.641797)
			(xy 41.383766 -408.63779) (xy 41.268294 -408.625788) (xy 41.153926 -408.605848) (xy 41.041206 -408.578065)
			(xy 40.930672 -408.542571) (xy 40.822849 -408.499536) (xy 40.718252 -408.449165) (xy 40.61738 -408.391698)
			(xy 40.520713 -408.327408) (xy 40.428712 -408.256603) (xy 40.341815 -408.179619) (xy 40.260436 -408.096823)
			(xy 40.184963 -408.00861) (xy 40.115756 -407.9154) (xy 40.053144 -407.817637) (xy 39.997427 -407.715788)
			(xy 39.948869 -407.610338) (xy 39.907701 -407.501789) (xy 39.874121 -407.390658) (xy 39.848288 -407.277475)
			(xy 39.830325 -407.16278) (xy 39.820317 -407.047118) (xy 39.818314 -406.931042) (xy 29.59608 -406.931042)
			(xy 29.59608 -407.962862) (xy 29.596592 -407.985182) (xy 29.604369 -408.029138) (xy 29.619706 -408.071059)
			(xy 29.642133 -408.109655) (xy 29.670959 -408.143739) (xy 29.705297 -408.172261) (xy 29.744091 -408.194344)
			(xy 29.786147 -408.209309) (xy 29.83017 -408.216695) (xy 29.874807 -408.216274) (xy 29.918684 -408.20806)
			(xy 29.96045 -408.192306) (xy 29.979874 -408.181302) (xy 30.017126 -408.159686) (xy 30.094912 -408.122692)
			(xy 30.175756 -408.092967) (xy 30.258979 -408.070759) (xy 30.343884 -408.056255) (xy 30.429759 -408.049577)
			(xy 30.515886 -408.050779) (xy 30.601542 -408.059853) (xy 30.686009 -408.076722) (xy 30.768579 -408.101244)
			(xy 30.848561 -408.133215) (xy 30.925284 -408.172366) (xy 30.998105 -408.21837) (xy 31.066414 -408.27084)
			(xy 31.129638 -408.329337) (xy 31.187248 -408.393371) (xy 31.238761 -408.462405) (xy 31.283745 -408.53586)
			(xy 31.321823 -408.613121) (xy 31.352675 -408.693541) (xy 31.376044 -408.776445) (xy 31.391734 -408.861139)
			(xy 31.399613 -408.946913) (xy 31.399615 -409.033048) (xy 31.399575 -409.033488) (xy 34.599874 -409.033488)
			(xy 34.599874 -408.946588) (xy 34.607892 -408.860059) (xy 34.62386 -408.774639) (xy 34.647641 -408.691057)
			(xy 34.679033 -408.610025) (xy 34.717767 -408.532236) (xy 34.763514 -408.458352) (xy 34.815883 -408.389005)
			(xy 34.874427 -408.324785) (xy 34.938647 -408.266241) (xy 35.007994 -408.213872) (xy 35.081878 -408.168125)
			(xy 35.159667 -408.129391) (xy 35.240699 -408.097999) (xy 35.324281 -408.074218) (xy 35.409701 -408.05825)
			(xy 35.49623 -408.050232) (xy 35.53968 -408.04973) (xy 35.58313 -408.050232) (xy 35.669659 -408.05825)
			(xy 35.755079 -408.074218) (xy 35.838661 -408.097999) (xy 35.919693 -408.129391) (xy 35.997482 -408.168125)
			(xy 36.071366 -408.213872) (xy 36.140713 -408.266241) (xy 36.204933 -408.324785) (xy 36.263477 -408.389005)
			(xy 36.315846 -408.458352) (xy 36.361593 -408.532236) (xy 36.400327 -408.610025) (xy 36.431719 -408.691057)
			(xy 36.4555 -408.774639) (xy 36.471468 -408.860059) (xy 36.479486 -408.946588) (xy 36.479486 -409.033488)
			(xy 36.471468 -409.120017) (xy 36.4555 -409.205437) (xy 36.431719 -409.289019) (xy 36.400327 -409.370051)
			(xy 36.361593 -409.44784) (xy 36.315846 -409.521724) (xy 36.263477 -409.591071) (xy 36.204933 -409.655291)
			(xy 36.140713 -409.713835) (xy 36.071366 -409.766204) (xy 35.997482 -409.811951) (xy 35.919693 -409.850685)
			(xy 35.838661 -409.882077) (xy 35.755079 -409.905858) (xy 35.669659 -409.921826) (xy 35.58313 -409.929844)
			(xy 35.49623 -409.929844) (xy 35.409701 -409.921826) (xy 35.324281 -409.905858) (xy 35.240699 -409.882077)
			(xy 35.159667 -409.850685) (xy 35.081878 -409.811951) (xy 35.007994 -409.766204) (xy 34.938647 -409.713835)
			(xy 34.874427 -409.655291) (xy 34.815883 -409.591071) (xy 34.763514 -409.521724) (xy 34.717767 -409.44784)
			(xy 34.679033 -409.370051) (xy 34.647641 -409.289019) (xy 34.62386 -409.205437) (xy 34.607892 -409.120017)
			(xy 34.599874 -409.033488) (xy 31.399575 -409.033488) (xy 31.391739 -409.118822) (xy 31.376053 -409.203517)
			(xy 31.352688 -409.286422) (xy 31.321838 -409.366843) (xy 31.283763 -409.444106) (xy 31.238783 -409.517563)
			(xy 31.187273 -409.586599) (xy 31.129665 -409.650635) (xy 31.066443 -409.709135) (xy 30.998137 -409.761608)
			(xy 30.925317 -409.807614) (xy 30.848596 -409.846769) (xy 30.768616 -409.878743) (xy 30.686046 -409.903269)
			(xy 30.60158 -409.920141) (xy 30.515925 -409.929219) (xy 30.429798 -409.930425) (xy 30.343922 -409.92375)
			(xy 30.259017 -409.909249) (xy 30.175793 -409.887045) (xy 30.094948 -409.857323) (xy 30.017161 -409.820332)
			(xy 29.979874 -409.798774) (xy 29.960453 -409.787773) (xy 29.918684 -409.772049) (xy 29.874811 -409.763859)
			(xy 29.830181 -409.763455) (xy 29.786167 -409.770849) (xy 29.74412 -409.785815) (xy 29.705332 -409.807893)
			(xy 29.670994 -409.836404) (xy 29.642162 -409.870472) (xy 29.619721 -409.909051) (xy 29.604361 -409.950956)
			(xy 29.596554 -409.994899) (xy 29.59608 -410.017214) (xy 29.59608 -410.502862) (xy 29.596592 -410.525182)
			(xy 29.604369 -410.569138) (xy 29.619706 -410.611059) (xy 29.642133 -410.649655) (xy 29.670959 -410.683739)
			(xy 29.705297 -410.712261) (xy 29.744091 -410.734344) (xy 29.786147 -410.749309) (xy 29.83017 -410.756695)
			(xy 29.874807 -410.756274) (xy 29.918684 -410.74806) (xy 29.96045 -410.732306) (xy 29.979874 -410.721302)
			(xy 30.017126 -410.699686) (xy 30.094912 -410.662692) (xy 30.175756 -410.632967) (xy 30.258979 -410.610759)
			(xy 30.343884 -410.596255) (xy 30.429759 -410.589577) (xy 30.515886 -410.590779) (xy 30.601542 -410.599853)
			(xy 30.686009 -410.616722) (xy 30.768579 -410.641244) (xy 30.848561 -410.673215) (xy 30.925284 -410.712366)
			(xy 30.998105 -410.75837) (xy 31.066414 -410.81084) (xy 31.129638 -410.869337) (xy 31.187248 -410.933371)
			(xy 31.238761 -411.002405) (xy 31.283745 -411.07586) (xy 31.321823 -411.153121) (xy 31.352675 -411.233541)
			(xy 31.376044 -411.316445) (xy 31.391734 -411.401139) (xy 31.399613 -411.486913) (xy 31.399615 -411.573048)
			(xy 31.399575 -411.573488) (xy 34.599874 -411.573488) (xy 34.599874 -411.486588) (xy 34.607892 -411.400059)
			(xy 34.62386 -411.314639) (xy 34.647641 -411.231057) (xy 34.679033 -411.150025) (xy 34.717767 -411.072236)
			(xy 34.763514 -410.998352) (xy 34.815883 -410.929005) (xy 34.874427 -410.864785) (xy 34.938647 -410.806241)
			(xy 35.007994 -410.753872) (xy 35.081878 -410.708125) (xy 35.159667 -410.669391) (xy 35.240699 -410.637999)
			(xy 35.324281 -410.614218) (xy 35.409701 -410.59825) (xy 35.49623 -410.590232) (xy 35.53968 -410.58973)
			(xy 35.58313 -410.590232) (xy 35.669659 -410.59825) (xy 35.755079 -410.614218) (xy 35.838661 -410.637999)
			(xy 35.919693 -410.669391) (xy 35.997482 -410.708125) (xy 36.071366 -410.753872) (xy 36.140713 -410.806241)
			(xy 36.204933 -410.864785) (xy 36.263477 -410.929005) (xy 36.315846 -410.998352) (xy 36.361593 -411.072236)
			(xy 36.400327 -411.150025) (xy 36.431719 -411.231057) (xy 36.4555 -411.314639) (xy 36.471468 -411.400059)
			(xy 36.479486 -411.486588) (xy 36.479486 -411.573488) (xy 36.471468 -411.660017) (xy 36.4555 -411.745437)
			(xy 36.431719 -411.829019) (xy 36.400327 -411.910051) (xy 36.366143 -411.978703) (xy 65.802248 -411.978703)
			(xy 65.802248 -411.907381) (xy 65.810234 -411.836507) (xy 65.826104 -411.766972) (xy 65.849661 -411.699652)
			(xy 65.880606 -411.635393) (xy 65.918552 -411.575002) (xy 65.963021 -411.51924) (xy 66.013454 -411.468807)
			(xy 66.069216 -411.424338) (xy 66.129607 -411.386392) (xy 66.193866 -411.355447) (xy 66.261186 -411.33189)
			(xy 66.330721 -411.31602) (xy 66.401595 -411.308034) (xy 66.437256 -411.307534) (xy 66.472917 -411.308034)
			(xy 66.543791 -411.31602) (xy 66.613326 -411.33189) (xy 66.680646 -411.355447) (xy 66.744905 -411.386392)
			(xy 66.805296 -411.424338) (xy 66.861058 -411.468807) (xy 66.911491 -411.51924) (xy 66.95596 -411.575002)
			(xy 66.993906 -411.635393) (xy 67.024851 -411.699652) (xy 67.048408 -411.766972) (xy 67.064278 -411.836507)
			(xy 67.072264 -411.907381) (xy 67.072264 -411.978703) (xy 68.79386 -411.978703) (xy 68.79386 -411.907381)
			(xy 68.801846 -411.836507) (xy 68.817716 -411.766972) (xy 68.841273 -411.699652) (xy 68.872218 -411.635393)
			(xy 68.910164 -411.575002) (xy 68.954633 -411.51924) (xy 69.005066 -411.468807) (xy 69.060828 -411.424338)
			(xy 69.121219 -411.386392) (xy 69.185478 -411.355447) (xy 69.252798 -411.33189) (xy 69.322333 -411.31602)
			(xy 69.393207 -411.308034) (xy 69.428868 -411.307534) (xy 69.464529 -411.308034) (xy 69.535403 -411.31602)
			(xy 69.604938 -411.33189) (xy 69.672258 -411.355447) (xy 69.736517 -411.386392) (xy 69.796908 -411.424338)
			(xy 69.85267 -411.468807) (xy 69.903103 -411.51924) (xy 69.947572 -411.575002) (xy 69.985518 -411.635393)
			(xy 70.016463 -411.699652) (xy 70.04002 -411.766972) (xy 70.05589 -411.836507) (xy 70.063876 -411.907381)
			(xy 70.063876 -411.978703) (xy 70.05589 -412.049577) (xy 70.04002 -412.119112) (xy 70.016463 -412.186432)
			(xy 69.985518 -412.250691) (xy 69.947572 -412.311082) (xy 69.903103 -412.366844) (xy 69.85267 -412.417277)
			(xy 69.796908 -412.461746) (xy 69.736517 -412.499692) (xy 69.672258 -412.530637) (xy 69.604938 -412.554194)
			(xy 69.535403 -412.570064) (xy 69.464529 -412.57805) (xy 69.393207 -412.57805) (xy 69.322333 -412.570064)
			(xy 69.252798 -412.554194) (xy 69.185478 -412.530637) (xy 69.121219 -412.499692) (xy 69.060828 -412.461746)
			(xy 69.005066 -412.417277) (xy 68.954633 -412.366844) (xy 68.910164 -412.311082) (xy 68.872218 -412.250691)
			(xy 68.841273 -412.186432) (xy 68.817716 -412.119112) (xy 68.801846 -412.049577) (xy 68.79386 -411.978703)
			(xy 67.072264 -411.978703) (xy 67.064278 -412.049577) (xy 67.048408 -412.119112) (xy 67.024851 -412.186432)
			(xy 66.993906 -412.250691) (xy 66.95596 -412.311082) (xy 66.911491 -412.366844) (xy 66.861058 -412.417277)
			(xy 66.805296 -412.461746) (xy 66.744905 -412.499692) (xy 66.680646 -412.530637) (xy 66.613326 -412.554194)
			(xy 66.543791 -412.570064) (xy 66.472917 -412.57805) (xy 66.401595 -412.57805) (xy 66.330721 -412.570064)
			(xy 66.261186 -412.554194) (xy 66.193866 -412.530637) (xy 66.129607 -412.499692) (xy 66.069216 -412.461746)
			(xy 66.013454 -412.417277) (xy 65.963021 -412.366844) (xy 65.918552 -412.311082) (xy 65.880606 -412.250691)
			(xy 65.849661 -412.186432) (xy 65.826104 -412.119112) (xy 65.810234 -412.049577) (xy 65.802248 -411.978703)
			(xy 36.366143 -411.978703) (xy 36.361593 -411.98784) (xy 36.315846 -412.061724) (xy 36.263477 -412.131071)
			(xy 36.204933 -412.195291) (xy 36.140713 -412.253835) (xy 36.071366 -412.306204) (xy 35.997482 -412.351951)
			(xy 35.919693 -412.390685) (xy 35.838661 -412.422077) (xy 35.755079 -412.445858) (xy 35.669659 -412.461826)
			(xy 35.58313 -412.469844) (xy 35.49623 -412.469844) (xy 35.409701 -412.461826) (xy 35.324281 -412.445858)
			(xy 35.240699 -412.422077) (xy 35.159667 -412.390685) (xy 35.081878 -412.351951) (xy 35.007994 -412.306204)
			(xy 34.938647 -412.253835) (xy 34.874427 -412.195291) (xy 34.815883 -412.131071) (xy 34.763514 -412.061724)
			(xy 34.717767 -411.98784) (xy 34.679033 -411.910051) (xy 34.647641 -411.829019) (xy 34.62386 -411.745437)
			(xy 34.607892 -411.660017) (xy 34.599874 -411.573488) (xy 31.399575 -411.573488) (xy 31.391739 -411.658822)
			(xy 31.376053 -411.743517) (xy 31.352688 -411.826422) (xy 31.321838 -411.906843) (xy 31.283763 -411.984106)
			(xy 31.238783 -412.057563) (xy 31.187273 -412.126599) (xy 31.129665 -412.190635) (xy 31.066443 -412.249135)
			(xy 30.998137 -412.301608) (xy 30.925317 -412.347614) (xy 30.848596 -412.386769) (xy 30.768616 -412.418743)
			(xy 30.686046 -412.443269) (xy 30.60158 -412.460141) (xy 30.515925 -412.469219) (xy 30.429798 -412.470425)
			(xy 30.343922 -412.46375) (xy 30.259017 -412.449249) (xy 30.175793 -412.427045) (xy 30.094948 -412.397323)
			(xy 30.017161 -412.360332) (xy 29.979874 -412.338774) (xy 29.960453 -412.327773) (xy 29.918684 -412.312049)
			(xy 29.874811 -412.303859) (xy 29.830181 -412.303455) (xy 29.786167 -412.310849) (xy 29.74412 -412.325815)
			(xy 29.705332 -412.347893) (xy 29.670994 -412.376404) (xy 29.642162 -412.410472) (xy 29.619721 -412.449051)
			(xy 29.604361 -412.490956) (xy 29.596554 -412.534899) (xy 29.59608 -412.557214) (xy 29.59608 -413.042862)
			(xy 29.596592 -413.065182) (xy 29.604369 -413.109138) (xy 29.619706 -413.151059) (xy 29.642133 -413.189655)
			(xy 29.670959 -413.223739) (xy 29.705297 -413.252261) (xy 29.744091 -413.274344) (xy 29.786147 -413.289309)
			(xy 29.83017 -413.296695) (xy 29.874807 -413.296274) (xy 29.918684 -413.28806) (xy 29.96045 -413.272306)
			(xy 29.979874 -413.261302) (xy 30.017126 -413.239686) (xy 30.094912 -413.202692) (xy 30.175756 -413.172967)
			(xy 30.258979 -413.150759) (xy 30.343884 -413.136255) (xy 30.429759 -413.129577) (xy 30.515886 -413.130779)
			(xy 30.601542 -413.139853) (xy 30.686009 -413.156722) (xy 30.768579 -413.181244) (xy 30.848561 -413.213215)
			(xy 30.925284 -413.252366) (xy 30.998105 -413.29837) (xy 31.066414 -413.35084) (xy 31.129638 -413.409337)
			(xy 31.187248 -413.473371) (xy 31.238761 -413.542405) (xy 31.283745 -413.61586) (xy 31.321823 -413.693121)
			(xy 31.352675 -413.773541) (xy 31.376044 -413.856445) (xy 31.391734 -413.941139) (xy 31.399613 -414.026913)
			(xy 31.399615 -414.113048) (xy 31.399575 -414.113488) (xy 34.599874 -414.113488) (xy 34.599874 -414.026588)
			(xy 34.607892 -413.940059) (xy 34.62386 -413.854639) (xy 34.647641 -413.771057) (xy 34.679033 -413.690025)
			(xy 34.717767 -413.612236) (xy 34.763514 -413.538352) (xy 34.815883 -413.469005) (xy 34.874427 -413.404785)
			(xy 34.938647 -413.346241) (xy 35.007994 -413.293872) (xy 35.081878 -413.248125) (xy 35.159667 -413.209391)
			(xy 35.240699 -413.177999) (xy 35.324281 -413.154218) (xy 35.409701 -413.13825) (xy 35.49623 -413.130232)
			(xy 35.53968 -413.12973) (xy 35.58313 -413.130232) (xy 35.669659 -413.13825) (xy 35.755079 -413.154218)
			(xy 35.838661 -413.177999) (xy 35.919693 -413.209391) (xy 35.997482 -413.248125) (xy 36.071366 -413.293872)
			(xy 36.140713 -413.346241) (xy 36.204933 -413.404785) (xy 36.263477 -413.469005) (xy 36.315846 -413.538352)
			(xy 36.361593 -413.612236) (xy 36.400327 -413.690025) (xy 36.431719 -413.771057) (xy 36.4555 -413.854639)
			(xy 36.471468 -413.940059) (xy 36.479486 -414.026588) (xy 36.479486 -414.113488) (xy 36.471468 -414.200017)
			(xy 36.4555 -414.285437) (xy 36.431719 -414.369019) (xy 36.400327 -414.450051) (xy 36.361593 -414.52784)
			(xy 36.315846 -414.601724) (xy 36.279757 -414.649513) (xy 65.802248 -414.649513) (xy 65.802248 -414.578191)
			(xy 65.810234 -414.507317) (xy 65.826104 -414.437782) (xy 65.849661 -414.370462) (xy 65.880606 -414.306203)
			(xy 65.918552 -414.245812) (xy 65.963021 -414.19005) (xy 66.013454 -414.139617) (xy 66.069216 -414.095148)
			(xy 66.129607 -414.057202) (xy 66.193866 -414.026257) (xy 66.261186 -414.0027) (xy 66.330721 -413.98683)
			(xy 66.401595 -413.978844) (xy 66.437256 -413.978344) (xy 66.472917 -413.978844) (xy 66.543791 -413.98683)
			(xy 66.613326 -414.0027) (xy 66.680646 -414.026257) (xy 66.744905 -414.057202) (xy 66.805296 -414.095148)
			(xy 66.861058 -414.139617) (xy 66.911491 -414.19005) (xy 66.95596 -414.245812) (xy 66.993906 -414.306203)
			(xy 67.024851 -414.370462) (xy 67.048408 -414.437782) (xy 67.064278 -414.507317) (xy 67.072264 -414.578191)
			(xy 67.072264 -414.649513) (xy 68.79386 -414.649513) (xy 68.79386 -414.578191) (xy 68.801846 -414.507317)
			(xy 68.817716 -414.437782) (xy 68.841273 -414.370462) (xy 68.872218 -414.306203) (xy 68.910164 -414.245812)
			(xy 68.954633 -414.19005) (xy 69.005066 -414.139617) (xy 69.060828 -414.095148) (xy 69.121219 -414.057202)
			(xy 69.185478 -414.026257) (xy 69.252798 -414.0027) (xy 69.322333 -413.98683) (xy 69.393207 -413.978844)
			(xy 69.428868 -413.978344) (xy 69.464529 -413.978844) (xy 69.535403 -413.98683) (xy 69.604938 -414.0027)
			(xy 69.672258 -414.026257) (xy 69.736517 -414.057202) (xy 69.796908 -414.095148) (xy 69.85267 -414.139617)
			(xy 69.903103 -414.19005) (xy 69.947572 -414.245812) (xy 69.985518 -414.306203) (xy 70.016463 -414.370462)
			(xy 70.04002 -414.437782) (xy 70.05589 -414.507317) (xy 70.063876 -414.578191) (xy 70.063876 -414.649513)
			(xy 70.05589 -414.720387) (xy 70.04002 -414.789922) (xy 70.016463 -414.857242) (xy 69.985518 -414.921501)
			(xy 69.947572 -414.981892) (xy 69.903103 -415.037654) (xy 69.85267 -415.088087) (xy 69.796908 -415.132556)
			(xy 69.736517 -415.170502) (xy 69.672258 -415.201447) (xy 69.604938 -415.225004) (xy 69.535403 -415.240874)
			(xy 69.464529 -415.24886) (xy 69.393207 -415.24886) (xy 69.322333 -415.240874) (xy 69.252798 -415.225004)
			(xy 69.185478 -415.201447) (xy 69.121219 -415.170502) (xy 69.060828 -415.132556) (xy 69.005066 -415.088087)
			(xy 68.954633 -415.037654) (xy 68.910164 -414.981892) (xy 68.872218 -414.921501) (xy 68.841273 -414.857242)
			(xy 68.817716 -414.789922) (xy 68.801846 -414.720387) (xy 68.79386 -414.649513) (xy 67.072264 -414.649513)
			(xy 67.064278 -414.720387) (xy 67.048408 -414.789922) (xy 67.024851 -414.857242) (xy 66.993906 -414.921501)
			(xy 66.95596 -414.981892) (xy 66.911491 -415.037654) (xy 66.861058 -415.088087) (xy 66.805296 -415.132556)
			(xy 66.744905 -415.170502) (xy 66.680646 -415.201447) (xy 66.613326 -415.225004) (xy 66.543791 -415.240874)
			(xy 66.472917 -415.24886) (xy 66.401595 -415.24886) (xy 66.330721 -415.240874) (xy 66.261186 -415.225004)
			(xy 66.193866 -415.201447) (xy 66.129607 -415.170502) (xy 66.069216 -415.132556) (xy 66.013454 -415.088087)
			(xy 65.963021 -415.037654) (xy 65.918552 -414.981892) (xy 65.880606 -414.921501) (xy 65.849661 -414.857242)
			(xy 65.826104 -414.789922) (xy 65.810234 -414.720387) (xy 65.802248 -414.649513) (xy 36.279757 -414.649513)
			(xy 36.263477 -414.671071) (xy 36.204933 -414.735291) (xy 36.140713 -414.793835) (xy 36.071366 -414.846204)
			(xy 35.997482 -414.891951) (xy 35.919693 -414.930685) (xy 35.838661 -414.962077) (xy 35.755079 -414.985858)
			(xy 35.669659 -415.001826) (xy 35.58313 -415.009844) (xy 35.49623 -415.009844) (xy 35.409701 -415.001826)
			(xy 35.324281 -414.985858) (xy 35.240699 -414.962077) (xy 35.159667 -414.930685) (xy 35.081878 -414.891951)
			(xy 35.007994 -414.846204) (xy 34.938647 -414.793835) (xy 34.874427 -414.735291) (xy 34.815883 -414.671071)
			(xy 34.763514 -414.601724) (xy 34.717767 -414.52784) (xy 34.679033 -414.450051) (xy 34.647641 -414.369019)
			(xy 34.62386 -414.285437) (xy 34.607892 -414.200017) (xy 34.599874 -414.113488) (xy 31.399575 -414.113488)
			(xy 31.391739 -414.198822) (xy 31.376053 -414.283517) (xy 31.352688 -414.366422) (xy 31.321838 -414.446843)
			(xy 31.283763 -414.524106) (xy 31.238783 -414.597563) (xy 31.187273 -414.666599) (xy 31.129665 -414.730635)
			(xy 31.066443 -414.789135) (xy 30.998137 -414.841608) (xy 30.925317 -414.887614) (xy 30.848596 -414.926769)
			(xy 30.768616 -414.958743) (xy 30.686046 -414.983269) (xy 30.60158 -415.000141) (xy 30.515925 -415.009219)
			(xy 30.429798 -415.010425) (xy 30.343922 -415.00375) (xy 30.259017 -414.989249) (xy 30.175793 -414.967045)
			(xy 30.094948 -414.937323) (xy 30.017161 -414.900332) (xy 29.979874 -414.878774) (xy 29.960453 -414.867773)
			(xy 29.918684 -414.852049) (xy 29.874811 -414.843859) (xy 29.830181 -414.843455) (xy 29.786167 -414.850849)
			(xy 29.74412 -414.865815) (xy 29.705332 -414.887893) (xy 29.670994 -414.916404) (xy 29.642162 -414.950472)
			(xy 29.619721 -414.989051) (xy 29.604361 -415.030956) (xy 29.596554 -415.074899) (xy 29.59608 -415.097214)
			(xy 29.59608 -415.582862) (xy 29.596592 -415.605182) (xy 29.604369 -415.649138) (xy 29.619706 -415.691059)
			(xy 29.642133 -415.729655) (xy 29.670959 -415.763739) (xy 29.705297 -415.792261) (xy 29.744091 -415.814344)
			(xy 29.786147 -415.829309) (xy 29.83017 -415.836695) (xy 29.874807 -415.836274) (xy 29.918684 -415.82806)
			(xy 29.96045 -415.812306) (xy 29.979874 -415.801302) (xy 30.017126 -415.779686) (xy 30.094912 -415.742692)
			(xy 30.175756 -415.712967) (xy 30.258979 -415.690759) (xy 30.343884 -415.676255) (xy 30.429759 -415.669577)
			(xy 30.515886 -415.670779) (xy 30.601542 -415.679853) (xy 30.686009 -415.696722) (xy 30.768579 -415.721244)
			(xy 30.848561 -415.753215) (xy 30.925284 -415.792366) (xy 30.998105 -415.83837) (xy 31.066414 -415.89084)
			(xy 31.129638 -415.949337) (xy 31.187248 -416.013371) (xy 31.238761 -416.082405) (xy 31.283745 -416.15586)
			(xy 31.321823 -416.233121) (xy 31.352675 -416.313541) (xy 31.376044 -416.396445) (xy 31.391734 -416.481139)
			(xy 31.399613 -416.566913) (xy 31.399615 -416.653048) (xy 31.399575 -416.653488) (xy 34.599874 -416.653488)
			(xy 34.599874 -416.566588) (xy 34.607892 -416.480059) (xy 34.62386 -416.394639) (xy 34.647641 -416.311057)
			(xy 34.679033 -416.230025) (xy 34.717767 -416.152236) (xy 34.763514 -416.078352) (xy 34.815883 -416.009005)
			(xy 34.874427 -415.944785) (xy 34.938647 -415.886241) (xy 35.007994 -415.833872) (xy 35.081878 -415.788125)
			(xy 35.159667 -415.749391) (xy 35.240699 -415.717999) (xy 35.324281 -415.694218) (xy 35.409701 -415.67825)
			(xy 35.49623 -415.670232) (xy 35.53968 -415.66973) (xy 35.58313 -415.670232) (xy 35.669659 -415.67825)
			(xy 35.755079 -415.694218) (xy 35.838661 -415.717999) (xy 35.919693 -415.749391) (xy 35.997482 -415.788125)
			(xy 36.071366 -415.833872) (xy 36.140713 -415.886241) (xy 36.204933 -415.944785) (xy 36.263477 -416.009005)
			(xy 36.315846 -416.078352) (xy 36.361593 -416.152236) (xy 36.400327 -416.230025) (xy 36.431719 -416.311057)
			(xy 36.4555 -416.394639) (xy 36.471468 -416.480059) (xy 36.479486 -416.566588) (xy 36.479486 -416.653488)
			(xy 36.471468 -416.740017) (xy 36.4555 -416.825437) (xy 36.431719 -416.909019) (xy 36.400327 -416.990051)
			(xy 36.361593 -417.06784) (xy 36.315846 -417.141724) (xy 36.263477 -417.211071) (xy 36.204933 -417.275291)
			(xy 36.158321 -417.317783) (xy 65.802248 -417.317783) (xy 65.802248 -417.246461) (xy 65.810234 -417.175587)
			(xy 65.826104 -417.106052) (xy 65.849661 -417.038732) (xy 65.880606 -416.974473) (xy 65.918552 -416.914082)
			(xy 65.963021 -416.85832) (xy 66.013454 -416.807887) (xy 66.069216 -416.763418) (xy 66.129607 -416.725472)
			(xy 66.193866 -416.694527) (xy 66.261186 -416.67097) (xy 66.330721 -416.6551) (xy 66.401595 -416.647114)
			(xy 66.437256 -416.646614) (xy 66.472917 -416.647114) (xy 66.543791 -416.6551) (xy 66.613326 -416.67097)
			(xy 66.680646 -416.694527) (xy 66.744905 -416.725472) (xy 66.805296 -416.763418) (xy 66.861058 -416.807887)
			(xy 66.911491 -416.85832) (xy 66.95596 -416.914082) (xy 66.993906 -416.974473) (xy 67.024851 -417.038732)
			(xy 67.048408 -417.106052) (xy 67.064278 -417.175587) (xy 67.072264 -417.246461) (xy 67.072264 -417.317783)
			(xy 68.79386 -417.317783) (xy 68.79386 -417.246461) (xy 68.801846 -417.175587) (xy 68.817716 -417.106052)
			(xy 68.841273 -417.038732) (xy 68.872218 -416.974473) (xy 68.910164 -416.914082) (xy 68.954633 -416.85832)
			(xy 69.005066 -416.807887) (xy 69.060828 -416.763418) (xy 69.121219 -416.725472) (xy 69.185478 -416.694527)
			(xy 69.252798 -416.67097) (xy 69.322333 -416.6551) (xy 69.393207 -416.647114) (xy 69.428868 -416.646614)
			(xy 69.464529 -416.647114) (xy 69.535403 -416.6551) (xy 69.604938 -416.67097) (xy 69.672258 -416.694527)
			(xy 69.736517 -416.725472) (xy 69.796908 -416.763418) (xy 69.85267 -416.807887) (xy 69.903103 -416.85832)
			(xy 69.947572 -416.914082) (xy 69.985518 -416.974473) (xy 70.016463 -417.038732) (xy 70.04002 -417.106052)
			(xy 70.05589 -417.175587) (xy 70.063876 -417.246461) (xy 70.063876 -417.317783) (xy 70.05589 -417.388657)
			(xy 70.04002 -417.458192) (xy 70.016463 -417.525512) (xy 69.985518 -417.589771) (xy 69.947572 -417.650162)
			(xy 69.903103 -417.705924) (xy 69.85267 -417.756357) (xy 69.796908 -417.800826) (xy 69.736517 -417.838772)
			(xy 69.672258 -417.869717) (xy 69.604938 -417.893274) (xy 69.535403 -417.909144) (xy 69.464529 -417.91713)
			(xy 69.393207 -417.91713) (xy 69.322333 -417.909144) (xy 69.252798 -417.893274) (xy 69.185478 -417.869717)
			(xy 69.121219 -417.838772) (xy 69.060828 -417.800826) (xy 69.005066 -417.756357) (xy 68.954633 -417.705924)
			(xy 68.910164 -417.650162) (xy 68.872218 -417.589771) (xy 68.841273 -417.525512) (xy 68.817716 -417.458192)
			(xy 68.801846 -417.388657) (xy 68.79386 -417.317783) (xy 67.072264 -417.317783) (xy 67.064278 -417.388657)
			(xy 67.048408 -417.458192) (xy 67.024851 -417.525512) (xy 66.993906 -417.589771) (xy 66.95596 -417.650162)
			(xy 66.911491 -417.705924) (xy 66.861058 -417.756357) (xy 66.805296 -417.800826) (xy 66.744905 -417.838772)
			(xy 66.680646 -417.869717) (xy 66.613326 -417.893274) (xy 66.543791 -417.909144) (xy 66.472917 -417.91713)
			(xy 66.401595 -417.91713) (xy 66.330721 -417.909144) (xy 66.261186 -417.893274) (xy 66.193866 -417.869717)
			(xy 66.129607 -417.838772) (xy 66.069216 -417.800826) (xy 66.013454 -417.756357) (xy 65.963021 -417.705924)
			(xy 65.918552 -417.650162) (xy 65.880606 -417.589771) (xy 65.849661 -417.525512) (xy 65.826104 -417.458192)
			(xy 65.810234 -417.388657) (xy 65.802248 -417.317783) (xy 36.158321 -417.317783) (xy 36.140713 -417.333835)
			(xy 36.071366 -417.386204) (xy 35.997482 -417.431951) (xy 35.919693 -417.470685) (xy 35.838661 -417.502077)
			(xy 35.755079 -417.525858) (xy 35.669659 -417.541826) (xy 35.58313 -417.549844) (xy 35.49623 -417.549844)
			(xy 35.409701 -417.541826) (xy 35.324281 -417.525858) (xy 35.240699 -417.502077) (xy 35.159667 -417.470685)
			(xy 35.081878 -417.431951) (xy 35.007994 -417.386204) (xy 34.938647 -417.333835) (xy 34.874427 -417.275291)
			(xy 34.815883 -417.211071) (xy 34.763514 -417.141724) (xy 34.717767 -417.06784) (xy 34.679033 -416.990051)
			(xy 34.647641 -416.909019) (xy 34.62386 -416.825437) (xy 34.607892 -416.740017) (xy 34.599874 -416.653488)
			(xy 31.399575 -416.653488) (xy 31.391739 -416.738822) (xy 31.376053 -416.823517) (xy 31.352688 -416.906422)
			(xy 31.321838 -416.986843) (xy 31.283763 -417.064106) (xy 31.238783 -417.137563) (xy 31.187273 -417.206599)
			(xy 31.129665 -417.270635) (xy 31.066443 -417.329135) (xy 30.998137 -417.381608) (xy 30.925317 -417.427614)
			(xy 30.848596 -417.466769) (xy 30.768616 -417.498743) (xy 30.686046 -417.523269) (xy 30.60158 -417.540141)
			(xy 30.515925 -417.549219) (xy 30.429798 -417.550425) (xy 30.343922 -417.54375) (xy 30.259017 -417.529249)
			(xy 30.175793 -417.507045) (xy 30.094948 -417.477323) (xy 30.017161 -417.440332) (xy 29.979874 -417.418774)
			(xy 29.960453 -417.407773) (xy 29.918684 -417.392049) (xy 29.874811 -417.383859) (xy 29.830181 -417.383455)
			(xy 29.786167 -417.390849) (xy 29.74412 -417.405815) (xy 29.705332 -417.427893) (xy 29.670994 -417.456404)
			(xy 29.642162 -417.490472) (xy 29.619721 -417.529051) (xy 29.604361 -417.570956) (xy 29.596554 -417.614899)
			(xy 29.59608 -417.637214) (xy 29.59608 -418.122862) (xy 29.596592 -418.145182) (xy 29.604369 -418.189138)
			(xy 29.619706 -418.231059) (xy 29.642133 -418.269655) (xy 29.670959 -418.303739) (xy 29.705297 -418.332261)
			(xy 29.744091 -418.354344) (xy 29.786147 -418.369309) (xy 29.83017 -418.376695) (xy 29.874807 -418.376274)
			(xy 29.918684 -418.36806) (xy 29.96045 -418.352306) (xy 29.979874 -418.341302) (xy 30.017126 -418.319686)
			(xy 30.094912 -418.282692) (xy 30.175756 -418.252967) (xy 30.258979 -418.230759) (xy 30.343884 -418.216255)
			(xy 30.429759 -418.209577) (xy 30.515886 -418.210779) (xy 30.601542 -418.219853) (xy 30.686009 -418.236722)
			(xy 30.768579 -418.261244) (xy 30.848561 -418.293215) (xy 30.925284 -418.332366) (xy 30.998105 -418.37837)
			(xy 31.066414 -418.43084) (xy 31.129638 -418.489337) (xy 31.187248 -418.553371) (xy 31.238761 -418.622405)
			(xy 31.283745 -418.69586) (xy 31.321823 -418.773121) (xy 31.352675 -418.853541) (xy 31.376044 -418.936445)
			(xy 31.391734 -419.021139) (xy 31.399613 -419.106913) (xy 31.399615 -419.193048) (xy 31.399575 -419.193488)
			(xy 34.599874 -419.193488) (xy 34.599874 -419.106588) (xy 34.607892 -419.020059) (xy 34.62386 -418.934639)
			(xy 34.647641 -418.851057) (xy 34.679033 -418.770025) (xy 34.717767 -418.692236) (xy 34.763514 -418.618352)
			(xy 34.815883 -418.549005) (xy 34.874427 -418.484785) (xy 34.938647 -418.426241) (xy 35.007994 -418.373872)
			(xy 35.081878 -418.328125) (xy 35.159667 -418.289391) (xy 35.240699 -418.257999) (xy 35.324281 -418.234218)
			(xy 35.409701 -418.21825) (xy 35.49623 -418.210232) (xy 35.53968 -418.20973) (xy 35.58313 -418.210232)
			(xy 35.669659 -418.21825) (xy 35.755079 -418.234218) (xy 35.838661 -418.257999) (xy 35.919693 -418.289391)
			(xy 35.997482 -418.328125) (xy 36.071366 -418.373872) (xy 36.140713 -418.426241) (xy 36.204933 -418.484785)
			(xy 36.263477 -418.549005) (xy 36.315846 -418.618352) (xy 36.352477 -418.677513) (xy 51.478932 -418.677513)
			(xy 51.478932 -418.596403) (xy 51.486882 -418.515684) (xy 51.502705 -418.436133) (xy 51.52625 -418.358517)
			(xy 51.557289 -418.283581) (xy 51.595524 -418.212049) (xy 51.640586 -418.144609) (xy 51.692041 -418.08191)
			(xy 51.749394 -418.024557) (xy 51.812093 -417.973102) (xy 51.879533 -417.92804) (xy 51.951065 -417.889805)
			(xy 52.026001 -417.858766) (xy 52.103617 -417.835221) (xy 52.183168 -417.819398) (xy 52.263887 -417.811448)
			(xy 52.304442 -417.81095) (xy 52.344997 -417.811448) (xy 52.425716 -417.819398) (xy 52.505267 -417.835221)
			(xy 52.582883 -417.858766) (xy 52.657819 -417.889805) (xy 52.729351 -417.92804) (xy 52.796791 -417.973102)
			(xy 52.85949 -418.024557) (xy 52.916843 -418.08191) (xy 52.968298 -418.144609) (xy 53.01336 -418.212049)
			(xy 53.051595 -418.283581) (xy 53.082634 -418.358517) (xy 53.106179 -418.436133) (xy 53.122002 -418.515684)
			(xy 53.129952 -418.596403) (xy 53.129952 -418.677513) (xy 53.122002 -418.758232) (xy 53.106179 -418.837783)
			(xy 53.082634 -418.915399) (xy 53.051595 -418.990335) (xy 53.01336 -419.061867) (xy 52.968298 -419.129307)
			(xy 52.916843 -419.192006) (xy 52.85949 -419.249359) (xy 52.796791 -419.300814) (xy 52.729351 -419.345876)
			(xy 52.657819 -419.384111) (xy 52.582883 -419.41515) (xy 52.505267 -419.438695) (xy 52.425716 -419.454518)
			(xy 52.344997 -419.462468) (xy 52.263887 -419.462468) (xy 52.183168 -419.454518) (xy 52.103617 -419.438695)
			(xy 52.026001 -419.41515) (xy 51.951065 -419.384111) (xy 51.879533 -419.345876) (xy 51.812093 -419.300814)
			(xy 51.749394 -419.249359) (xy 51.692041 -419.192006) (xy 51.640586 -419.129307) (xy 51.595524 -419.061867)
			(xy 51.557289 -418.990335) (xy 51.52625 -418.915399) (xy 51.502705 -418.837783) (xy 51.486882 -418.758232)
			(xy 51.478932 -418.677513) (xy 36.352477 -418.677513) (xy 36.361593 -418.692236) (xy 36.400327 -418.770025)
			(xy 36.431719 -418.851057) (xy 36.4555 -418.934639) (xy 36.471468 -419.020059) (xy 36.479486 -419.106588)
			(xy 36.479486 -419.193488) (xy 36.471468 -419.280017) (xy 36.4555 -419.365437) (xy 36.431719 -419.449019)
			(xy 36.400327 -419.530051) (xy 36.361593 -419.60784) (xy 36.315846 -419.681724) (xy 36.310064 -419.689381)
			(xy 65.802248 -419.689381) (xy 65.802248 -419.618059) (xy 65.810234 -419.547185) (xy 65.826104 -419.47765)
			(xy 65.849661 -419.41033) (xy 65.880606 -419.346071) (xy 65.918552 -419.28568) (xy 65.963021 -419.229918)
			(xy 66.013454 -419.179485) (xy 66.069216 -419.135016) (xy 66.129607 -419.09707) (xy 66.193866 -419.066125)
			(xy 66.261186 -419.042568) (xy 66.330721 -419.026698) (xy 66.401595 -419.018712) (xy 66.437256 -419.018212)
			(xy 66.472917 -419.018712) (xy 66.543791 -419.026698) (xy 66.613326 -419.042568) (xy 66.680646 -419.066125)
			(xy 66.744905 -419.09707) (xy 66.805296 -419.135016) (xy 66.861058 -419.179485) (xy 66.911491 -419.229918)
			(xy 66.95596 -419.28568) (xy 66.993906 -419.346071) (xy 67.024851 -419.41033) (xy 67.048408 -419.47765)
			(xy 67.064278 -419.547185) (xy 67.072264 -419.618059) (xy 67.072264 -419.689381) (xy 68.79386 -419.689381)
			(xy 68.79386 -419.618059) (xy 68.801846 -419.547185) (xy 68.817716 -419.47765) (xy 68.841273 -419.41033)
			(xy 68.872218 -419.346071) (xy 68.910164 -419.28568) (xy 68.954633 -419.229918) (xy 69.005066 -419.179485)
			(xy 69.060828 -419.135016) (xy 69.121219 -419.09707) (xy 69.185478 -419.066125) (xy 69.252798 -419.042568)
			(xy 69.322333 -419.026698) (xy 69.393207 -419.018712) (xy 69.428868 -419.018212) (xy 69.464529 -419.018712)
			(xy 69.535403 -419.026698) (xy 69.604938 -419.042568) (xy 69.672258 -419.066125) (xy 69.736517 -419.09707)
			(xy 69.796908 -419.135016) (xy 69.85267 -419.179485) (xy 69.903103 -419.229918) (xy 69.947572 -419.28568)
			(xy 69.985518 -419.346071) (xy 70.016463 -419.41033) (xy 70.04002 -419.47765) (xy 70.05589 -419.547185)
			(xy 70.063876 -419.618059) (xy 70.063876 -419.689381) (xy 70.05589 -419.760255) (xy 70.04002 -419.82979)
			(xy 70.016463 -419.89711) (xy 69.985518 -419.961369) (xy 69.947572 -420.02176) (xy 69.903103 -420.077522)
			(xy 69.872829 -420.107796) (xy 86.877655 -420.107796) (xy 86.879665 -419.917113) (xy 86.889712 -419.726684)
			(xy 86.907778 -419.536848) (xy 86.933831 -419.347942) (xy 86.967824 -419.160303) (xy 87.009697 -418.974263)
			(xy 87.059376 -418.790154) (xy 87.116772 -418.608303) (xy 87.181783 -418.429033) (xy 87.254294 -418.252663)
			(xy 87.334175 -418.079507) (xy 87.421285 -417.909872) (xy 87.515469 -417.74406) (xy 87.61656 -417.582366)
			(xy 87.724376 -417.425078) (xy 87.838728 -417.272475) (xy 87.959411 -417.124827) (xy 88.086212 -416.982399)
			(xy 88.218903 -416.845443) (xy 88.357251 -416.714202) (xy 88.501008 -416.58891) (xy 88.649919 -416.46979)
			(xy 88.80372 -416.357054) (xy 88.962136 -416.250901) (xy 89.124887 -416.151521) (xy 89.291682 -416.059091)
			(xy 89.462226 -415.973774) (xy 89.636214 -415.895722) (xy 89.813339 -415.825075) (xy 89.993284 -415.761957)
			(xy 90.17573 -415.706481) (xy 90.360353 -415.658746) (xy 90.546823 -415.618836) (xy 90.734811 -415.586823)
			(xy 90.923981 -415.562763) (xy 91.113997 -415.5467) (xy 91.304521 -415.538661) (xy 91.399868 -415.538158)
			(xy 91.495215 -415.538661) (xy 91.685739 -415.5467) (xy 91.875755 -415.562763) (xy 92.064925 -415.586823)
			(xy 92.252913 -415.618836) (xy 92.439383 -415.658746) (xy 92.624006 -415.706481) (xy 92.806452 -415.761957)
			(xy 92.986397 -415.825075) (xy 93.163522 -415.895722) (xy 93.33751 -415.973774) (xy 93.508054 -416.059091)
			(xy 93.674849 -416.151521) (xy 93.8376 -416.250901) (xy 93.996016 -416.357054) (xy 94.149817 -416.46979)
			(xy 94.298728 -416.58891) (xy 94.442485 -416.714202) (xy 94.580833 -416.845443) (xy 94.713524 -416.982399)
			(xy 94.840325 -417.124827) (xy 94.961008 -417.272475) (xy 95.07536 -417.425078) (xy 95.183176 -417.582366)
			(xy 95.284267 -417.74406) (xy 95.378451 -417.909872) (xy 95.465561 -418.079507) (xy 95.545442 -418.252663)
			(xy 95.617953 -418.429033) (xy 95.682964 -418.608303) (xy 95.74036 -418.790154) (xy 95.790039 -418.974263)
			(xy 95.831912 -419.160303) (xy 95.865905 -419.347942) (xy 95.891958 -419.536848) (xy 95.910024 -419.726684)
			(xy 95.920071 -419.917113) (xy 95.922081 -420.107796) (xy 95.916051 -420.298395) (xy 95.901992 -420.488569)
			(xy 95.879927 -420.677982) (xy 95.849898 -420.866297) (xy 95.811956 -421.053178) (xy 95.76617 -421.238294)
			(xy 95.712621 -421.421314) (xy 95.651403 -421.601915) (xy 95.582627 -421.779774) (xy 95.506414 -421.954576)
			(xy 95.4229 -422.12601) (xy 95.332233 -422.29377) (xy 95.234574 -422.457559) (xy 95.130097 -422.617086)
			(xy 95.018988 -422.772067) (xy 94.901445 -422.922225) (xy 94.777675 -423.067295) (xy 94.6479 -423.207019)
			(xy 94.512351 -423.341147) (xy 94.371267 -423.469441) (xy 94.2249 -423.591675) (xy 94.073511 -423.707629)
			(xy 93.917368 -423.817098) (xy 93.756749 -423.919887) (xy 93.591939 -424.015813) (xy 93.423232 -424.104707)
			(xy 93.250927 -424.186409) (xy 93.075332 -424.260775) (xy 92.896757 -424.327673) (xy 92.715521 -424.386983)
			(xy 92.531946 -424.4386) (xy 92.346358 -424.482432) (xy 92.159088 -424.518401) (xy 91.970467 -424.546444)
			(xy 91.780832 -424.56651) (xy 91.590519 -424.578564) (xy 91.399868 -424.582585) (xy 91.209217 -424.578564)
			(xy 91.018904 -424.56651) (xy 90.829269 -424.546444) (xy 90.640648 -424.518401) (xy 90.453378 -424.482432)
			(xy 90.26779 -424.4386) (xy 90.084215 -424.386983) (xy 89.902979 -424.327673) (xy 89.724404 -424.260775)
			(xy 89.548809 -424.186409) (xy 89.376504 -424.104707) (xy 89.207797 -424.015813) (xy 89.042987 -423.919887)
			(xy 88.882368 -423.817098) (xy 88.726225 -423.707629) (xy 88.574836 -423.591675) (xy 88.428469 -423.469441)
			(xy 88.287385 -423.341147) (xy 88.151836 -423.207019) (xy 88.022061 -423.067295) (xy 87.898291 -422.922225)
			(xy 87.780748 -422.772067) (xy 87.669639 -422.617086) (xy 87.565162 -422.457559) (xy 87.467503 -422.29377)
			(xy 87.376836 -422.12601) (xy 87.293322 -421.954576) (xy 87.217109 -421.779774) (xy 87.148333 -421.601915)
			(xy 87.087115 -421.421314) (xy 87.033566 -421.238294) (xy 86.98778 -421.053178) (xy 86.949838 -420.866297)
			(xy 86.919809 -420.677982) (xy 86.897744 -420.488569) (xy 86.883685 -420.298395) (xy 86.877655 -420.107796)
			(xy 69.872829 -420.107796) (xy 69.85267 -420.127955) (xy 69.796908 -420.172424) (xy 69.736517 -420.21037)
			(xy 69.672258 -420.241315) (xy 69.604938 -420.264872) (xy 69.535403 -420.280742) (xy 69.464529 -420.288728)
			(xy 69.393207 -420.288728) (xy 69.322333 -420.280742) (xy 69.252798 -420.264872) (xy 69.185478 -420.241315)
			(xy 69.121219 -420.21037) (xy 69.060828 -420.172424) (xy 69.005066 -420.127955) (xy 68.954633 -420.077522)
			(xy 68.910164 -420.02176) (xy 68.872218 -419.961369) (xy 68.841273 -419.89711) (xy 68.817716 -419.82979)
			(xy 68.801846 -419.760255) (xy 68.79386 -419.689381) (xy 67.072264 -419.689381) (xy 67.064278 -419.760255)
			(xy 67.048408 -419.82979) (xy 67.024851 -419.89711) (xy 66.993906 -419.961369) (xy 66.95596 -420.02176)
			(xy 66.911491 -420.077522) (xy 66.861058 -420.127955) (xy 66.805296 -420.172424) (xy 66.744905 -420.21037)
			(xy 66.680646 -420.241315) (xy 66.613326 -420.264872) (xy 66.543791 -420.280742) (xy 66.472917 -420.288728)
			(xy 66.401595 -420.288728) (xy 66.330721 -420.280742) (xy 66.261186 -420.264872) (xy 66.193866 -420.241315)
			(xy 66.129607 -420.21037) (xy 66.069216 -420.172424) (xy 66.013454 -420.127955) (xy 65.963021 -420.077522)
			(xy 65.918552 -420.02176) (xy 65.880606 -419.961369) (xy 65.849661 -419.89711) (xy 65.826104 -419.82979)
			(xy 65.810234 -419.760255) (xy 65.802248 -419.689381) (xy 36.310064 -419.689381) (xy 36.263477 -419.751071)
			(xy 36.204933 -419.815291) (xy 36.140713 -419.873835) (xy 36.071366 -419.926204) (xy 35.997482 -419.971951)
			(xy 35.919693 -420.010685) (xy 35.838661 -420.042077) (xy 35.755079 -420.065858) (xy 35.669659 -420.081826)
			(xy 35.58313 -420.089844) (xy 35.49623 -420.089844) (xy 35.409701 -420.081826) (xy 35.324281 -420.065858)
			(xy 35.240699 -420.042077) (xy 35.159667 -420.010685) (xy 35.081878 -419.971951) (xy 35.007994 -419.926204)
			(xy 34.938647 -419.873835) (xy 34.874427 -419.815291) (xy 34.815883 -419.751071) (xy 34.763514 -419.681724)
			(xy 34.717767 -419.60784) (xy 34.679033 -419.530051) (xy 34.647641 -419.449019) (xy 34.62386 -419.365437)
			(xy 34.607892 -419.280017) (xy 34.599874 -419.193488) (xy 31.399575 -419.193488) (xy 31.391739 -419.278822)
			(xy 31.376053 -419.363517) (xy 31.352688 -419.446422) (xy 31.321838 -419.526843) (xy 31.283763 -419.604106)
			(xy 31.238783 -419.677563) (xy 31.187273 -419.746599) (xy 31.129665 -419.810635) (xy 31.066443 -419.869135)
			(xy 30.998137 -419.921608) (xy 30.925317 -419.967614) (xy 30.848596 -420.006769) (xy 30.768616 -420.038743)
			(xy 30.686046 -420.063269) (xy 30.60158 -420.080141) (xy 30.515925 -420.089219) (xy 30.429798 -420.090425)
			(xy 30.343922 -420.08375) (xy 30.259017 -420.069249) (xy 30.175793 -420.047045) (xy 30.094948 -420.017323)
			(xy 30.017161 -419.980332) (xy 29.979874 -419.958774) (xy 29.960453 -419.947773) (xy 29.918684 -419.932049)
			(xy 29.874811 -419.923859) (xy 29.830181 -419.923455) (xy 29.786167 -419.930849) (xy 29.74412 -419.945815)
			(xy 29.705332 -419.967893) (xy 29.670994 -419.996404) (xy 29.642162 -420.030472) (xy 29.619721 -420.069051)
			(xy 29.604361 -420.110956) (xy 29.596554 -420.154899) (xy 29.59608 -420.177214) (xy 29.59608 -420.662862)
			(xy 29.596592 -420.685182) (xy 29.604369 -420.729138) (xy 29.619706 -420.771059) (xy 29.642133 -420.809655)
			(xy 29.670959 -420.843739) (xy 29.705297 -420.872261) (xy 29.744091 -420.894344) (xy 29.786147 -420.909309)
			(xy 29.83017 -420.916695) (xy 29.874807 -420.916274) (xy 29.918684 -420.90806) (xy 29.96045 -420.892306)
			(xy 29.979874 -420.881302) (xy 30.017126 -420.859686) (xy 30.094912 -420.822692) (xy 30.175756 -420.792967)
			(xy 30.258979 -420.770759) (xy 30.343884 -420.756255) (xy 30.429759 -420.749577) (xy 30.515886 -420.750779)
			(xy 30.601542 -420.759853) (xy 30.686009 -420.776722) (xy 30.768579 -420.801244) (xy 30.848561 -420.833215)
			(xy 30.925284 -420.872366) (xy 30.998105 -420.91837) (xy 31.066414 -420.97084) (xy 31.129638 -421.029337)
			(xy 31.187248 -421.093371) (xy 31.238761 -421.162405) (xy 31.283745 -421.23586) (xy 31.321823 -421.313121)
			(xy 31.352675 -421.393541) (xy 31.376044 -421.476445) (xy 31.391734 -421.561139) (xy 31.399613 -421.646913)
			(xy 31.399615 -421.733048) (xy 31.399575 -421.733488) (xy 34.599874 -421.733488) (xy 34.599874 -421.646588)
			(xy 34.607892 -421.560059) (xy 34.62386 -421.474639) (xy 34.647641 -421.391057) (xy 34.679033 -421.310025)
			(xy 34.717767 -421.232236) (xy 34.763514 -421.158352) (xy 34.815883 -421.089005) (xy 34.874427 -421.024785)
			(xy 34.938647 -420.966241) (xy 35.007994 -420.913872) (xy 35.081878 -420.868125) (xy 35.159667 -420.829391)
			(xy 35.240699 -420.797999) (xy 35.324281 -420.774218) (xy 35.409701 -420.75825) (xy 35.49623 -420.750232)
			(xy 35.53968 -420.74973) (xy 35.58313 -420.750232) (xy 35.669659 -420.75825) (xy 35.755079 -420.774218)
			(xy 35.838661 -420.797999) (xy 35.919693 -420.829391) (xy 35.997482 -420.868125) (xy 36.071366 -420.913872)
			(xy 36.140713 -420.966241) (xy 36.152134 -420.976653) (xy 39.62196 -420.976653) (xy 39.62196 -420.905331)
			(xy 39.629946 -420.834457) (xy 39.645816 -420.764922) (xy 39.669373 -420.697602) (xy 39.700318 -420.633343)
			(xy 39.738264 -420.572952) (xy 39.782733 -420.51719) (xy 39.833166 -420.466757) (xy 39.888928 -420.422288)
			(xy 39.949319 -420.384342) (xy 40.013578 -420.353397) (xy 40.080898 -420.32984) (xy 40.150433 -420.31397)
			(xy 40.221307 -420.305984) (xy 40.256968 -420.305484) (xy 40.292629 -420.305984) (xy 40.363503 -420.31397)
			(xy 40.433038 -420.32984) (xy 40.500358 -420.353397) (xy 40.564617 -420.384342) (xy 40.625008 -420.422288)
			(xy 40.68077 -420.466757) (xy 40.731203 -420.51719) (xy 40.775672 -420.572952) (xy 40.813618 -420.633343)
			(xy 40.844563 -420.697602) (xy 40.86812 -420.764922) (xy 40.88399 -420.834457) (xy 40.891976 -420.905331)
			(xy 40.891976 -420.976653) (xy 40.88399 -421.047527) (xy 40.86812 -421.117062) (xy 40.844563 -421.184382)
			(xy 40.813618 -421.248641) (xy 40.775672 -421.309032) (xy 40.731203 -421.364794) (xy 40.68077 -421.415227)
			(xy 40.625008 -421.459696) (xy 40.564617 -421.497642) (xy 40.500358 -421.528587) (xy 40.433038 -421.552144)
			(xy 40.363503 -421.568014) (xy 40.292629 -421.576) (xy 40.221307 -421.576) (xy 40.150433 -421.568014)
			(xy 40.080898 -421.552144) (xy 40.013578 -421.528587) (xy 39.949319 -421.497642) (xy 39.888928 -421.459696)
			(xy 39.833166 -421.415227) (xy 39.782733 -421.364794) (xy 39.738264 -421.309032) (xy 39.700318 -421.248641)
			(xy 39.669373 -421.184382) (xy 39.645816 -421.117062) (xy 39.629946 -421.047527) (xy 39.62196 -420.976653)
			(xy 36.152134 -420.976653) (xy 36.204933 -421.024785) (xy 36.263477 -421.089005) (xy 36.315846 -421.158352)
			(xy 36.361593 -421.232236) (xy 36.400327 -421.310025) (xy 36.431719 -421.391057) (xy 36.4555 -421.474639)
			(xy 36.471468 -421.560059) (xy 36.479486 -421.646588) (xy 36.479486 -421.652293) (xy 65.802248 -421.652293)
			(xy 65.802248 -421.580971) (xy 65.810234 -421.510097) (xy 65.826104 -421.440562) (xy 65.849661 -421.373242)
			(xy 65.880606 -421.308983) (xy 65.918552 -421.248592) (xy 65.963021 -421.19283) (xy 66.013454 -421.142397)
			(xy 66.069216 -421.097928) (xy 66.129607 -421.059982) (xy 66.193866 -421.029037) (xy 66.261186 -421.00548)
			(xy 66.330721 -420.98961) (xy 66.401595 -420.981624) (xy 66.437256 -420.981124) (xy 66.472917 -420.981624)
			(xy 66.543791 -420.98961) (xy 66.613326 -421.00548) (xy 66.680646 -421.029037) (xy 66.744905 -421.059982)
			(xy 66.805296 -421.097928) (xy 66.861058 -421.142397) (xy 66.911491 -421.19283) (xy 66.95596 -421.248592)
			(xy 66.993906 -421.308983) (xy 67.024851 -421.373242) (xy 67.048408 -421.440562) (xy 67.064278 -421.510097)
			(xy 67.072264 -421.580971) (xy 67.072264 -421.652293) (xy 68.79386 -421.652293) (xy 68.79386 -421.580971)
			(xy 68.801846 -421.510097) (xy 68.817716 -421.440562) (xy 68.841273 -421.373242) (xy 68.872218 -421.308983)
			(xy 68.910164 -421.248592) (xy 68.954633 -421.19283) (xy 69.005066 -421.142397) (xy 69.060828 -421.097928)
			(xy 69.121219 -421.059982) (xy 69.185478 -421.029037) (xy 69.252798 -421.00548) (xy 69.322333 -420.98961)
			(xy 69.393207 -420.981624) (xy 69.428868 -420.981124) (xy 69.464529 -420.981624) (xy 69.535403 -420.98961)
			(xy 69.604938 -421.00548) (xy 69.672258 -421.029037) (xy 69.736517 -421.059982) (xy 69.796908 -421.097928)
			(xy 69.85267 -421.142397) (xy 69.903103 -421.19283) (xy 69.947572 -421.248592) (xy 69.985518 -421.308983)
			(xy 70.016463 -421.373242) (xy 70.04002 -421.440562) (xy 70.05589 -421.510097) (xy 70.063876 -421.580971)
			(xy 70.063876 -421.652293) (xy 70.05589 -421.723167) (xy 70.04002 -421.792702) (xy 70.016463 -421.860022)
			(xy 69.985518 -421.924281) (xy 69.947572 -421.984672) (xy 69.903103 -422.040434) (xy 69.85267 -422.090867)
			(xy 69.796908 -422.135336) (xy 69.736517 -422.173282) (xy 69.672258 -422.204227) (xy 69.604938 -422.227784)
			(xy 69.535403 -422.243654) (xy 69.464529 -422.25164) (xy 69.393207 -422.25164) (xy 69.322333 -422.243654)
			(xy 69.252798 -422.227784) (xy 69.185478 -422.204227) (xy 69.121219 -422.173282) (xy 69.060828 -422.135336)
			(xy 69.005066 -422.090867) (xy 68.954633 -422.040434) (xy 68.910164 -421.984672) (xy 68.872218 -421.924281)
			(xy 68.841273 -421.860022) (xy 68.817716 -421.792702) (xy 68.801846 -421.723167) (xy 68.79386 -421.652293)
			(xy 67.072264 -421.652293) (xy 67.064278 -421.723167) (xy 67.048408 -421.792702) (xy 67.024851 -421.860022)
			(xy 66.993906 -421.924281) (xy 66.95596 -421.984672) (xy 66.911491 -422.040434) (xy 66.861058 -422.090867)
			(xy 66.805296 -422.135336) (xy 66.744905 -422.173282) (xy 66.680646 -422.204227) (xy 66.613326 -422.227784)
			(xy 66.543791 -422.243654) (xy 66.472917 -422.25164) (xy 66.401595 -422.25164) (xy 66.330721 -422.243654)
			(xy 66.261186 -422.227784) (xy 66.193866 -422.204227) (xy 66.129607 -422.173282) (xy 66.069216 -422.135336)
			(xy 66.013454 -422.090867) (xy 65.963021 -422.040434) (xy 65.918552 -421.984672) (xy 65.880606 -421.924281)
			(xy 65.849661 -421.860022) (xy 65.826104 -421.792702) (xy 65.810234 -421.723167) (xy 65.802248 -421.652293)
			(xy 36.479486 -421.652293) (xy 36.479486 -421.733488) (xy 36.471468 -421.820017) (xy 36.4555 -421.905437)
			(xy 36.431719 -421.989019) (xy 36.400327 -422.070051) (xy 36.361593 -422.14784) (xy 36.315846 -422.221724)
			(xy 36.263477 -422.291071) (xy 36.204933 -422.355291) (xy 36.140713 -422.413835) (xy 36.071366 -422.466204)
			(xy 35.997482 -422.511951) (xy 35.919693 -422.550685) (xy 35.838661 -422.582077) (xy 35.755079 -422.605858)
			(xy 35.669659 -422.621826) (xy 35.58313 -422.629844) (xy 35.49623 -422.629844) (xy 35.409701 -422.621826)
			(xy 35.324281 -422.605858) (xy 35.240699 -422.582077) (xy 35.159667 -422.550685) (xy 35.081878 -422.511951)
			(xy 35.007994 -422.466204) (xy 34.938647 -422.413835) (xy 34.874427 -422.355291) (xy 34.815883 -422.291071)
			(xy 34.763514 -422.221724) (xy 34.717767 -422.14784) (xy 34.679033 -422.070051) (xy 34.647641 -421.989019)
			(xy 34.62386 -421.905437) (xy 34.607892 -421.820017) (xy 34.599874 -421.733488) (xy 31.399575 -421.733488)
			(xy 31.391739 -421.818822) (xy 31.376053 -421.903517) (xy 31.352688 -421.986422) (xy 31.321838 -422.066843)
			(xy 31.283763 -422.144106) (xy 31.238783 -422.217563) (xy 31.187273 -422.286599) (xy 31.129665 -422.350635)
			(xy 31.066443 -422.409135) (xy 30.998137 -422.461608) (xy 30.925317 -422.507614) (xy 30.848596 -422.546769)
			(xy 30.768616 -422.578743) (xy 30.686046 -422.603269) (xy 30.60158 -422.620141) (xy 30.515925 -422.629219)
			(xy 30.429798 -422.630425) (xy 30.343922 -422.62375) (xy 30.259017 -422.609249) (xy 30.175793 -422.587045)
			(xy 30.094948 -422.557323) (xy 30.017161 -422.520332) (xy 29.979874 -422.498774) (xy 29.960453 -422.487773)
			(xy 29.918684 -422.472049) (xy 29.874811 -422.463859) (xy 29.830181 -422.463455) (xy 29.786167 -422.470849)
			(xy 29.74412 -422.485815) (xy 29.705332 -422.507893) (xy 29.670994 -422.536404) (xy 29.642162 -422.570472)
			(xy 29.619721 -422.609051) (xy 29.604361 -422.650956) (xy 29.596554 -422.694899) (xy 29.59608 -422.717214)
			(xy 29.59608 -423.202862) (xy 29.596592 -423.225182) (xy 29.604369 -423.269138) (xy 29.619706 -423.311059)
			(xy 29.642133 -423.349655) (xy 29.670959 -423.383739) (xy 29.705297 -423.412261) (xy 29.744091 -423.434344)
			(xy 29.786147 -423.449309) (xy 29.83017 -423.456695) (xy 29.874807 -423.456274) (xy 29.918684 -423.44806)
			(xy 29.96045 -423.432306) (xy 29.979874 -423.421302) (xy 30.017126 -423.399686) (xy 30.094912 -423.362692)
			(xy 30.175756 -423.332967) (xy 30.258979 -423.310759) (xy 30.343884 -423.296255) (xy 30.429759 -423.289577)
			(xy 30.515886 -423.290779) (xy 30.601542 -423.299853) (xy 30.686009 -423.316722) (xy 30.768579 -423.341244)
			(xy 30.848561 -423.373215) (xy 30.925284 -423.412366) (xy 30.998105 -423.45837) (xy 31.066414 -423.51084)
			(xy 31.129638 -423.569337) (xy 31.187248 -423.633371) (xy 31.238761 -423.702405) (xy 31.283745 -423.77586)
			(xy 31.321823 -423.853121) (xy 31.352675 -423.933541) (xy 31.376044 -424.016445) (xy 31.391734 -424.101139)
			(xy 31.399613 -424.186913) (xy 31.399615 -424.273048) (xy 31.399575 -424.273488) (xy 34.599874 -424.273488)
			(xy 34.599874 -424.186588) (xy 34.607892 -424.100059) (xy 34.62386 -424.014639) (xy 34.647641 -423.931057)
			(xy 34.679033 -423.850025) (xy 34.717767 -423.772236) (xy 34.763514 -423.698352) (xy 34.815883 -423.629005)
			(xy 34.874427 -423.564785) (xy 34.938647 -423.506241) (xy 35.007994 -423.453872) (xy 35.081878 -423.408125)
			(xy 35.159667 -423.369391) (xy 35.240699 -423.337999) (xy 35.324281 -423.314218) (xy 35.409701 -423.29825)
			(xy 35.49623 -423.290232) (xy 35.53968 -423.28973) (xy 35.58313 -423.290232) (xy 35.669659 -423.29825)
			(xy 35.755079 -423.314218) (xy 35.838661 -423.337999) (xy 35.919693 -423.369391) (xy 35.997482 -423.408125)
			(xy 36.071366 -423.453872) (xy 36.140713 -423.506241) (xy 36.204933 -423.564785) (xy 36.263477 -423.629005)
			(xy 36.277416 -423.647463) (xy 39.62196 -423.647463) (xy 39.62196 -423.576141) (xy 39.629946 -423.505267)
			(xy 39.645816 -423.435732) (xy 39.669373 -423.368412) (xy 39.700318 -423.304153) (xy 39.738264 -423.243762)
			(xy 39.782733 -423.188) (xy 39.833166 -423.137567) (xy 39.888928 -423.093098) (xy 39.949319 -423.055152)
			(xy 40.013578 -423.024207) (xy 40.080898 -423.00065) (xy 40.150433 -422.98478) (xy 40.221307 -422.976794)
			(xy 40.256968 -422.976294) (xy 40.292629 -422.976794) (xy 40.363503 -422.98478) (xy 40.433038 -423.00065)
			(xy 40.500358 -423.024207) (xy 40.564617 -423.055152) (xy 40.625008 -423.093098) (xy 40.68077 -423.137567)
			(xy 40.731203 -423.188) (xy 40.775672 -423.243762) (xy 40.813618 -423.304153) (xy 40.844563 -423.368412)
			(xy 40.86812 -423.435732) (xy 40.88399 -423.505267) (xy 40.891976 -423.576141) (xy 40.891976 -423.647463)
			(xy 40.88399 -423.718337) (xy 40.86812 -423.787872) (xy 40.865346 -423.795799) (xy 65.802248 -423.795799)
			(xy 65.802248 -423.724477) (xy 65.810234 -423.653603) (xy 65.826104 -423.584068) (xy 65.849661 -423.516748)
			(xy 65.880606 -423.452489) (xy 65.918552 -423.392098) (xy 65.963021 -423.336336) (xy 66.013454 -423.285903)
			(xy 66.069216 -423.241434) (xy 66.129607 -423.203488) (xy 66.193866 -423.172543) (xy 66.261186 -423.148986)
			(xy 66.330721 -423.133116) (xy 66.401595 -423.12513) (xy 66.437256 -423.12463) (xy 66.472917 -423.12513)
			(xy 66.543791 -423.133116) (xy 66.613326 -423.148986) (xy 66.680646 -423.172543) (xy 66.744905 -423.203488)
			(xy 66.805296 -423.241434) (xy 66.861058 -423.285903) (xy 66.911491 -423.336336) (xy 66.95596 -423.392098)
			(xy 66.993906 -423.452489) (xy 67.024851 -423.516748) (xy 67.048408 -423.584068) (xy 67.064278 -423.653603)
			(xy 67.072264 -423.724477) (xy 67.072264 -423.795799) (xy 68.79386 -423.795799) (xy 68.79386 -423.724477)
			(xy 68.801846 -423.653603) (xy 68.817716 -423.584068) (xy 68.841273 -423.516748) (xy 68.872218 -423.452489)
			(xy 68.910164 -423.392098) (xy 68.954633 -423.336336) (xy 69.005066 -423.285903) (xy 69.060828 -423.241434)
			(xy 69.121219 -423.203488) (xy 69.185478 -423.172543) (xy 69.252798 -423.148986) (xy 69.322333 -423.133116)
			(xy 69.393207 -423.12513) (xy 69.428868 -423.12463) (xy 69.464529 -423.12513) (xy 69.535403 -423.133116)
			(xy 69.604938 -423.148986) (xy 69.672258 -423.172543) (xy 69.736517 -423.203488) (xy 69.796908 -423.241434)
			(xy 69.85267 -423.285903) (xy 69.903103 -423.336336) (xy 69.947572 -423.392098) (xy 69.985518 -423.452489)
			(xy 70.016463 -423.516748) (xy 70.04002 -423.584068) (xy 70.05589 -423.653603) (xy 70.063876 -423.724477)
			(xy 70.063876 -423.795799) (xy 70.05589 -423.866673) (xy 70.04002 -423.936208) (xy 70.016463 -424.003528)
			(xy 69.985518 -424.067787) (xy 69.947572 -424.128178) (xy 69.903103 -424.18394) (xy 69.85267 -424.234373)
			(xy 69.796908 -424.278842) (xy 69.736517 -424.316788) (xy 69.672258 -424.347733) (xy 69.604938 -424.37129)
			(xy 69.535403 -424.38716) (xy 69.464529 -424.395146) (xy 69.393207 -424.395146) (xy 69.322333 -424.38716)
			(xy 69.252798 -424.37129) (xy 69.185478 -424.347733) (xy 69.121219 -424.316788) (xy 69.060828 -424.278842)
			(xy 69.005066 -424.234373) (xy 68.954633 -424.18394) (xy 68.910164 -424.128178) (xy 68.872218 -424.067787)
			(xy 68.841273 -424.003528) (xy 68.817716 -423.936208) (xy 68.801846 -423.866673) (xy 68.79386 -423.795799)
			(xy 67.072264 -423.795799) (xy 67.064278 -423.866673) (xy 67.048408 -423.936208) (xy 67.024851 -424.003528)
			(xy 66.993906 -424.067787) (xy 66.95596 -424.128178) (xy 66.911491 -424.18394) (xy 66.861058 -424.234373)
			(xy 66.805296 -424.278842) (xy 66.744905 -424.316788) (xy 66.680646 -424.347733) (xy 66.613326 -424.37129)
			(xy 66.543791 -424.38716) (xy 66.472917 -424.395146) (xy 66.401595 -424.395146) (xy 66.330721 -424.38716)
			(xy 66.261186 -424.37129) (xy 66.193866 -424.347733) (xy 66.129607 -424.316788) (xy 66.069216 -424.278842)
			(xy 66.013454 -424.234373) (xy 65.963021 -424.18394) (xy 65.918552 -424.128178) (xy 65.880606 -424.067787)
			(xy 65.849661 -424.003528) (xy 65.826104 -423.936208) (xy 65.810234 -423.866673) (xy 65.802248 -423.795799)
			(xy 40.865346 -423.795799) (xy 40.844563 -423.855192) (xy 40.813618 -423.919451) (xy 40.775672 -423.979842)
			(xy 40.731203 -424.035604) (xy 40.68077 -424.086037) (xy 40.625008 -424.130506) (xy 40.564617 -424.168452)
			(xy 40.500358 -424.199397) (xy 40.433038 -424.222954) (xy 40.363503 -424.238824) (xy 40.292629 -424.24681)
			(xy 40.221307 -424.24681) (xy 40.150433 -424.238824) (xy 40.080898 -424.222954) (xy 40.013578 -424.199397)
			(xy 39.949319 -424.168452) (xy 39.888928 -424.130506) (xy 39.833166 -424.086037) (xy 39.782733 -424.035604)
			(xy 39.738264 -423.979842) (xy 39.700318 -423.919451) (xy 39.669373 -423.855192) (xy 39.645816 -423.787872)
			(xy 39.629946 -423.718337) (xy 39.62196 -423.647463) (xy 36.277416 -423.647463) (xy 36.315846 -423.698352)
			(xy 36.361593 -423.772236) (xy 36.400327 -423.850025) (xy 36.431719 -423.931057) (xy 36.4555 -424.014639)
			(xy 36.471468 -424.100059) (xy 36.479486 -424.186588) (xy 36.479486 -424.273488) (xy 36.471468 -424.360017)
			(xy 36.4555 -424.445437) (xy 36.431719 -424.529019) (xy 36.400327 -424.610051) (xy 36.361593 -424.68784)
			(xy 36.315846 -424.761724) (xy 36.263477 -424.831071) (xy 36.204933 -424.895291) (xy 36.140713 -424.953835)
			(xy 36.071366 -425.006204) (xy 35.997482 -425.051951) (xy 35.919693 -425.090685) (xy 35.838661 -425.122077)
			(xy 35.755079 -425.145858) (xy 35.669659 -425.161826) (xy 35.58313 -425.169844) (xy 35.49623 -425.169844)
			(xy 35.409701 -425.161826) (xy 35.324281 -425.145858) (xy 35.240699 -425.122077) (xy 35.159667 -425.090685)
			(xy 35.081878 -425.051951) (xy 35.007994 -425.006204) (xy 34.938647 -424.953835) (xy 34.874427 -424.895291)
			(xy 34.815883 -424.831071) (xy 34.763514 -424.761724) (xy 34.717767 -424.68784) (xy 34.679033 -424.610051)
			(xy 34.647641 -424.529019) (xy 34.62386 -424.445437) (xy 34.607892 -424.360017) (xy 34.599874 -424.273488)
			(xy 31.399575 -424.273488) (xy 31.391739 -424.358822) (xy 31.376053 -424.443517) (xy 31.352688 -424.526422)
			(xy 31.321838 -424.606843) (xy 31.283763 -424.684106) (xy 31.238783 -424.757563) (xy 31.187273 -424.826599)
			(xy 31.129665 -424.890635) (xy 31.066443 -424.949135) (xy 30.998137 -425.001608) (xy 30.925317 -425.047614)
			(xy 30.848596 -425.086769) (xy 30.768616 -425.118743) (xy 30.686046 -425.143269) (xy 30.60158 -425.160141)
			(xy 30.515925 -425.169219) (xy 30.429798 -425.170425) (xy 30.343922 -425.16375) (xy 30.259017 -425.149249)
			(xy 30.175793 -425.127045) (xy 30.094948 -425.097323) (xy 30.017161 -425.060332) (xy 29.979874 -425.038774)
			(xy 29.960453 -425.027773) (xy 29.918684 -425.012049) (xy 29.874811 -425.003859) (xy 29.830181 -425.003455)
			(xy 29.786167 -425.010849) (xy 29.74412 -425.025815) (xy 29.705332 -425.047893) (xy 29.670994 -425.076404)
			(xy 29.642162 -425.110472) (xy 29.619721 -425.149051) (xy 29.604361 -425.190956) (xy 29.596554 -425.234899)
			(xy 29.59608 -425.257214) (xy 29.59608 -425.742862) (xy 29.596592 -425.765182) (xy 29.604369 -425.809138)
			(xy 29.619706 -425.851059) (xy 29.642133 -425.889655) (xy 29.670959 -425.923739) (xy 29.705297 -425.952261)
			(xy 29.744091 -425.974344) (xy 29.786147 -425.989309) (xy 29.83017 -425.996695) (xy 29.874807 -425.996274)
			(xy 29.918684 -425.98806) (xy 29.96045 -425.972306) (xy 29.979874 -425.961302) (xy 30.017126 -425.939686)
			(xy 30.094912 -425.902692) (xy 30.175756 -425.872967) (xy 30.258979 -425.850759) (xy 30.343884 -425.836255)
			(xy 30.429759 -425.829577) (xy 30.515886 -425.830779) (xy 30.601542 -425.839853) (xy 30.686009 -425.856722)
			(xy 30.768579 -425.881244) (xy 30.848561 -425.913215) (xy 30.925284 -425.952366) (xy 30.998105 -425.99837)
			(xy 31.066414 -426.05084) (xy 31.129638 -426.109337) (xy 31.187248 -426.173371) (xy 31.238761 -426.242405)
			(xy 31.283745 -426.31586) (xy 31.321823 -426.393121) (xy 31.352675 -426.473541) (xy 31.376044 -426.556445)
			(xy 31.391734 -426.641139) (xy 31.399613 -426.726913) (xy 31.399615 -426.813048) (xy 31.399575 -426.813488)
			(xy 34.599874 -426.813488) (xy 34.599874 -426.726588) (xy 34.607892 -426.640059) (xy 34.62386 -426.554639)
			(xy 34.647641 -426.471057) (xy 34.679033 -426.390025) (xy 34.717767 -426.312236) (xy 34.763514 -426.238352)
			(xy 34.815883 -426.169005) (xy 34.874427 -426.104785) (xy 34.938647 -426.046241) (xy 35.007994 -425.993872)
			(xy 35.081878 -425.948125) (xy 35.159667 -425.909391) (xy 35.240699 -425.877999) (xy 35.324281 -425.854218)
			(xy 35.409701 -425.83825) (xy 35.49623 -425.830232) (xy 35.53968 -425.82973) (xy 35.58313 -425.830232)
			(xy 35.669659 -425.83825) (xy 35.755079 -425.854218) (xy 35.838661 -425.877999) (xy 35.919693 -425.909391)
			(xy 35.997482 -425.948125) (xy 36.071366 -425.993872) (xy 36.140713 -426.046241) (xy 36.204933 -426.104785)
			(xy 36.263477 -426.169005) (xy 36.315846 -426.238352) (xy 36.361593 -426.312236) (xy 36.363334 -426.315733)
			(xy 39.62196 -426.315733) (xy 39.62196 -426.244411) (xy 39.629946 -426.173537) (xy 39.645816 -426.104002)
			(xy 39.669373 -426.036682) (xy 39.700318 -425.972423) (xy 39.738264 -425.912032) (xy 39.782733 -425.85627)
			(xy 39.833166 -425.805837) (xy 39.888928 -425.761368) (xy 39.949319 -425.723422) (xy 40.013578 -425.692477)
			(xy 40.080898 -425.66892) (xy 40.150433 -425.65305) (xy 40.221307 -425.645064) (xy 40.256968 -425.644564)
			(xy 40.292629 -425.645064) (xy 40.363503 -425.65305) (xy 40.433038 -425.66892) (xy 40.500358 -425.692477)
			(xy 40.564617 -425.723422) (xy 40.625008 -425.761368) (xy 40.68077 -425.805837) (xy 40.731203 -425.85627)
			(xy 40.758328 -425.890283) (xy 64.063364 -425.890283) (xy 64.063364 -425.818961) (xy 64.07135 -425.748087)
			(xy 64.08722 -425.678552) (xy 64.110777 -425.611232) (xy 64.141722 -425.546973) (xy 64.179668 -425.486582)
			(xy 64.224137 -425.43082) (xy 64.27457 -425.380387) (xy 64.330332 -425.335918) (xy 64.390723 -425.297972)
			(xy 64.454982 -425.267027) (xy 64.522302 -425.24347) (xy 64.591837 -425.2276) (xy 64.662711 -425.219614)
			(xy 64.698372 -425.219114) (xy 64.734033 -425.219614) (xy 64.804907 -425.2276) (xy 64.874442 -425.24347)
			(xy 64.941762 -425.267027) (xy 65.006021 -425.297972) (xy 65.066412 -425.335918) (xy 65.122174 -425.380387)
			(xy 65.172607 -425.43082) (xy 65.217076 -425.486582) (xy 65.255022 -425.546973) (xy 65.285967 -425.611232)
			(xy 65.309524 -425.678552) (xy 65.325394 -425.748087) (xy 65.33338 -425.818961) (xy 65.33338 -425.890283)
			(xy 66.867778 -425.890283) (xy 66.867778 -425.818961) (xy 66.875764 -425.748087) (xy 66.891634 -425.678552)
			(xy 66.915191 -425.611232) (xy 66.946136 -425.546973) (xy 66.984082 -425.486582) (xy 67.028551 -425.43082)
			(xy 67.078984 -425.380387) (xy 67.134746 -425.335918) (xy 67.195137 -425.297972) (xy 67.259396 -425.267027)
			(xy 67.326716 -425.24347) (xy 67.396251 -425.2276) (xy 67.467125 -425.219614) (xy 67.502786 -425.219114)
			(xy 67.538447 -425.219614) (xy 67.609321 -425.2276) (xy 67.678856 -425.24347) (xy 67.746176 -425.267027)
			(xy 67.810435 -425.297972) (xy 67.870826 -425.335918) (xy 67.926588 -425.380387) (xy 67.977021 -425.43082)
			(xy 68.02149 -425.486582) (xy 68.059436 -425.546973) (xy 68.090381 -425.611232) (xy 68.113938 -425.678552)
			(xy 68.129808 -425.748087) (xy 68.137794 -425.818961) (xy 68.137794 -425.890283) (xy 68.129808 -425.961157)
			(xy 68.113938 -426.030692) (xy 68.090381 -426.098012) (xy 68.059436 -426.162271) (xy 68.02149 -426.222662)
			(xy 67.977021 -426.278424) (xy 67.926588 -426.328857) (xy 67.870826 -426.373326) (xy 67.810435 -426.411272)
			(xy 67.746176 -426.442217) (xy 67.678856 -426.465774) (xy 67.609321 -426.481644) (xy 67.538447 -426.48963)
			(xy 67.467125 -426.48963) (xy 67.396251 -426.481644) (xy 67.326716 -426.465774) (xy 67.259396 -426.442217)
			(xy 67.195137 -426.411272) (xy 67.134746 -426.373326) (xy 67.078984 -426.328857) (xy 67.028551 -426.278424)
			(xy 66.984082 -426.222662) (xy 66.946136 -426.162271) (xy 66.915191 -426.098012) (xy 66.891634 -426.030692)
			(xy 66.875764 -425.961157) (xy 66.867778 -425.890283) (xy 65.33338 -425.890283) (xy 65.325394 -425.961157)
			(xy 65.309524 -426.030692) (xy 65.285967 -426.098012) (xy 65.255022 -426.162271) (xy 65.217076 -426.222662)
			(xy 65.172607 -426.278424) (xy 65.122174 -426.328857) (xy 65.066412 -426.373326) (xy 65.006021 -426.411272)
			(xy 64.941762 -426.442217) (xy 64.874442 -426.465774) (xy 64.804907 -426.481644) (xy 64.734033 -426.48963)
			(xy 64.662711 -426.48963) (xy 64.591837 -426.481644) (xy 64.522302 -426.465774) (xy 64.454982 -426.442217)
			(xy 64.390723 -426.411272) (xy 64.330332 -426.373326) (xy 64.27457 -426.328857) (xy 64.224137 -426.278424)
			(xy 64.179668 -426.222662) (xy 64.141722 -426.162271) (xy 64.110777 -426.098012) (xy 64.08722 -426.030692)
			(xy 64.07135 -425.961157) (xy 64.063364 -425.890283) (xy 40.758328 -425.890283) (xy 40.775672 -425.912032)
			(xy 40.813618 -425.972423) (xy 40.844563 -426.036682) (xy 40.86812 -426.104002) (xy 40.88399 -426.173537)
			(xy 40.891976 -426.244411) (xy 40.891976 -426.315733) (xy 40.88399 -426.386607) (xy 40.86812 -426.456142)
			(xy 40.844563 -426.523462) (xy 40.813618 -426.587721) (xy 40.775672 -426.648112) (xy 40.731203 -426.703874)
			(xy 40.68077 -426.754307) (xy 40.625008 -426.798776) (xy 40.564617 -426.836722) (xy 40.500358 -426.867667)
			(xy 40.433038 -426.891224) (xy 40.363503 -426.907094) (xy 40.292629 -426.91508) (xy 40.221307 -426.91508)
			(xy 40.150433 -426.907094) (xy 40.080898 -426.891224) (xy 40.013578 -426.867667) (xy 39.949319 -426.836722)
			(xy 39.888928 -426.798776) (xy 39.833166 -426.754307) (xy 39.782733 -426.703874) (xy 39.738264 -426.648112)
			(xy 39.700318 -426.587721) (xy 39.669373 -426.523462) (xy 39.645816 -426.456142) (xy 39.629946 -426.386607)
			(xy 39.62196 -426.315733) (xy 36.363334 -426.315733) (xy 36.400327 -426.390025) (xy 36.431719 -426.471057)
			(xy 36.4555 -426.554639) (xy 36.471468 -426.640059) (xy 36.479486 -426.726588) (xy 36.479486 -426.813488)
			(xy 36.471468 -426.900017) (xy 36.4555 -426.985437) (xy 36.431719 -427.069019) (xy 36.400327 -427.150051)
			(xy 36.361593 -427.22784) (xy 36.315846 -427.301724) (xy 36.263477 -427.371071) (xy 36.204933 -427.435291)
			(xy 36.140713 -427.493835) (xy 36.071366 -427.546204) (xy 35.997482 -427.591951) (xy 35.919693 -427.630685)
			(xy 35.838661 -427.662077) (xy 35.755079 -427.685858) (xy 35.669659 -427.701826) (xy 35.58313 -427.709844)
			(xy 35.49623 -427.709844) (xy 35.409701 -427.701826) (xy 35.324281 -427.685858) (xy 35.240699 -427.662077)
			(xy 35.159667 -427.630685) (xy 35.081878 -427.591951) (xy 35.007994 -427.546204) (xy 34.938647 -427.493835)
			(xy 34.874427 -427.435291) (xy 34.815883 -427.371071) (xy 34.763514 -427.301724) (xy 34.717767 -427.22784)
			(xy 34.679033 -427.150051) (xy 34.647641 -427.069019) (xy 34.62386 -426.985437) (xy 34.607892 -426.900017)
			(xy 34.599874 -426.813488) (xy 31.399575 -426.813488) (xy 31.391739 -426.898822) (xy 31.376053 -426.983517)
			(xy 31.352688 -427.066422) (xy 31.321838 -427.146843) (xy 31.283763 -427.224106) (xy 31.238783 -427.297563)
			(xy 31.187273 -427.366599) (xy 31.129665 -427.430635) (xy 31.066443 -427.489135) (xy 30.998137 -427.541608)
			(xy 30.925317 -427.587614) (xy 30.848596 -427.626769) (xy 30.768616 -427.658743) (xy 30.686046 -427.683269)
			(xy 30.60158 -427.700141) (xy 30.515925 -427.709219) (xy 30.429798 -427.710425) (xy 30.343922 -427.70375)
			(xy 30.259017 -427.689249) (xy 30.175793 -427.667045) (xy 30.094948 -427.637323) (xy 30.017161 -427.600332)
			(xy 29.979874 -427.578774) (xy 29.960453 -427.567773) (xy 29.918684 -427.552049) (xy 29.874811 -427.543859)
			(xy 29.830181 -427.543455) (xy 29.786167 -427.550849) (xy 29.74412 -427.565815) (xy 29.705332 -427.587893)
			(xy 29.670994 -427.616404) (xy 29.642162 -427.650472) (xy 29.619721 -427.689051) (xy 29.604361 -427.730956)
			(xy 29.596554 -427.774899) (xy 29.59608 -427.797214) (xy 29.59608 -428.282862) (xy 29.596592 -428.305182)
			(xy 29.604369 -428.349138) (xy 29.619706 -428.391059) (xy 29.642133 -428.429655) (xy 29.670959 -428.463739)
			(xy 29.705297 -428.492261) (xy 29.744091 -428.514344) (xy 29.786147 -428.529309) (xy 29.83017 -428.536695)
			(xy 29.874807 -428.536274) (xy 29.918684 -428.52806) (xy 29.96045 -428.512306) (xy 29.979874 -428.501302)
			(xy 30.017126 -428.479686) (xy 30.094912 -428.442692) (xy 30.175756 -428.412967) (xy 30.258979 -428.390759)
			(xy 30.343884 -428.376255) (xy 30.429759 -428.369577) (xy 30.515886 -428.370779) (xy 30.601542 -428.379853)
			(xy 30.686009 -428.396722) (xy 30.768579 -428.421244) (xy 30.848561 -428.453215) (xy 30.925284 -428.492366)
			(xy 30.998105 -428.53837) (xy 31.066414 -428.59084) (xy 31.129638 -428.649337) (xy 31.187248 -428.713371)
			(xy 31.238761 -428.782405) (xy 31.283745 -428.85586) (xy 31.321823 -428.933121) (xy 31.352675 -429.013541)
			(xy 31.376044 -429.096445) (xy 31.391734 -429.181139) (xy 31.399613 -429.266913) (xy 31.399615 -429.353048)
			(xy 31.399575 -429.353488) (xy 34.599874 -429.353488) (xy 34.599874 -429.266588) (xy 34.607892 -429.180059)
			(xy 34.62386 -429.094639) (xy 34.647641 -429.011057) (xy 34.679033 -428.930025) (xy 34.717767 -428.852236)
			(xy 34.763514 -428.778352) (xy 34.815883 -428.709005) (xy 34.874427 -428.644785) (xy 34.938647 -428.586241)
			(xy 35.007994 -428.533872) (xy 35.081878 -428.488125) (xy 35.159667 -428.449391) (xy 35.240699 -428.417999)
			(xy 35.324281 -428.394218) (xy 35.409701 -428.37825) (xy 35.49623 -428.370232) (xy 35.53968 -428.36973)
			(xy 35.58313 -428.370232) (xy 35.669659 -428.37825) (xy 35.755079 -428.394218) (xy 35.838661 -428.417999)
			(xy 35.919693 -428.449391) (xy 35.997482 -428.488125) (xy 36.071366 -428.533872) (xy 36.140713 -428.586241)
			(xy 36.204933 -428.644785) (xy 36.243719 -428.687331) (xy 39.62196 -428.687331) (xy 39.62196 -428.616009)
			(xy 39.629946 -428.545135) (xy 39.645816 -428.4756) (xy 39.669373 -428.40828) (xy 39.700318 -428.344021)
			(xy 39.738264 -428.28363) (xy 39.782733 -428.227868) (xy 39.833166 -428.177435) (xy 39.888928 -428.132966)
			(xy 39.949319 -428.09502) (xy 40.013578 -428.064075) (xy 40.080898 -428.040518) (xy 40.150433 -428.024648)
			(xy 40.221307 -428.016662) (xy 40.256968 -428.016162) (xy 40.292629 -428.016662) (xy 40.363503 -428.024648)
			(xy 40.433038 -428.040518) (xy 40.500358 -428.064075) (xy 40.564617 -428.09502) (xy 40.625008 -428.132966)
			(xy 40.68077 -428.177435) (xy 40.731203 -428.227868) (xy 40.775672 -428.28363) (xy 40.813618 -428.344021)
			(xy 40.844563 -428.40828) (xy 40.86812 -428.4756) (xy 40.88399 -428.545135) (xy 40.885788 -428.561093)
			(xy 64.063364 -428.561093) (xy 64.063364 -428.489771) (xy 64.07135 -428.418897) (xy 64.08722 -428.349362)
			(xy 64.110777 -428.282042) (xy 64.141722 -428.217783) (xy 64.179668 -428.157392) (xy 64.224137 -428.10163)
			(xy 64.27457 -428.051197) (xy 64.330332 -428.006728) (xy 64.390723 -427.968782) (xy 64.454982 -427.937837)
			(xy 64.522302 -427.91428) (xy 64.591837 -427.89841) (xy 64.662711 -427.890424) (xy 64.698372 -427.889924)
			(xy 64.734033 -427.890424) (xy 64.804907 -427.89841) (xy 64.874442 -427.91428) (xy 64.941762 -427.937837)
			(xy 65.006021 -427.968782) (xy 65.066412 -428.006728) (xy 65.122174 -428.051197) (xy 65.172607 -428.10163)
			(xy 65.217076 -428.157392) (xy 65.255022 -428.217783) (xy 65.285967 -428.282042) (xy 65.309524 -428.349362)
			(xy 65.325394 -428.418897) (xy 65.33338 -428.489771) (xy 65.33338 -428.561093) (xy 66.867778 -428.561093)
			(xy 66.867778 -428.489771) (xy 66.875764 -428.418897) (xy 66.891634 -428.349362) (xy 66.915191 -428.282042)
			(xy 66.946136 -428.217783) (xy 66.984082 -428.157392) (xy 67.028551 -428.10163) (xy 67.078984 -428.051197)
			(xy 67.134746 -428.006728) (xy 67.195137 -427.968782) (xy 67.259396 -427.937837) (xy 67.326716 -427.91428)
			(xy 67.396251 -427.89841) (xy 67.467125 -427.890424) (xy 67.502786 -427.889924) (xy 67.538447 -427.890424)
			(xy 67.609321 -427.89841) (xy 67.678856 -427.91428) (xy 67.746176 -427.937837) (xy 67.810435 -427.968782)
			(xy 67.870826 -428.006728) (xy 67.926588 -428.051197) (xy 67.977021 -428.10163) (xy 68.02149 -428.157392)
			(xy 68.059436 -428.217783) (xy 68.090381 -428.282042) (xy 68.113938 -428.349362) (xy 68.129808 -428.418897)
			(xy 68.137794 -428.489771) (xy 68.137794 -428.561093) (xy 68.129808 -428.631967) (xy 68.113938 -428.701502)
			(xy 68.090381 -428.768822) (xy 68.059436 -428.833081) (xy 68.02149 -428.893472) (xy 67.977021 -428.949234)
			(xy 67.926588 -428.999667) (xy 67.870826 -429.044136) (xy 67.810435 -429.082082) (xy 67.746176 -429.113027)
			(xy 67.678856 -429.136584) (xy 67.609321 -429.152454) (xy 67.538447 -429.16044) (xy 67.467125 -429.16044)
			(xy 67.396251 -429.152454) (xy 67.326716 -429.136584) (xy 67.259396 -429.113027) (xy 67.195137 -429.082082)
			(xy 67.134746 -429.044136) (xy 67.078984 -428.999667) (xy 67.028551 -428.949234) (xy 66.984082 -428.893472)
			(xy 66.946136 -428.833081) (xy 66.915191 -428.768822) (xy 66.891634 -428.701502) (xy 66.875764 -428.631967)
			(xy 66.867778 -428.561093) (xy 65.33338 -428.561093) (xy 65.325394 -428.631967) (xy 65.309524 -428.701502)
			(xy 65.285967 -428.768822) (xy 65.255022 -428.833081) (xy 65.217076 -428.893472) (xy 65.172607 -428.949234)
			(xy 65.122174 -428.999667) (xy 65.066412 -429.044136) (xy 65.006021 -429.082082) (xy 64.941762 -429.113027)
			(xy 64.874442 -429.136584) (xy 64.804907 -429.152454) (xy 64.734033 -429.16044) (xy 64.662711 -429.16044)
			(xy 64.591837 -429.152454) (xy 64.522302 -429.136584) (xy 64.454982 -429.113027) (xy 64.390723 -429.082082)
			(xy 64.330332 -429.044136) (xy 64.27457 -428.999667) (xy 64.224137 -428.949234) (xy 64.179668 -428.893472)
			(xy 64.141722 -428.833081) (xy 64.110777 -428.768822) (xy 64.08722 -428.701502) (xy 64.07135 -428.631967)
			(xy 64.063364 -428.561093) (xy 40.885788 -428.561093) (xy 40.891976 -428.616009) (xy 40.891976 -428.687331)
			(xy 40.88399 -428.758205) (xy 40.86812 -428.82774) (xy 40.844563 -428.89506) (xy 40.813618 -428.959319)
			(xy 40.775672 -429.01971) (xy 40.731203 -429.075472) (xy 40.68077 -429.125905) (xy 40.625008 -429.170374)
			(xy 40.564617 -429.20832) (xy 40.500358 -429.239265) (xy 40.433038 -429.262822) (xy 40.363503 -429.278692)
			(xy 40.292629 -429.286678) (xy 40.221307 -429.286678) (xy 40.150433 -429.278692) (xy 40.080898 -429.262822)
			(xy 40.013578 -429.239265) (xy 39.949319 -429.20832) (xy 39.888928 -429.170374) (xy 39.833166 -429.125905)
			(xy 39.782733 -429.075472) (xy 39.738264 -429.01971) (xy 39.700318 -428.959319) (xy 39.669373 -428.89506)
			(xy 39.645816 -428.82774) (xy 39.629946 -428.758205) (xy 39.62196 -428.687331) (xy 36.243719 -428.687331)
			(xy 36.263477 -428.709005) (xy 36.315846 -428.778352) (xy 36.361593 -428.852236) (xy 36.400327 -428.930025)
			(xy 36.431719 -429.011057) (xy 36.4555 -429.094639) (xy 36.471468 -429.180059) (xy 36.479486 -429.266588)
			(xy 36.479486 -429.353488) (xy 36.471468 -429.440017) (xy 36.4555 -429.525437) (xy 36.431719 -429.609019)
			(xy 36.400327 -429.690051) (xy 36.361593 -429.76784) (xy 36.315846 -429.841724) (xy 36.263477 -429.911071)
			(xy 36.204933 -429.975291) (xy 36.140713 -430.033835) (xy 36.071366 -430.086204) (xy 35.997482 -430.131951)
			(xy 35.919693 -430.170685) (xy 35.838661 -430.202077) (xy 35.755079 -430.225858) (xy 35.669659 -430.241826)
			(xy 35.58313 -430.249844) (xy 35.49623 -430.249844) (xy 35.409701 -430.241826) (xy 35.324281 -430.225858)
			(xy 35.240699 -430.202077) (xy 35.159667 -430.170685) (xy 35.081878 -430.131951) (xy 35.007994 -430.086204)
			(xy 34.938647 -430.033835) (xy 34.874427 -429.975291) (xy 34.815883 -429.911071) (xy 34.763514 -429.841724)
			(xy 34.717767 -429.76784) (xy 34.679033 -429.690051) (xy 34.647641 -429.609019) (xy 34.62386 -429.525437)
			(xy 34.607892 -429.440017) (xy 34.599874 -429.353488) (xy 31.399575 -429.353488) (xy 31.391739 -429.438822)
			(xy 31.376053 -429.523517) (xy 31.352688 -429.606422) (xy 31.321838 -429.686843) (xy 31.283763 -429.764106)
			(xy 31.238783 -429.837563) (xy 31.187273 -429.906599) (xy 31.129665 -429.970635) (xy 31.066443 -430.029135)
			(xy 30.998137 -430.081608) (xy 30.925317 -430.127614) (xy 30.848596 -430.166769) (xy 30.768616 -430.198743)
			(xy 30.686046 -430.223269) (xy 30.60158 -430.240141) (xy 30.515925 -430.249219) (xy 30.429798 -430.250425)
			(xy 30.343922 -430.24375) (xy 30.259017 -430.229249) (xy 30.175793 -430.207045) (xy 30.094948 -430.177323)
			(xy 30.017161 -430.140332) (xy 29.979874 -430.118774) (xy 29.960453 -430.107773) (xy 29.918684 -430.092049)
			(xy 29.874811 -430.083859) (xy 29.830181 -430.083455) (xy 29.786167 -430.090849) (xy 29.74412 -430.105815)
			(xy 29.705332 -430.127893) (xy 29.670994 -430.156404) (xy 29.642162 -430.190472) (xy 29.619721 -430.229051)
			(xy 29.604361 -430.270956) (xy 29.596554 -430.314899) (xy 29.59608 -430.337214) (xy 29.59608 -430.650243)
			(xy 39.62196 -430.650243) (xy 39.62196 -430.578921) (xy 39.629946 -430.508047) (xy 39.645816 -430.438512)
			(xy 39.669373 -430.371192) (xy 39.700318 -430.306933) (xy 39.738264 -430.246542) (xy 39.782733 -430.19078)
			(xy 39.833166 -430.140347) (xy 39.888928 -430.095878) (xy 39.949319 -430.057932) (xy 40.013578 -430.026987)
			(xy 40.080898 -430.00343) (xy 40.150433 -429.98756) (xy 40.221307 -429.979574) (xy 40.256968 -429.979074)
			(xy 40.292629 -429.979574) (xy 40.363503 -429.98756) (xy 40.433038 -430.00343) (xy 40.500358 -430.026987)
			(xy 40.564617 -430.057932) (xy 40.625008 -430.095878) (xy 40.629001 -430.099062) (xy 72.868285 -430.099062)
			(xy 72.874295 -429.896361) (xy 72.888307 -429.694056) (xy 72.910302 -429.492462) (xy 72.940243 -429.291895)
			(xy 72.978084 -429.092667) (xy 73.023767 -428.895089) (xy 73.07722 -428.699471) (xy 73.138359 -428.506117)
			(xy 73.20709 -428.315329) (xy 73.283304 -428.127406) (xy 73.366883 -427.94264) (xy 73.457696 -427.761321)
			(xy 73.555601 -427.583731) (xy 73.660446 -427.410147) (xy 73.772067 -427.240841) (xy 73.890289 -427.076076)
			(xy 74.014929 -426.916111) (xy 74.14579 -426.761195) (xy 74.28267 -426.61157) (xy 74.425354 -426.46747)
			(xy 74.57362 -426.329118) (xy 74.727236 -426.196733) (xy 74.885961 -426.070519) (xy 75.04955 -425.950675)
			(xy 75.217745 -425.837387) (xy 75.390284 -425.730832) (xy 75.566899 -425.631177) (xy 75.747312 -425.538577)
			(xy 75.931243 -425.453177) (xy 76.118404 -425.37511) (xy 76.308504 -425.304498) (xy 76.501244 -425.241452)
			(xy 76.696325 -425.186069) (xy 76.893442 -425.138437) (xy 77.092286 -425.098629) (xy 77.292548 -425.066707)
			(xy 77.493914 -425.042723) (xy 77.696071 -425.026712) (xy 77.898703 -425.018701) (xy 78.000098 -425.0182)
			(xy 78.101493 -425.018701) (xy 78.304125 -425.026712) (xy 78.506282 -425.042723) (xy 78.707648 -425.066707)
			(xy 78.90791 -425.098629) (xy 79.106754 -425.138437) (xy 79.303871 -425.186069) (xy 79.498952 -425.241452)
			(xy 79.691692 -425.304498) (xy 79.881792 -425.37511) (xy 80.068953 -425.453177) (xy 80.252884 -425.538577)
			(xy 80.433297 -425.631177) (xy 80.609912 -425.730832) (xy 80.782451 -425.837387) (xy 80.950646 -425.950675)
			(xy 81.114235 -426.070519) (xy 81.27296 -426.196733) (xy 81.426576 -426.329118) (xy 81.574842 -426.46747)
			(xy 81.717526 -426.61157) (xy 81.854406 -426.761195) (xy 81.985267 -426.916111) (xy 82.109907 -427.076076)
			(xy 82.228129 -427.240841) (xy 82.33975 -427.410147) (xy 82.444595 -427.583731) (xy 82.5425 -427.761321)
			(xy 82.633313 -427.94264) (xy 82.716892 -428.127406) (xy 82.793106 -428.315329) (xy 82.861837 -428.506117)
			(xy 82.922976 -428.699471) (xy 82.976429 -428.895089) (xy 83.022112 -429.092667) (xy 83.059953 -429.291895)
			(xy 83.089894 -429.492462) (xy 83.111889 -429.694056) (xy 83.125901 -429.896361) (xy 83.131911 -430.099062)
			(xy 83.129907 -430.301842) (xy 83.119894 -430.504385) (xy 83.101887 -430.706374) (xy 83.075915 -430.907493)
			(xy 83.042017 -431.10743) (xy 83.000246 -431.305872) (xy 82.950669 -431.502508) (xy 82.893361 -431.697032)
			(xy 82.828414 -431.88914) (xy 82.755927 -432.078533) (xy 82.676015 -432.264914) (xy 82.588803 -432.447992)
			(xy 82.494425 -432.627482) (xy 82.39303 -432.803103) (xy 82.284776 -432.974582) (xy 82.169832 -433.141649)
			(xy 82.048377 -433.304046) (xy 81.920602 -433.461517) (xy 81.786705 -433.613817) (xy 81.646896 -433.760709)
			(xy 81.501392 -433.901962) (xy 81.350422 -434.037357) (xy 81.194221 -434.166682) (xy 81.033032 -434.289735)
			(xy 80.867108 -434.406324) (xy 80.696708 -434.516267) (xy 80.522097 -434.619392) (xy 80.343548 -434.715538)
			(xy 80.16134 -434.804556) (xy 79.975758 -434.886305) (xy 79.787091 -434.960659) (xy 79.595633 -435.027501)
			(xy 79.401685 -435.086727) (xy 79.205548 -435.138245) (xy 79.007529 -435.181974) (xy 78.807937 -435.217845)
			(xy 78.607083 -435.245804) (xy 78.405282 -435.265805) (xy 78.202848 -435.277818) (xy 78.000098 -435.281825)
			(xy 77.797348 -435.277818) (xy 77.594914 -435.265805) (xy 77.393113 -435.245804) (xy 77.192259 -435.217845)
			(xy 76.992667 -435.181974) (xy 76.794648 -435.138245) (xy 76.598511 -435.086727) (xy 76.404563 -435.027501)
			(xy 76.213105 -434.960659) (xy 76.024438 -434.886305) (xy 75.838856 -434.804556) (xy 75.656648 -434.715538)
			(xy 75.478099 -434.619392) (xy 75.303488 -434.516267) (xy 75.133088 -434.406324) (xy 74.967164 -434.289735)
			(xy 74.805975 -434.166682) (xy 74.649774 -434.037357) (xy 74.498804 -433.901962) (xy 74.3533 -433.760709)
			(xy 74.213491 -433.613817) (xy 74.079594 -433.461517) (xy 73.951819 -433.304046) (xy 73.830364 -433.141649)
			(xy 73.71542 -432.974582) (xy 73.607166 -432.803103) (xy 73.505771 -432.627482) (xy 73.411393 -432.447992)
			(xy 73.324181 -432.264914) (xy 73.244269 -432.078533) (xy 73.171782 -431.88914) (xy 73.106835 -431.697032)
			(xy 73.049527 -431.502508) (xy 72.99995 -431.305872) (xy 72.958179 -431.10743) (xy 72.924281 -430.907493)
			(xy 72.898309 -430.706374) (xy 72.880302 -430.504385) (xy 72.870289 -430.301842) (xy 72.868285 -430.099062)
			(xy 40.629001 -430.099062) (xy 40.68077 -430.140347) (xy 40.731203 -430.19078) (xy 40.775672 -430.246542)
			(xy 40.813618 -430.306933) (xy 40.844563 -430.371192) (xy 40.86812 -430.438512) (xy 40.88399 -430.508047)
			(xy 40.891976 -430.578921) (xy 40.891976 -430.650243) (xy 40.88399 -430.721117) (xy 40.86812 -430.790652)
			(xy 40.844563 -430.857972) (xy 40.813618 -430.922231) (xy 40.775672 -430.982622) (xy 40.731203 -431.038384)
			(xy 40.68077 -431.088817) (xy 40.625008 -431.133286) (xy 40.564617 -431.171232) (xy 40.500358 -431.202177)
			(xy 40.433038 -431.225734) (xy 40.417137 -431.229363) (xy 64.063364 -431.229363) (xy 64.063364 -431.158041)
			(xy 64.07135 -431.087167) (xy 64.08722 -431.017632) (xy 64.110777 -430.950312) (xy 64.141722 -430.886053)
			(xy 64.179668 -430.825662) (xy 64.224137 -430.7699) (xy 64.27457 -430.719467) (xy 64.330332 -430.674998)
			(xy 64.390723 -430.637052) (xy 64.454982 -430.606107) (xy 64.522302 -430.58255) (xy 64.591837 -430.56668)
			(xy 64.662711 -430.558694) (xy 64.698372 -430.558194) (xy 64.734033 -430.558694) (xy 64.804907 -430.56668)
			(xy 64.874442 -430.58255) (xy 64.941762 -430.606107) (xy 65.006021 -430.637052) (xy 65.066412 -430.674998)
			(xy 65.122174 -430.719467) (xy 65.172607 -430.7699) (xy 65.217076 -430.825662) (xy 65.255022 -430.886053)
			(xy 65.285967 -430.950312) (xy 65.309524 -431.017632) (xy 65.325394 -431.087167) (xy 65.33338 -431.158041)
			(xy 65.33338 -431.229363) (xy 66.867778 -431.229363) (xy 66.867778 -431.158041) (xy 66.875764 -431.087167)
			(xy 66.891634 -431.017632) (xy 66.915191 -430.950312) (xy 66.946136 -430.886053) (xy 66.984082 -430.825662)
			(xy 67.028551 -430.7699) (xy 67.078984 -430.719467) (xy 67.134746 -430.674998) (xy 67.195137 -430.637052)
			(xy 67.259396 -430.606107) (xy 67.326716 -430.58255) (xy 67.396251 -430.56668) (xy 67.467125 -430.558694)
			(xy 67.502786 -430.558194) (xy 67.538447 -430.558694) (xy 67.609321 -430.56668) (xy 67.678856 -430.58255)
			(xy 67.746176 -430.606107) (xy 67.810435 -430.637052) (xy 67.870826 -430.674998) (xy 67.926588 -430.719467)
			(xy 67.977021 -430.7699) (xy 68.02149 -430.825662) (xy 68.059436 -430.886053) (xy 68.090381 -430.950312)
			(xy 68.113938 -431.017632) (xy 68.129808 -431.087167) (xy 68.137794 -431.158041) (xy 68.137794 -431.229363)
			(xy 68.129808 -431.300237) (xy 68.113938 -431.369772) (xy 68.090381 -431.437092) (xy 68.059436 -431.501351)
			(xy 68.02149 -431.561742) (xy 67.977021 -431.617504) (xy 67.926588 -431.667937) (xy 67.870826 -431.712406)
			(xy 67.810435 -431.750352) (xy 67.746176 -431.781297) (xy 67.678856 -431.804854) (xy 67.609321 -431.820724)
			(xy 67.538447 -431.82871) (xy 67.467125 -431.82871) (xy 67.396251 -431.820724) (xy 67.326716 -431.804854)
			(xy 67.259396 -431.781297) (xy 67.195137 -431.750352) (xy 67.134746 -431.712406) (xy 67.078984 -431.667937)
			(xy 67.028551 -431.617504) (xy 66.984082 -431.561742) (xy 66.946136 -431.501351) (xy 66.915191 -431.437092)
			(xy 66.891634 -431.369772) (xy 66.875764 -431.300237) (xy 66.867778 -431.229363) (xy 65.33338 -431.229363)
			(xy 65.325394 -431.300237) (xy 65.309524 -431.369772) (xy 65.285967 -431.437092) (xy 65.255022 -431.501351)
			(xy 65.217076 -431.561742) (xy 65.172607 -431.617504) (xy 65.122174 -431.667937) (xy 65.066412 -431.712406)
			(xy 65.006021 -431.750352) (xy 64.941762 -431.781297) (xy 64.874442 -431.804854) (xy 64.804907 -431.820724)
			(xy 64.734033 -431.82871) (xy 64.662711 -431.82871) (xy 64.591837 -431.820724) (xy 64.522302 -431.804854)
			(xy 64.454982 -431.781297) (xy 64.390723 -431.750352) (xy 64.330332 -431.712406) (xy 64.27457 -431.667937)
			(xy 64.224137 -431.617504) (xy 64.179668 -431.561742) (xy 64.141722 -431.501351) (xy 64.110777 -431.437092)
			(xy 64.08722 -431.369772) (xy 64.07135 -431.300237) (xy 64.063364 -431.229363) (xy 40.417137 -431.229363)
			(xy 40.363503 -431.241604) (xy 40.292629 -431.24959) (xy 40.221307 -431.24959) (xy 40.150433 -431.241604)
			(xy 40.080898 -431.225734) (xy 40.013578 -431.202177) (xy 39.949319 -431.171232) (xy 39.888928 -431.133286)
			(xy 39.833166 -431.088817) (xy 39.782733 -431.038384) (xy 39.738264 -430.982622) (xy 39.700318 -430.922231)
			(xy 39.669373 -430.857972) (xy 39.645816 -430.790652) (xy 39.629946 -430.721117) (xy 39.62196 -430.650243)
			(xy 29.59608 -430.650243) (xy 29.59608 -430.822862) (xy 29.596592 -430.845182) (xy 29.604369 -430.889138)
			(xy 29.619706 -430.931059) (xy 29.642133 -430.969655) (xy 29.670959 -431.003739) (xy 29.705297 -431.032261)
			(xy 29.744091 -431.054344) (xy 29.786147 -431.069309) (xy 29.83017 -431.076695) (xy 29.874807 -431.076274)
			(xy 29.918684 -431.06806) (xy 29.96045 -431.052306) (xy 29.979874 -431.041302) (xy 30.017126 -431.019686)
			(xy 30.094912 -430.982692) (xy 30.175756 -430.952967) (xy 30.258979 -430.930759) (xy 30.343884 -430.916255)
			(xy 30.429759 -430.909577) (xy 30.515886 -430.910779) (xy 30.601542 -430.919853) (xy 30.686009 -430.936722)
			(xy 30.768579 -430.961244) (xy 30.848561 -430.993215) (xy 30.925284 -431.032366) (xy 30.998105 -431.07837)
			(xy 31.066414 -431.13084) (xy 31.129638 -431.189337) (xy 31.187248 -431.253371) (xy 31.238761 -431.322405)
			(xy 31.283745 -431.39586) (xy 31.321823 -431.473121) (xy 31.352675 -431.553541) (xy 31.376044 -431.636445)
			(xy 31.391734 -431.721139) (xy 31.399613 -431.806913) (xy 31.399615 -431.893048) (xy 31.399575 -431.893488)
			(xy 34.599874 -431.893488) (xy 34.599874 -431.806588) (xy 34.607892 -431.720059) (xy 34.62386 -431.634639)
			(xy 34.647641 -431.551057) (xy 34.679033 -431.470025) (xy 34.717767 -431.392236) (xy 34.763514 -431.318352)
			(xy 34.815883 -431.249005) (xy 34.874427 -431.184785) (xy 34.938647 -431.126241) (xy 35.007994 -431.073872)
			(xy 35.081878 -431.028125) (xy 35.159667 -430.989391) (xy 35.240699 -430.957999) (xy 35.324281 -430.934218)
			(xy 35.409701 -430.91825) (xy 35.49623 -430.910232) (xy 35.53968 -430.90973) (xy 35.58313 -430.910232)
			(xy 35.669659 -430.91825) (xy 35.755079 -430.934218) (xy 35.838661 -430.957999) (xy 35.919693 -430.989391)
			(xy 35.997482 -431.028125) (xy 36.071366 -431.073872) (xy 36.140713 -431.126241) (xy 36.204933 -431.184785)
			(xy 36.263477 -431.249005) (xy 36.315846 -431.318352) (xy 36.361593 -431.392236) (xy 36.400327 -431.470025)
			(xy 36.431719 -431.551057) (xy 36.4555 -431.634639) (xy 36.471468 -431.720059) (xy 36.479486 -431.806588)
			(xy 36.479486 -431.893488) (xy 36.471468 -431.980017) (xy 36.4555 -432.065437) (xy 36.431719 -432.149019)
			(xy 36.400327 -432.230051) (xy 36.361593 -432.30784) (xy 36.315846 -432.381724) (xy 36.263477 -432.451071)
			(xy 36.204933 -432.515291) (xy 36.140713 -432.573835) (xy 36.071366 -432.626204) (xy 35.997482 -432.671951)
			(xy 35.919693 -432.710685) (xy 35.838661 -432.742077) (xy 35.755079 -432.765858) (xy 35.669659 -432.781826)
			(xy 35.58313 -432.789844) (xy 35.49623 -432.789844) (xy 35.409701 -432.781826) (xy 35.324281 -432.765858)
			(xy 35.240699 -432.742077) (xy 35.159667 -432.710685) (xy 35.081878 -432.671951) (xy 35.007994 -432.626204)
			(xy 34.938647 -432.573835) (xy 34.874427 -432.515291) (xy 34.815883 -432.451071) (xy 34.763514 -432.381724)
			(xy 34.717767 -432.30784) (xy 34.679033 -432.230051) (xy 34.647641 -432.149019) (xy 34.62386 -432.065437)
			(xy 34.607892 -431.980017) (xy 34.599874 -431.893488) (xy 31.399575 -431.893488) (xy 31.391739 -431.978822)
			(xy 31.376053 -432.063517) (xy 31.352688 -432.146422) (xy 31.321838 -432.226843) (xy 31.283763 -432.304106)
			(xy 31.238783 -432.377563) (xy 31.187273 -432.446599) (xy 31.129665 -432.510635) (xy 31.066443 -432.569135)
			(xy 30.998137 -432.621608) (xy 30.925317 -432.667614) (xy 30.848596 -432.706769) (xy 30.768616 -432.738743)
			(xy 30.686046 -432.763269) (xy 30.60158 -432.780141) (xy 30.515925 -432.789219) (xy 30.429798 -432.790425)
			(xy 30.343922 -432.78375) (xy 30.259017 -432.769249) (xy 30.175793 -432.747045) (xy 30.094948 -432.717323)
			(xy 30.017161 -432.680332) (xy 29.979874 -432.658774) (xy 29.960453 -432.647773) (xy 29.918684 -432.632049)
			(xy 29.874811 -432.623859) (xy 29.830181 -432.623455) (xy 29.786167 -432.630849) (xy 29.74412 -432.645815)
			(xy 29.705332 -432.667893) (xy 29.670994 -432.696404) (xy 29.642162 -432.730472) (xy 29.619721 -432.769051)
			(xy 29.610668 -432.793749) (xy 39.62196 -432.793749) (xy 39.62196 -432.722427) (xy 39.629946 -432.651553)
			(xy 39.645816 -432.582018) (xy 39.669373 -432.514698) (xy 39.700318 -432.450439) (xy 39.738264 -432.390048)
			(xy 39.782733 -432.334286) (xy 39.833166 -432.283853) (xy 39.888928 -432.239384) (xy 39.949319 -432.201438)
			(xy 40.013578 -432.170493) (xy 40.080898 -432.146936) (xy 40.150433 -432.131066) (xy 40.221307 -432.12308)
			(xy 40.256968 -432.12258) (xy 40.292629 -432.12308) (xy 40.363503 -432.131066) (xy 40.433038 -432.146936)
			(xy 40.500358 -432.170493) (xy 40.564617 -432.201438) (xy 40.625008 -432.239384) (xy 40.68077 -432.283853)
			(xy 40.731203 -432.334286) (xy 40.775672 -432.390048) (xy 40.813618 -432.450439) (xy 40.844563 -432.514698)
			(xy 40.86812 -432.582018) (xy 40.88399 -432.651553) (xy 40.891976 -432.722427) (xy 40.891976 -432.793749)
			(xy 40.88399 -432.864623) (xy 40.86812 -432.934158) (xy 40.844563 -433.001478) (xy 40.813618 -433.065737)
			(xy 40.775672 -433.126128) (xy 40.731203 -433.18189) (xy 40.68077 -433.232323) (xy 40.625008 -433.276792)
			(xy 40.564617 -433.314738) (xy 40.500358 -433.345683) (xy 40.433038 -433.36924) (xy 40.363503 -433.38511)
			(xy 40.292629 -433.393096) (xy 40.221307 -433.393096) (xy 40.150433 -433.38511) (xy 40.080898 -433.36924)
			(xy 40.013578 -433.345683) (xy 39.949319 -433.314738) (xy 39.888928 -433.276792) (xy 39.833166 -433.232323)
			(xy 39.782733 -433.18189) (xy 39.738264 -433.126128) (xy 39.700318 -433.065737) (xy 39.669373 -433.001478)
			(xy 39.645816 -432.934158) (xy 39.629946 -432.864623) (xy 39.62196 -432.793749) (xy 29.610668 -432.793749)
			(xy 29.604361 -432.810956) (xy 29.596554 -432.854899) (xy 29.59608 -432.877214) (xy 29.59608 -433.362862)
			(xy 29.596592 -433.385182) (xy 29.604369 -433.429138) (xy 29.619706 -433.471059) (xy 29.642133 -433.509655)
			(xy 29.670959 -433.543739) (xy 29.705297 -433.572261) (xy 29.744091 -433.594344) (xy 29.786147 -433.609309)
			(xy 29.83017 -433.616695) (xy 29.874807 -433.616274) (xy 29.918684 -433.60806) (xy 29.96045 -433.592306)
			(xy 29.979874 -433.581302) (xy 30.017126 -433.559686) (xy 30.094912 -433.522692) (xy 30.175756 -433.492967)
			(xy 30.258979 -433.470759) (xy 30.343884 -433.456255) (xy 30.429759 -433.449577) (xy 30.515886 -433.450779)
			(xy 30.601542 -433.459853) (xy 30.686009 -433.476722) (xy 30.768579 -433.501244) (xy 30.848561 -433.533215)
			(xy 30.925284 -433.572366) (xy 30.998105 -433.61837) (xy 31.066414 -433.67084) (xy 31.129638 -433.729337)
			(xy 31.187248 -433.793371) (xy 31.238761 -433.862405) (xy 31.283745 -433.93586) (xy 31.321823 -434.013121)
			(xy 31.352675 -434.093541) (xy 31.376044 -434.176445) (xy 31.391734 -434.261139) (xy 31.399613 -434.346913)
			(xy 31.399615 -434.433048) (xy 31.399575 -434.433488) (xy 34.599874 -434.433488) (xy 34.599874 -434.346588)
			(xy 34.607892 -434.260059) (xy 34.62386 -434.174639) (xy 34.647641 -434.091057) (xy 34.679033 -434.010025)
			(xy 34.717767 -433.932236) (xy 34.763514 -433.858352) (xy 34.815883 -433.789005) (xy 34.874427 -433.724785)
			(xy 34.938647 -433.666241) (xy 35.007994 -433.613872) (xy 35.081878 -433.568125) (xy 35.159667 -433.529391)
			(xy 35.240699 -433.497999) (xy 35.324281 -433.474218) (xy 35.409701 -433.45825) (xy 35.49623 -433.450232)
			(xy 35.53968 -433.44973) (xy 35.58313 -433.450232) (xy 35.669659 -433.45825) (xy 35.755079 -433.474218)
			(xy 35.838661 -433.497999) (xy 35.919693 -433.529391) (xy 35.997482 -433.568125) (xy 36.050514 -433.600961)
			(xy 64.063364 -433.600961) (xy 64.063364 -433.529639) (xy 64.07135 -433.458765) (xy 64.08722 -433.38923)
			(xy 64.110777 -433.32191) (xy 64.141722 -433.257651) (xy 64.179668 -433.19726) (xy 64.224137 -433.141498)
			(xy 64.27457 -433.091065) (xy 64.330332 -433.046596) (xy 64.390723 -433.00865) (xy 64.454982 -432.977705)
			(xy 64.522302 -432.954148) (xy 64.591837 -432.938278) (xy 64.662711 -432.930292) (xy 64.698372 -432.929792)
			(xy 64.734033 -432.930292) (xy 64.804907 -432.938278) (xy 64.874442 -432.954148) (xy 64.941762 -432.977705)
			(xy 65.006021 -433.00865) (xy 65.066412 -433.046596) (xy 65.122174 -433.091065) (xy 65.172607 -433.141498)
			(xy 65.217076 -433.19726) (xy 65.255022 -433.257651) (xy 65.285967 -433.32191) (xy 65.309524 -433.38923)
			(xy 65.325394 -433.458765) (xy 65.33338 -433.529639) (xy 65.33338 -433.600961) (xy 66.867778 -433.600961)
			(xy 66.867778 -433.529639) (xy 66.875764 -433.458765) (xy 66.891634 -433.38923) (xy 66.915191 -433.32191)
			(xy 66.946136 -433.257651) (xy 66.984082 -433.19726) (xy 67.028551 -433.141498) (xy 67.078984 -433.091065)
			(xy 67.134746 -433.046596) (xy 67.195137 -433.00865) (xy 67.259396 -432.977705) (xy 67.326716 -432.954148)
			(xy 67.396251 -432.938278) (xy 67.467125 -432.930292) (xy 67.502786 -432.929792) (xy 67.538447 -432.930292)
			(xy 67.609321 -432.938278) (xy 67.678856 -432.954148) (xy 67.746176 -432.977705) (xy 67.810435 -433.00865)
			(xy 67.870826 -433.046596) (xy 67.926588 -433.091065) (xy 67.977021 -433.141498) (xy 68.02149 -433.19726)
			(xy 68.059436 -433.257651) (xy 68.090381 -433.32191) (xy 68.113938 -433.38923) (xy 68.129808 -433.458765)
			(xy 68.137794 -433.529639) (xy 68.137794 -433.600961) (xy 68.129808 -433.671835) (xy 68.113938 -433.74137)
			(xy 68.090381 -433.80869) (xy 68.059436 -433.872949) (xy 68.02149 -433.93334) (xy 67.977021 -433.989102)
			(xy 67.926588 -434.039535) (xy 67.870826 -434.084004) (xy 67.810435 -434.12195) (xy 67.746176 -434.152895)
			(xy 67.678856 -434.176452) (xy 67.609321 -434.192322) (xy 67.538447 -434.200308) (xy 67.467125 -434.200308)
			(xy 67.396251 -434.192322) (xy 67.326716 -434.176452) (xy 67.259396 -434.152895) (xy 67.195137 -434.12195)
			(xy 67.134746 -434.084004) (xy 67.078984 -434.039535) (xy 67.028551 -433.989102) (xy 66.984082 -433.93334)
			(xy 66.946136 -433.872949) (xy 66.915191 -433.80869) (xy 66.891634 -433.74137) (xy 66.875764 -433.671835)
			(xy 66.867778 -433.600961) (xy 65.33338 -433.600961) (xy 65.325394 -433.671835) (xy 65.309524 -433.74137)
			(xy 65.285967 -433.80869) (xy 65.255022 -433.872949) (xy 65.217076 -433.93334) (xy 65.172607 -433.989102)
			(xy 65.122174 -434.039535) (xy 65.066412 -434.084004) (xy 65.006021 -434.12195) (xy 64.941762 -434.152895)
			(xy 64.874442 -434.176452) (xy 64.804907 -434.192322) (xy 64.734033 -434.200308) (xy 64.662711 -434.200308)
			(xy 64.591837 -434.192322) (xy 64.522302 -434.176452) (xy 64.454982 -434.152895) (xy 64.390723 -434.12195)
			(xy 64.330332 -434.084004) (xy 64.27457 -434.039535) (xy 64.224137 -433.989102) (xy 64.179668 -433.93334)
			(xy 64.141722 -433.872949) (xy 64.110777 -433.80869) (xy 64.08722 -433.74137) (xy 64.07135 -433.671835)
			(xy 64.063364 -433.600961) (xy 36.050514 -433.600961) (xy 36.071366 -433.613872) (xy 36.140713 -433.666241)
			(xy 36.204933 -433.724785) (xy 36.263477 -433.789005) (xy 36.315846 -433.858352) (xy 36.361593 -433.932236)
			(xy 36.400327 -434.010025) (xy 36.431719 -434.091057) (xy 36.4555 -434.174639) (xy 36.471468 -434.260059)
			(xy 36.479486 -434.346588) (xy 36.479486 -434.433488) (xy 36.471468 -434.520017) (xy 36.4555 -434.605437)
			(xy 36.431719 -434.689019) (xy 36.400327 -434.770051) (xy 36.361593 -434.84784) (xy 36.315846 -434.921724)
			(xy 36.263477 -434.991071) (xy 36.204933 -435.055291) (xy 36.140713 -435.113835) (xy 36.071366 -435.166204)
			(xy 35.997482 -435.211951) (xy 35.919693 -435.250685) (xy 35.838661 -435.282077) (xy 35.755079 -435.305858)
			(xy 35.669659 -435.321826) (xy 35.58313 -435.329844) (xy 35.49623 -435.329844) (xy 35.409701 -435.321826)
			(xy 35.324281 -435.305858) (xy 35.240699 -435.282077) (xy 35.159667 -435.250685) (xy 35.081878 -435.211951)
			(xy 35.007994 -435.166204) (xy 34.938647 -435.113835) (xy 34.874427 -435.055291) (xy 34.815883 -434.991071)
			(xy 34.763514 -434.921724) (xy 34.717767 -434.84784) (xy 34.679033 -434.770051) (xy 34.647641 -434.689019)
			(xy 34.62386 -434.605437) (xy 34.607892 -434.520017) (xy 34.599874 -434.433488) (xy 31.399575 -434.433488)
			(xy 31.391739 -434.518822) (xy 31.376053 -434.603517) (xy 31.352688 -434.686422) (xy 31.321838 -434.766843)
			(xy 31.283763 -434.844106) (xy 31.238783 -434.917563) (xy 31.187273 -434.986599) (xy 31.129665 -435.050635)
			(xy 31.066443 -435.109135) (xy 30.998137 -435.161608) (xy 30.925317 -435.207614) (xy 30.848596 -435.246769)
			(xy 30.768616 -435.278743) (xy 30.686046 -435.303269) (xy 30.60158 -435.320141) (xy 30.515925 -435.329219)
			(xy 30.429798 -435.330425) (xy 30.343922 -435.32375) (xy 30.259017 -435.309249) (xy 30.175793 -435.287045)
			(xy 30.094948 -435.257323) (xy 30.017161 -435.220332) (xy 29.979874 -435.198774) (xy 29.960453 -435.187773)
			(xy 29.918684 -435.172049) (xy 29.874811 -435.163859) (xy 29.830181 -435.163455) (xy 29.786167 -435.170849)
			(xy 29.74412 -435.185815) (xy 29.705332 -435.207893) (xy 29.670994 -435.236404) (xy 29.642162 -435.270472)
			(xy 29.619721 -435.309051) (xy 29.604361 -435.350956) (xy 29.596554 -435.394899) (xy 29.59608 -435.417214)
			(xy 29.59608 -435.563873) (xy 64.063364 -435.563873) (xy 64.063364 -435.492551) (xy 64.07135 -435.421677)
			(xy 64.08722 -435.352142) (xy 64.110777 -435.284822) (xy 64.141722 -435.220563) (xy 64.179668 -435.160172)
			(xy 64.224137 -435.10441) (xy 64.27457 -435.053977) (xy 64.330332 -435.009508) (xy 64.390723 -434.971562)
			(xy 64.454982 -434.940617) (xy 64.522302 -434.91706) (xy 64.591837 -434.90119) (xy 64.662711 -434.893204)
			(xy 64.698372 -434.892704) (xy 64.734033 -434.893204) (xy 64.804907 -434.90119) (xy 64.874442 -434.91706)
			(xy 64.941762 -434.940617) (xy 65.006021 -434.971562) (xy 65.066412 -435.009508) (xy 65.122174 -435.053977)
			(xy 65.172607 -435.10441) (xy 65.217076 -435.160172) (xy 65.255022 -435.220563) (xy 65.285967 -435.284822)
			(xy 65.309524 -435.352142) (xy 65.325394 -435.421677) (xy 65.33338 -435.492551) (xy 65.33338 -435.563873)
			(xy 66.867778 -435.563873) (xy 66.867778 -435.492551) (xy 66.875764 -435.421677) (xy 66.891634 -435.352142)
			(xy 66.915191 -435.284822) (xy 66.946136 -435.220563) (xy 66.984082 -435.160172) (xy 67.028551 -435.10441)
			(xy 67.078984 -435.053977) (xy 67.134746 -435.009508) (xy 67.195137 -434.971562) (xy 67.259396 -434.940617)
			(xy 67.326716 -434.91706) (xy 67.396251 -434.90119) (xy 67.467125 -434.893204) (xy 67.502786 -434.892704)
			(xy 67.538447 -434.893204) (xy 67.609321 -434.90119) (xy 67.678856 -434.91706) (xy 67.746176 -434.940617)
			(xy 67.810435 -434.971562) (xy 67.870826 -435.009508) (xy 67.926588 -435.053977) (xy 67.977021 -435.10441)
			(xy 68.02149 -435.160172) (xy 68.059436 -435.220563) (xy 68.090381 -435.284822) (xy 68.113938 -435.352142)
			(xy 68.129808 -435.421677) (xy 68.137794 -435.492551) (xy 68.137794 -435.563873) (xy 68.129808 -435.634747)
			(xy 68.113938 -435.704282) (xy 68.090381 -435.771602) (xy 68.059436 -435.835861) (xy 68.02149 -435.896252)
			(xy 67.977021 -435.952014) (xy 67.926588 -436.002447) (xy 67.870826 -436.046916) (xy 67.810435 -436.084862)
			(xy 67.746176 -436.115807) (xy 67.678856 -436.139364) (xy 67.609321 -436.155234) (xy 67.538447 -436.16322)
			(xy 67.467125 -436.16322) (xy 67.396251 -436.155234) (xy 67.326716 -436.139364) (xy 67.259396 -436.115807)
			(xy 67.195137 -436.084862) (xy 67.134746 -436.046916) (xy 67.078984 -436.002447) (xy 67.028551 -435.952014)
			(xy 66.984082 -435.896252) (xy 66.946136 -435.835861) (xy 66.915191 -435.771602) (xy 66.891634 -435.704282)
			(xy 66.875764 -435.634747) (xy 66.867778 -435.563873) (xy 65.33338 -435.563873) (xy 65.325394 -435.634747)
			(xy 65.309524 -435.704282) (xy 65.285967 -435.771602) (xy 65.255022 -435.835861) (xy 65.217076 -435.896252)
			(xy 65.172607 -435.952014) (xy 65.122174 -436.002447) (xy 65.066412 -436.046916) (xy 65.006021 -436.084862)
			(xy 64.941762 -436.115807) (xy 64.874442 -436.139364) (xy 64.804907 -436.155234) (xy 64.734033 -436.16322)
			(xy 64.662711 -436.16322) (xy 64.591837 -436.155234) (xy 64.522302 -436.139364) (xy 64.454982 -436.115807)
			(xy 64.390723 -436.084862) (xy 64.330332 -436.046916) (xy 64.27457 -436.002447) (xy 64.224137 -435.952014)
			(xy 64.179668 -435.896252) (xy 64.141722 -435.835861) (xy 64.110777 -435.771602) (xy 64.08722 -435.704282)
			(xy 64.07135 -435.634747) (xy 64.063364 -435.563873) (xy 29.59608 -435.563873) (xy 29.59608 -435.902862)
			(xy 29.596592 -435.925182) (xy 29.604369 -435.969138) (xy 29.619706 -436.011059) (xy 29.642133 -436.049655)
			(xy 29.670959 -436.083739) (xy 29.705297 -436.112261) (xy 29.744091 -436.134344) (xy 29.786147 -436.149309)
			(xy 29.83017 -436.156695) (xy 29.874807 -436.156274) (xy 29.918684 -436.14806) (xy 29.96045 -436.132306)
			(xy 29.979874 -436.121302) (xy 30.017952 -436.099297) (xy 30.097456 -436.061685) (xy 30.180125 -436.031661)
			(xy 30.265237 -436.009488) (xy 30.352047 -435.99536) (xy 30.439797 -435.989401) (xy 30.52772 -435.991661)
			(xy 30.615048 -436.002123) (xy 30.701017 -436.020694) (xy 30.784876 -436.047212) (xy 30.865893 -436.081445)
			(xy 30.943359 -436.123094) (xy 31.016597 -436.171795) (xy 31.084966 -436.227123) (xy 31.147871 -436.288593)
			(xy 31.20476 -436.355669) (xy 31.255137 -436.427765) (xy 31.298561 -436.50425) (xy 31.334653 -436.584455)
			(xy 31.363098 -436.667681) (xy 31.383646 -436.753199) (xy 31.396118 -436.840263) (xy 31.400406 -436.92811)
			(xy 31.398374 -436.973488) (xy 34.599874 -436.973488) (xy 34.599874 -436.886588) (xy 34.607892 -436.800059)
			(xy 34.62386 -436.714639) (xy 34.647641 -436.631057) (xy 34.679033 -436.550025) (xy 34.717767 -436.472236)
			(xy 34.763514 -436.398352) (xy 34.815883 -436.329005) (xy 34.874427 -436.264785) (xy 34.938647 -436.206241)
			(xy 35.007994 -436.153872) (xy 35.081878 -436.108125) (xy 35.159667 -436.069391) (xy 35.240699 -436.037999)
			(xy 35.324281 -436.014218) (xy 35.409701 -435.99825) (xy 35.49623 -435.990232) (xy 35.53968 -435.98973)
			(xy 35.58313 -435.990232) (xy 35.669659 -435.99825) (xy 35.755079 -436.014218) (xy 35.838661 -436.037999)
			(xy 35.919693 -436.069391) (xy 35.997482 -436.108125) (xy 36.071366 -436.153872) (xy 36.140713 -436.206241)
			(xy 36.204933 -436.264785) (xy 36.263477 -436.329005) (xy 36.315846 -436.398352) (xy 36.361593 -436.472236)
			(xy 36.400327 -436.550025) (xy 36.431719 -436.631057) (xy 36.4555 -436.714639) (xy 36.471468 -436.800059)
			(xy 36.479486 -436.886588) (xy 36.479486 -436.973488) (xy 36.471468 -437.060017) (xy 36.4555 -437.145437)
			(xy 36.431719 -437.229019) (xy 36.400327 -437.310051) (xy 36.361593 -437.38784) (xy 36.317396 -437.459221)
			(xy 63.99707 -437.459221) (xy 63.99707 -437.387899) (xy 64.005056 -437.317025) (xy 64.020926 -437.24749)
			(xy 64.044483 -437.18017) (xy 64.075428 -437.115911) (xy 64.113374 -437.05552) (xy 64.157843 -436.999758)
			(xy 64.208276 -436.949325) (xy 64.264038 -436.904856) (xy 64.324429 -436.86691) (xy 64.388688 -436.835965)
			(xy 64.456008 -436.812408) (xy 64.525543 -436.796538) (xy 64.596417 -436.788552) (xy 64.632078 -436.788052)
			(xy 64.667739 -436.788552) (xy 64.738613 -436.796538) (xy 64.808148 -436.812408) (xy 64.875468 -436.835965)
			(xy 64.939727 -436.86691) (xy 65.000118 -436.904856) (xy 65.05588 -436.949325) (xy 65.106313 -436.999758)
			(xy 65.150782 -437.05552) (xy 65.188728 -437.115911) (xy 65.219673 -437.18017) (xy 65.24323 -437.24749)
			(xy 65.2591 -437.317025) (xy 65.267086 -437.387899) (xy 65.267086 -437.459221) (xy 66.801484 -437.459221)
			(xy 66.801484 -437.387899) (xy 66.80947 -437.317025) (xy 66.82534 -437.24749) (xy 66.848897 -437.18017)
			(xy 66.879842 -437.115911) (xy 66.917788 -437.05552) (xy 66.962257 -436.999758) (xy 67.01269 -436.949325)
			(xy 67.068452 -436.904856) (xy 67.128843 -436.86691) (xy 67.193102 -436.835965) (xy 67.260422 -436.812408)
			(xy 67.329957 -436.796538) (xy 67.400831 -436.788552) (xy 67.436492 -436.788052) (xy 67.472153 -436.788552)
			(xy 67.543027 -436.796538) (xy 67.612562 -436.812408) (xy 67.679882 -436.835965) (xy 67.744141 -436.86691)
			(xy 67.804532 -436.904856) (xy 67.860294 -436.949325) (xy 67.910727 -436.999758) (xy 67.955196 -437.05552)
			(xy 67.993142 -437.115911) (xy 68.024087 -437.18017) (xy 68.047644 -437.24749) (xy 68.063514 -437.317025)
			(xy 68.0715 -437.387899) (xy 68.0715 -437.459221) (xy 68.063514 -437.530095) (xy 68.047644 -437.59963)
			(xy 68.024087 -437.66695) (xy 67.993142 -437.731209) (xy 67.955196 -437.7916) (xy 67.910727 -437.847362)
			(xy 67.860294 -437.897795) (xy 67.804532 -437.942264) (xy 67.744141 -437.98021) (xy 67.679882 -438.011155)
			(xy 67.612562 -438.034712) (xy 67.543027 -438.050582) (xy 67.472153 -438.058568) (xy 67.400831 -438.058568)
			(xy 67.329957 -438.050582) (xy 67.260422 -438.034712) (xy 67.193102 -438.011155) (xy 67.128843 -437.98021)
			(xy 67.068452 -437.942264) (xy 67.01269 -437.897795) (xy 66.962257 -437.847362) (xy 66.917788 -437.7916)
			(xy 66.879842 -437.731209) (xy 66.848897 -437.66695) (xy 66.82534 -437.59963) (xy 66.80947 -437.530095)
			(xy 66.801484 -437.459221) (xy 65.267086 -437.459221) (xy 65.2591 -437.530095) (xy 65.24323 -437.59963)
			(xy 65.219673 -437.66695) (xy 65.188728 -437.731209) (xy 65.150782 -437.7916) (xy 65.106313 -437.847362)
			(xy 65.05588 -437.897795) (xy 65.000118 -437.942264) (xy 64.939727 -437.98021) (xy 64.875468 -438.011155)
			(xy 64.808148 -438.034712) (xy 64.738613 -438.050582) (xy 64.667739 -438.058568) (xy 64.596417 -438.058568)
			(xy 64.525543 -438.050582) (xy 64.456008 -438.034712) (xy 64.388688 -438.011155) (xy 64.324429 -437.98021)
			(xy 64.264038 -437.942264) (xy 64.208276 -437.897795) (xy 64.157843 -437.847362) (xy 64.113374 -437.7916)
			(xy 64.075428 -437.731209) (xy 64.044483 -437.66695) (xy 64.020926 -437.59963) (xy 64.005056 -437.530095)
			(xy 63.99707 -437.459221) (xy 36.317396 -437.459221) (xy 36.315846 -437.461724) (xy 36.263477 -437.531071)
			(xy 36.204933 -437.595291) (xy 36.140713 -437.653835) (xy 36.071366 -437.706204) (xy 35.997482 -437.751951)
			(xy 35.919693 -437.790685) (xy 35.838661 -437.822077) (xy 35.755079 -437.845858) (xy 35.669659 -437.861826)
			(xy 35.58313 -437.869844) (xy 35.49623 -437.869844) (xy 35.409701 -437.861826) (xy 35.324281 -437.845858)
			(xy 35.240699 -437.822077) (xy 35.159667 -437.790685) (xy 35.081878 -437.751951) (xy 35.007994 -437.706204)
			(xy 34.938647 -437.653835) (xy 34.874427 -437.595291) (xy 34.815883 -437.531071) (xy 34.763514 -437.461724)
			(xy 34.717767 -437.38784) (xy 34.679033 -437.310051) (xy 34.647641 -437.229019) (xy 34.62386 -437.145437)
			(xy 34.607892 -437.060017) (xy 34.599874 -436.973488) (xy 31.398374 -436.973488) (xy 31.396471 -437.015974)
			(xy 31.384349 -437.103087) (xy 31.364144 -437.188687) (xy 31.336035 -437.272026) (xy 31.300265 -437.352377)
			(xy 31.257148 -437.429035) (xy 31.207062 -437.501332) (xy 31.150442 -437.568637) (xy 31.087785 -437.630359)
			(xy 31.019638 -437.685961) (xy 30.946596 -437.734956) (xy 30.869299 -437.776916) (xy 30.78842 -437.811474)
			(xy 30.7467 -437.825388) (xy 30.726205 -437.832449) (xy 30.687781 -437.852506) (xy 30.653315 -437.878789)
			(xy 30.623806 -437.910536) (xy 30.600109 -437.946828) (xy 30.582909 -437.986614) (xy 30.572707 -438.02874)
			(xy 30.569796 -438.071986) (xy 30.574262 -438.115099) (xy 30.585975 -438.156831) (xy 30.604596 -438.195971)
			(xy 30.629585 -438.231386) (xy 30.644592 -438.247028) (xy 32.540974 -440.14341) (xy 41.726865 -440.14341)
			(xy 41.732965 -440.087973) (xy 41.747071 -440.034016) (xy 41.768883 -439.982687) (xy 41.797937 -439.935081)
			(xy 41.833612 -439.892213) (xy 41.875149 -439.854996) (xy 41.921662 -439.824223) (xy 41.972159 -439.800551)
			(xy 42.025566 -439.784483) (xy 42.080742 -439.776363) (xy 42.108628 -439.775854) (xy 42.136514 -439.776363)
			(xy 42.19169 -439.784483) (xy 42.245097 -439.800551) (xy 42.251834 -439.803709) (xy 51.342788 -439.803709)
			(xy 51.342788 -439.722599) (xy 51.350738 -439.64188) (xy 51.366561 -439.562329) (xy 51.390106 -439.484713)
			(xy 51.421145 -439.409777) (xy 51.45938 -439.338245) (xy 51.504442 -439.270805) (xy 51.555897 -439.208106)
			(xy 51.61325 -439.150753) (xy 51.675949 -439.099298) (xy 51.743389 -439.054236) (xy 51.814921 -439.016001)
			(xy 51.889857 -438.984962) (xy 51.967473 -438.961417) (xy 52.047024 -438.945594) (xy 52.127743 -438.937644)
			(xy 52.168298 -438.937146) (xy 52.208853 -438.937644) (xy 52.289572 -438.945594) (xy 52.369123 -438.961417)
			(xy 52.446739 -438.984962) (xy 52.521675 -439.016001) (xy 52.593207 -439.054236) (xy 52.660647 -439.099298)
			(xy 52.723346 -439.150753) (xy 52.780699 -439.208106) (xy 52.832154 -439.270805) (xy 52.877216 -439.338245)
			(xy 52.915451 -439.409777) (xy 52.94649 -439.484713) (xy 52.970035 -439.562329) (xy 52.985858 -439.64188)
			(xy 52.993808 -439.722599) (xy 52.993808 -439.803709) (xy 52.985858 -439.884428) (xy 52.970035 -439.963979)
			(xy 52.94649 -440.041595) (xy 52.915451 -440.116531) (xy 52.877216 -440.188063) (xy 52.832154 -440.255503)
			(xy 52.780699 -440.318202) (xy 52.723346 -440.375555) (xy 52.660647 -440.42701) (xy 52.593207 -440.472072)
			(xy 52.521675 -440.510307) (xy 52.446739 -440.541346) (xy 52.369123 -440.564891) (xy 52.289572 -440.580714)
			(xy 52.208853 -440.588664) (xy 52.127743 -440.588664) (xy 52.047024 -440.580714) (xy 51.967473 -440.564891)
			(xy 51.889857 -440.541346) (xy 51.814921 -440.510307) (xy 51.743389 -440.472072) (xy 51.675949 -440.42701)
			(xy 51.61325 -440.375555) (xy 51.555897 -440.318202) (xy 51.504442 -440.255503) (xy 51.45938 -440.188063)
			(xy 51.421145 -440.116531) (xy 51.390106 -440.041595) (xy 51.366561 -439.963979) (xy 51.350738 -439.884428)
			(xy 51.342788 -439.803709) (xy 42.251834 -439.803709) (xy 42.295594 -439.824223) (xy 42.342107 -439.854996)
			(xy 42.383644 -439.892213) (xy 42.419319 -439.935081) (xy 42.448373 -439.982687) (xy 42.470185 -440.034016)
			(xy 42.484291 -440.087973) (xy 42.490391 -440.14341) (xy 42.488354 -440.199144) (xy 42.478224 -440.253987)
			(xy 42.460217 -440.306771) (xy 42.434716 -440.356371) (xy 42.402265 -440.401729) (xy 42.363556 -440.441878)
			(xy 42.319413 -440.475964) (xy 42.270778 -440.50326) (xy 42.218687 -440.523183) (xy 42.16425 -440.535309)
			(xy 42.108628 -440.53938) (xy 42.053006 -440.535309) (xy 41.998569 -440.523183) (xy 41.946478 -440.50326)
			(xy 41.897843 -440.475964) (xy 41.8537 -440.441878) (xy 41.814991 -440.401729) (xy 41.78254 -440.356371)
			(xy 41.757039 -440.306771) (xy 41.739032 -440.253987) (xy 41.728902 -440.199144) (xy 41.726865 -440.14341)
			(xy 32.540974 -440.14341) (xy 33.134572 -440.737008) (xy 39.288719 -440.737008) (xy 39.294819 -440.681571)
			(xy 39.308925 -440.627614) (xy 39.330737 -440.576285) (xy 39.359791 -440.528679) (xy 39.395466 -440.485811)
			(xy 39.437003 -440.448594) (xy 39.483516 -440.417821) (xy 39.534013 -440.394149) (xy 39.58742 -440.378081)
			(xy 39.642596 -440.369961) (xy 39.670482 -440.369452) (xy 39.698368 -440.369961) (xy 39.753544 -440.378081)
			(xy 39.806951 -440.394149) (xy 39.857448 -440.417821) (xy 39.903961 -440.448594) (xy 39.945498 -440.485811)
			(xy 39.981173 -440.528679) (xy 40.010227 -440.576285) (xy 40.032039 -440.627614) (xy 40.046145 -440.681571)
			(xy 40.052245 -440.737008) (xy 40.050208 -440.792742) (xy 40.040078 -440.847585) (xy 40.022071 -440.900369)
			(xy 40.000152 -440.943002) (xy 43.660313 -440.943002) (xy 43.666413 -440.887565) (xy 43.680519 -440.833608)
			(xy 43.702331 -440.782279) (xy 43.731385 -440.734673) (xy 43.76706 -440.691805) (xy 43.808597 -440.654588)
			(xy 43.85511 -440.623815) (xy 43.905607 -440.600143) (xy 43.959014 -440.584075) (xy 44.01419 -440.575955)
			(xy 44.042076 -440.575446) (xy 44.069962 -440.575955) (xy 44.125138 -440.584075) (xy 44.178545 -440.600143)
			(xy 44.229042 -440.623815) (xy 44.275555 -440.654588) (xy 44.317092 -440.691805) (xy 44.352767 -440.734673)
			(xy 44.381821 -440.782279) (xy 44.403633 -440.833608) (xy 44.417739 -440.887565) (xy 44.423839 -440.943002)
			(xy 44.421802 -440.998736) (xy 44.411672 -441.053579) (xy 44.393665 -441.106363) (xy 44.368164 -441.155963)
			(xy 44.335713 -441.201321) (xy 44.297004 -441.24147) (xy 44.252861 -441.275556) (xy 44.204226 -441.302852)
			(xy 44.152135 -441.322775) (xy 44.097698 -441.334901) (xy 44.042076 -441.338972) (xy 43.986454 -441.334901)
			(xy 43.932017 -441.322775) (xy 43.879926 -441.302852) (xy 43.831291 -441.275556) (xy 43.787148 -441.24147)
			(xy 43.748439 -441.201321) (xy 43.715988 -441.155963) (xy 43.690487 -441.106363) (xy 43.67248 -441.053579)
			(xy 43.66235 -440.998736) (xy 43.660313 -440.943002) (xy 40.000152 -440.943002) (xy 39.99657 -440.949969)
			(xy 39.964119 -440.995327) (xy 39.92541 -441.035476) (xy 39.881267 -441.069562) (xy 39.832632 -441.096858)
			(xy 39.780541 -441.116781) (xy 39.726104 -441.128907) (xy 39.670482 -441.132978) (xy 39.61486 -441.128907)
			(xy 39.560423 -441.116781) (xy 39.508332 -441.096858) (xy 39.459697 -441.069562) (xy 39.415554 -441.035476)
			(xy 39.376845 -440.995327) (xy 39.344394 -440.949969) (xy 39.318893 -440.900369) (xy 39.300886 -440.847585)
			(xy 39.290756 -440.792742) (xy 39.288719 -440.737008) (xy 33.134572 -440.737008) (xy 33.583898 -441.186334)
			(xy 37.796723 -441.186334) (xy 37.802823 -441.130897) (xy 37.816929 -441.07694) (xy 37.838741 -441.025611)
			(xy 37.867795 -440.978005) (xy 37.90347 -440.935137) (xy 37.945007 -440.89792) (xy 37.99152 -440.867147)
			(xy 38.042017 -440.843475) (xy 38.095424 -440.827407) (xy 38.1506 -440.819287) (xy 38.178486 -440.818778)
			(xy 38.206372 -440.819287) (xy 38.261548 -440.827407) (xy 38.314955 -440.843475) (xy 38.365452 -440.867147)
			(xy 38.411965 -440.89792) (xy 38.453502 -440.935137) (xy 38.489177 -440.978005) (xy 38.518231 -441.025611)
			(xy 38.540043 -441.07694) (xy 38.554149 -441.130897) (xy 38.560249 -441.186334) (xy 38.558212 -441.242068)
			(xy 38.548082 -441.296911) (xy 38.530075 -441.349695) (xy 38.504574 -441.399295) (xy 38.472123 -441.444653)
			(xy 38.433414 -441.484802) (xy 38.389271 -441.518888) (xy 38.340636 -441.546184) (xy 38.288545 -441.566107)
			(xy 38.234108 -441.578233) (xy 38.178486 -441.582304) (xy 38.122864 -441.578233) (xy 38.068427 -441.566107)
			(xy 38.016336 -441.546184) (xy 37.967701 -441.518888) (xy 37.923558 -441.484802) (xy 37.884849 -441.444653)
			(xy 37.852398 -441.399295) (xy 37.826897 -441.349695) (xy 37.80889 -441.296911) (xy 37.79876 -441.242068)
			(xy 37.796723 -441.186334) (xy 33.583898 -441.186334) (xy 34.288984 -441.89142) (xy 36.164266 -441.89142)
			(xy 36.185719 -441.891016) (xy 36.228017 -441.883828) (xy 36.268507 -441.869635) (xy 36.306035 -441.848839)
			(xy 36.339535 -441.822033) (xy 36.368054 -441.789978) (xy 36.390781 -441.753587) (xy 36.40707 -441.713894)
			(xy 36.416457 -441.672029) (xy 36.418012 -441.650628) (xy 36.41995 -441.623097) (xy 36.430764 -441.568976)
			(xy 36.449262 -441.516978) (xy 36.47506 -441.468189) (xy 36.507618 -441.423625) (xy 36.546258 -441.384218)
			(xy 36.590172 -441.350789) (xy 36.638445 -441.324036) (xy 36.690069 -441.304518) (xy 36.743966 -441.292642)
			(xy 36.799012 -441.288655) (xy 36.854058 -441.292642) (xy 36.907955 -441.304518) (xy 36.959579 -441.324036)
			(xy 37.007852 -441.350789) (xy 37.051766 -441.384218) (xy 37.090406 -441.423625) (xy 37.122964 -441.468189)
			(xy 37.148762 -441.516978) (xy 37.16726 -441.568976) (xy 37.178074 -441.623097) (xy 37.180012 -441.650628)
			(xy 37.181599 -441.672021) (xy 37.191008 -441.713869) (xy 37.207309 -441.753543) (xy 37.230039 -441.789918)
			(xy 37.258554 -441.82196) (xy 37.292043 -441.848761) (xy 37.329556 -441.869558) (xy 37.370029 -441.883763)
			(xy 37.412312 -441.890971) (xy 37.433758 -441.89142) (xy 40.89781 -441.89142) (xy 40.921272 -441.890853)
			(xy 40.967399 -441.882238) (xy 41.01116 -441.865302) (xy 41.051068 -441.84062) (xy 41.085768 -441.809032)
			(xy 41.11408 -441.771611) (xy 41.135041 -441.729629) (xy 41.14794 -441.684512) (xy 41.152338 -441.637794)
			(xy 41.148085 -441.591063) (xy 41.135326 -441.545907) (xy 41.125394 -441.524644) (xy 41.113543 -441.499616)
			(xy 41.096386 -441.446966) (xy 41.08702 -441.392388) (xy 41.085642 -441.33703) (xy 41.092281 -441.282054)
			(xy 41.106797 -441.228615) (xy 41.128885 -441.177836) (xy 41.158082 -441.130783) (xy 41.193773 -441.088445)
			(xy 41.23521 -441.051711) (xy 41.281522 -441.021352) (xy 41.331736 -440.998007) (xy 41.384797 -440.982166)
			(xy 41.43959 -440.974161) (xy 41.494966 -440.974161) (xy 41.549759 -440.982166) (xy 41.60282 -440.998007)
			(xy 41.653034 -441.021352) (xy 41.699346 -441.051711) (xy 41.740783 -441.088445) (xy 41.776474 -441.130783)
			(xy 41.805671 -441.177836) (xy 41.827759 -441.228615) (xy 41.842275 -441.282054) (xy 41.848914 -441.33703)
			(xy 41.847536 -441.392388) (xy 41.83817 -441.446966) (xy 41.821013 -441.499616) (xy 41.809162 -441.524644)
			(xy 41.799157 -441.545878) (xy 41.786392 -441.591045) (xy 41.782136 -441.637788) (xy 41.786535 -441.684518)
			(xy 41.799437 -441.729646) (xy 41.820406 -441.771638) (xy 41.848728 -441.809066) (xy 41.88344 -441.840659)
			(xy 41.923362 -441.865342) (xy 41.967138 -441.882275) (xy 42.013278 -441.890884) (xy 42.036746 -441.89142)
			(xy 42.201846 -441.89142) (xy 42.218495 -441.890897) (xy 42.250655 -441.88227) (xy 42.279489 -441.865616)
			(xy 42.303032 -441.842068) (xy 42.31968 -441.813231) (xy 42.328301 -441.781069) (xy 42.328846 -441.76442)
			(xy 42.328846 -441.762896) (xy 42.32903 -441.735454) (xy 42.336313 -441.681061) (xy 42.351315 -441.628273)
			(xy 42.373724 -441.57818) (xy 42.40308 -441.531813) (xy 42.438776 -441.490131) (xy 42.480075 -441.453994)
			(xy 42.526126 -441.424146) (xy 42.575978 -441.401204) (xy 42.628603 -441.385641) (xy 42.682915 -441.377778)
			(xy 42.737793 -441.377778) (xy 42.792105 -441.385641) (xy 42.84473 -441.401204) (xy 42.894582 -441.424146)
			(xy 42.940633 -441.453994) (xy 42.981932 -441.490131) (xy 43.017628 -441.531813) (xy 43.046984 -441.57818)
			(xy 43.069393 -441.628273) (xy 43.084395 -441.681061) (xy 43.091678 -441.735454) (xy 43.091862 -441.762896)
			(xy 43.091862 -441.76442) (xy 43.092425 -441.781066) (xy 43.101045 -441.813223) (xy 43.117691 -441.842055)
			(xy 43.14123 -441.865598) (xy 43.17006 -441.882248) (xy 43.202216 -441.890872) (xy 43.218862 -441.89142)
			(xy 74.34199 -441.89142) (xy 74.358607 -441.89088) (xy 74.390709 -441.88228) (xy 74.419504 -441.865687)
			(xy 74.431652 -441.854336) (xy 75.564238 -440.721496) (xy 89.11336 -440.721496) (xy 99.10064 -450.708776)
			(xy 99.10064 -484.701596) (xy 96.744028 -487.058208) (xy 96.735138 -487.089704) (xy 96.727075 -487.116078)
			(xy 96.70437 -487.166337) (xy 96.674667 -487.212804) (xy 96.638583 -487.254512) (xy 96.596872 -487.29059)
			(xy 96.550402 -487.320289) (xy 96.500141 -487.342989) (xy 96.473772 -487.35107) (xy 96.442276 -487.35996)
			(xy 92.344748 -491.457234) (xy 92.33341 -491.469394) (xy 92.316803 -491.498179) (xy 92.308206 -491.53028)
			(xy 92.307664 -491.546896) (xy 92.307664 -493.244124) (xy 92.308135 -493.260219) (xy 92.316197 -493.291382)
			(xy 92.331802 -493.319536) (xy 92.353957 -493.342888) (xy 92.367354 -493.35182) (xy 92.399518 -493.372485)
			(xy 92.459617 -493.419746) (xy 92.514303 -493.473177) (xy 92.562947 -493.532162) (xy 92.604989 -493.59602)
			(xy 92.639944 -493.664017) (xy 92.667409 -493.735369) (xy 92.687069 -493.809254) (xy 92.698696 -493.88482)
			(xy 92.702156 -493.961198) (xy 92.69741 -494.037506) (xy 92.684512 -494.112865) (xy 92.663611 -494.186409)
			(xy 92.634948 -494.257288) (xy 92.598853 -494.324687) (xy 92.555742 -494.387828) (xy 92.506111 -494.445985)
			(xy 92.450533 -494.498488) (xy 92.389648 -494.544731) (xy 92.324156 -494.584181) (xy 92.254814 -494.616385)
			(xy 92.182419 -494.64097) (xy 92.107806 -494.657655) (xy 92.031835 -494.666246) (xy 91.95538 -494.666644)
			(xy 91.879324 -494.658846) (xy 91.804541 -494.64294) (xy 91.731894 -494.619111) (xy 91.662219 -494.587632)
			(xy 91.59632 -494.548866) (xy 91.534956 -494.503261) (xy 91.478833 -494.45134) (xy 91.428599 -494.393704)
			(xy 91.384832 -494.331015) (xy 91.348036 -494.263996) (xy 91.318636 -494.19342) (xy 91.296969 -494.120098)
			(xy 91.289632 -494.082578) (xy 91.281504 -494.037366) (xy 91.210892 -493.978438) (xy 91.164664 -493.978438)
			(xy 91.148005 -493.978864) (xy 91.115823 -493.987497) (xy 91.086973 -494.004164) (xy 91.063419 -494.027732)
			(xy 91.046768 -494.056592) (xy 91.038154 -494.088778) (xy 91.037664 -494.105438) (xy 91.037664 -494.514124)
			(xy 91.038135 -494.530219) (xy 91.046197 -494.561382) (xy 91.061802 -494.589536) (xy 91.083957 -494.612888)
			(xy 91.097354 -494.62182) (xy 91.128899 -494.642128) (xy 91.187962 -494.688394) (xy 91.24183 -494.740618)
			(xy 91.289903 -494.79822) (xy 91.33165 -494.86056) (xy 91.366606 -494.926946) (xy 91.394383 -494.996642)
			(xy 91.414673 -495.068873) (xy 91.427251 -495.142838) (xy 91.431977 -495.217716) (xy 91.428799 -495.292676)
			(xy 91.417751 -495.366885) (xy 91.398957 -495.43952) (xy 91.372625 -495.509774) (xy 91.339048 -495.576868)
			(xy 91.298597 -495.640057) (xy 91.251723 -495.698639) (xy 91.198946 -495.751965) (xy 91.140851 -495.799441)
			(xy 91.078083 -495.840542) (xy 91.01134 -495.87481) (xy 90.941361 -495.901866) (xy 90.868924 -495.921409)
			(xy 90.794833 -495.933223) (xy 90.71991 -495.937175) (xy 90.644987 -495.933223) (xy 90.570896 -495.921409)
			(xy 90.498459 -495.901866) (xy 90.42848 -495.87481) (xy 90.361737 -495.840542) (xy 90.298969 -495.799441)
			(xy 90.240874 -495.751965) (xy 90.188097 -495.698639) (xy 90.141223 -495.640057) (xy 90.100772 -495.576868)
			(xy 90.067195 -495.509774) (xy 90.040863 -495.43952) (xy 90.022069 -495.366885) (xy 90.011021 -495.292676)
			(xy 90.007843 -495.217716) (xy 90.012569 -495.142838) (xy 90.025147 -495.068873) (xy 90.045437 -494.996642)
			(xy 90.073214 -494.926946) (xy 90.10817 -494.86056) (xy 90.149917 -494.79822) (xy 90.19799 -494.740618)
			(xy 90.251858 -494.688394) (xy 90.310921 -494.642128) (xy 90.342466 -494.62182) (xy 90.355844 -494.612861)
			(xy 90.378005 -494.589521) (xy 90.393616 -494.561375) (xy 90.401681 -494.530216) (xy 90.402156 -494.514124)
			(xy 90.402156 -494.105438) (xy 90.401672 -494.088781) (xy 90.393056 -494.056602) (xy 90.376402 -494.02775)
			(xy 90.352845 -494.004195) (xy 90.323993 -493.987542) (xy 90.291813 -493.978927) (xy 90.275156 -493.978438)
			(xy 90.228928 -493.978438) (xy 90.158316 -494.037366) (xy 90.150188 -494.082578) (xy 90.1428 -494.120219)
			(xy 90.121024 -494.193776) (xy 90.091465 -494.264565) (xy 90.054465 -494.331764) (xy 90.010452 -494.394595)
			(xy 89.959938 -494.452328) (xy 89.903509 -494.504293) (xy 89.841818 -494.54989) (xy 89.775581 -494.588587)
			(xy 89.705568 -494.619937) (xy 89.632588 -494.643576) (xy 89.55749 -494.65923) (xy 89.481144 -494.666717)
			(xy 89.404436 -494.66595) (xy 89.328255 -494.656938) (xy 89.253485 -494.639786) (xy 89.180993 -494.614693)
			(xy 89.111619 -494.58195) (xy 89.04617 -494.541936) (xy 88.985403 -494.495116) (xy 88.930023 -494.442032)
			(xy 88.880674 -494.383301) (xy 88.837926 -494.319603) (xy 88.802276 -494.251677) (xy 88.787732 -494.216182)
			(xy 88.778942 -494.195042) (xy 88.754835 -494.156124) (xy 88.724144 -494.122157) (xy 88.687861 -494.09424)
			(xy 88.647163 -494.073278) (xy 88.603367 -494.05995) (xy 88.557891 -494.054686) (xy 88.512208 -494.057659)
			(xy 88.467797 -494.068771) (xy 88.426097 -494.087662) (xy 88.388459 -494.113721) (xy 88.371934 -494.129568)
			(xy 88.354408 -494.147094) (xy 88.338602 -494.163644) (xy 88.312582 -494.201286) (xy 88.293722 -494.242978)
			(xy 88.282634 -494.287374) (xy 88.279674 -494.333037) (xy 88.284939 -494.378493) (xy 88.298259 -494.422271)
			(xy 88.319202 -494.462956) (xy 88.347093 -494.499233) (xy 88.381029 -494.52993) (xy 88.419913 -494.554054)
			(xy 88.441022 -494.562892) (xy 88.476275 -494.577384) (xy 88.54379 -494.612762) (xy 88.607138 -494.655151)
			(xy 88.665595 -494.704067) (xy 88.718489 -494.75895) (xy 88.765216 -494.81917) (xy 88.805241 -494.884038)
			(xy 88.838105 -494.952812) (xy 88.863432 -495.024704) (xy 88.880932 -495.09889) (xy 88.890404 -495.174522)
			(xy 88.891741 -495.250733) (xy 88.884926 -495.326651) (xy 88.870038 -495.401405) (xy 88.847248 -495.474141)
			(xy 88.816816 -495.544025) (xy 88.77909 -495.610257) (xy 88.734503 -495.672078) (xy 88.683566 -495.728782)
			(xy 88.626861 -495.779717) (xy 88.565038 -495.824302) (xy 88.498805 -495.862026) (xy 88.42892 -495.892456)
			(xy 88.356183 -495.915244) (xy 88.281428 -495.930129) (xy 88.205511 -495.936942) (xy 88.1293 -495.935603)
			(xy 88.053668 -495.926128) (xy 87.979482 -495.908625) (xy 87.907591 -495.883296) (xy 87.838818 -495.85043)
			(xy 87.773951 -495.810403) (xy 87.713732 -495.763674) (xy 87.658852 -495.710778) (xy 87.609938 -495.65232)
			(xy 87.56755 -495.588971) (xy 87.532174 -495.521454) (xy 87.517732 -495.486182) (xy 87.508942 -495.465042)
			(xy 87.484835 -495.426124) (xy 87.454144 -495.392157) (xy 87.417861 -495.36424) (xy 87.377163 -495.343278)
			(xy 87.333367 -495.32995) (xy 87.287891 -495.324686) (xy 87.242208 -495.327659) (xy 87.197797 -495.338771)
			(xy 87.156097 -495.357662) (xy 87.118459 -495.383721) (xy 87.101934 -495.399568) (xy 87.084408 -495.417094)
			(xy 87.068602 -495.433644) (xy 87.042582 -495.471286) (xy 87.023722 -495.512978) (xy 87.012634 -495.557374)
			(xy 87.009674 -495.603037) (xy 87.014939 -495.648493) (xy 87.028259 -495.692271) (xy 87.049202 -495.732956)
			(xy 87.077093 -495.769233) (xy 87.111029 -495.79993) (xy 87.149913 -495.824054) (xy 87.171022 -495.832892)
			(xy 87.205962 -495.847216) (xy 87.272887 -495.8822) (xy 87.335732 -495.924072) (xy 87.393792 -495.972362)
			(xy 87.446413 -496.026527) (xy 87.493004 -496.085959) (xy 87.533041 -496.149989) (xy 87.566075 -496.217898)
			(xy 87.591734 -496.288922) (xy 87.609729 -496.362264) (xy 87.619859 -496.437099) (xy 87.620971 -496.476111)
			(xy 88.737949 -496.476111) (xy 88.743998 -496.400541) (xy 88.758045 -496.326043) (xy 88.779931 -496.25346)
			(xy 88.809408 -496.183614) (xy 88.846143 -496.117297) (xy 88.889718 -496.055261) (xy 88.93964 -495.998208)
			(xy 88.995344 -495.946784) (xy 89.056199 -495.901573) (xy 89.121514 -495.863086) (xy 89.19055 -495.83176)
			(xy 89.262525 -495.80795) (xy 89.336623 -495.791925) (xy 89.412004 -495.783866) (xy 89.44991 -495.783362)
			(xy 89.487816 -495.783866) (xy 89.563197 -495.791925) (xy 89.637295 -495.80795) (xy 89.70927 -495.83176)
			(xy 89.778306 -495.863086) (xy 89.843621 -495.901573) (xy 89.904476 -495.946784) (xy 89.96018 -495.998208)
			(xy 90.010102 -496.055261) (xy 90.053677 -496.117297) (xy 90.090412 -496.183614) (xy 90.119889 -496.25346)
			(xy 90.141775 -496.326043) (xy 90.155822 -496.400541) (xy 90.161871 -496.476111) (xy 90.159852 -496.551895)
			(xy 90.14979 -496.627035) (xy 90.131798 -496.70068) (xy 90.10608 -496.771996) (xy 90.072928 -496.840173)
			(xy 90.032716 -496.904441) (xy 89.985901 -496.96407) (xy 89.933013 -497.018386) (xy 89.874651 -497.066772)
			(xy 89.811476 -497.10868) (xy 89.744205 -497.143636) (xy 89.6736 -497.171243) (xy 89.600459 -497.191189)
			(xy 89.525614 -497.203248) (xy 89.44991 -497.207283) (xy 89.374206 -497.203248) (xy 89.299361 -497.191189)
			(xy 89.22622 -497.171243) (xy 89.155615 -497.143636) (xy 89.088344 -497.10868) (xy 89.025169 -497.066772)
			(xy 88.966807 -497.018386) (xy 88.913919 -496.96407) (xy 88.867104 -496.904441) (xy 88.826892 -496.840173)
			(xy 88.79374 -496.771996) (xy 88.768022 -496.70068) (xy 88.75003 -496.627035) (xy 88.739968 -496.551895)
			(xy 88.737949 -496.476111) (xy 87.620971 -496.476111) (xy 87.62201 -496.512585) (xy 87.616157 -496.587875)
			(xy 87.602366 -496.662122) (xy 87.580793 -496.734492) (xy 87.551679 -496.804172) (xy 87.515353 -496.870378)
			(xy 87.472221 -496.932366) (xy 87.42277 -496.989439) (xy 87.367554 -497.040956) (xy 87.307194 -497.086339)
			(xy 87.24237 -497.125076) (xy 87.173808 -497.156733) (xy 87.102281 -497.180954) (xy 87.028591 -497.197467)
			(xy 86.953567 -497.206085) (xy 86.878053 -497.206712) (xy 86.802896 -497.199342) (xy 86.728942 -497.184056)
			(xy 86.657022 -497.161027) (xy 86.587944 -497.130514) (xy 86.522484 -497.092859) (xy 86.461379 -497.048485)
			(xy 86.405315 -496.997892) (xy 86.354922 -496.941649) (xy 86.310766 -496.880386) (xy 86.273345 -496.814793)
			(xy 86.243077 -496.745607) (xy 86.220304 -496.673605) (xy 86.205282 -496.599597) (xy 86.198179 -496.524415)
			(xy 86.199075 -496.448903) (xy 86.20796 -496.373911) (xy 86.224735 -496.30028) (xy 86.24921 -496.228839)
			(xy 86.281111 -496.160391) (xy 86.320079 -496.095704) (xy 86.365676 -496.035507) (xy 86.417389 -495.980475)
			(xy 86.474638 -495.931226) (xy 86.536779 -495.888316) (xy 86.603114 -495.852225) (xy 86.672897 -495.823359)
			(xy 86.745343 -495.802044) (xy 86.782402 -495.794792) (xy 86.827614 -495.786664) (xy 86.886542 -495.716052)
			(xy 86.886542 -495.669824) (xy 86.885936 -495.65318) (xy 86.877328 -495.621025) (xy 86.860691 -495.592193)
			(xy 86.837159 -495.568649) (xy 86.808336 -495.551998) (xy 86.776186 -495.543372) (xy 86.759542 -495.542824)
			(xy 86.350856 -495.542824) (xy 86.334758 -495.543252) (xy 86.30359 -495.551324) (xy 86.275436 -495.566941)
			(xy 86.252087 -495.58911) (xy 86.24316 -495.602514) (xy 86.222331 -495.634822) (xy 86.174778 -495.695222)
			(xy 86.120992 -495.750144) (xy 86.061598 -495.798948) (xy 85.997289 -495.841064) (xy 85.928814 -495.876003)
			(xy 85.856972 -495.903356) (xy 85.7826 -495.922805) (xy 85.706565 -495.934123) (xy 85.629753 -495.937178)
			(xy 85.553059 -495.931935) (xy 85.477377 -495.918455) (xy 85.40359 -495.896894) (xy 85.367876 -495.882676)
			(xy 85.346712 -495.874522) (xy 85.302398 -495.864904) (xy 85.257079 -495.863305) (xy 85.212197 -495.869775)
			(xy 85.169175 -495.884109) (xy 85.129381 -495.905851) (xy 85.094077 -495.934311) (xy 85.064386 -495.968585)
			(xy 85.04125 -496.007586) (xy 85.025403 -496.050073) (xy 85.01735 -496.094699) (xy 85.016848 -496.117372)
			(xy 85.016848 -496.872768) (xy 85.017399 -496.895439) (xy 85.025457 -496.94006) (xy 85.041305 -496.982543)
			(xy 85.064439 -497.02154) (xy 85.094126 -497.055813) (xy 85.129423 -497.084275) (xy 85.16921 -497.106021)
			(xy 85.212225 -497.120363) (xy 85.257102 -497.126844) (xy 85.302417 -497.125259) (xy 85.346732 -497.115659)
			(xy 85.367876 -497.107464) (xy 85.403568 -497.093298) (xy 85.477278 -497.071757) (xy 85.552878 -497.058278)
			(xy 85.62949 -497.053017) (xy 85.706224 -497.056036) (xy 85.782186 -497.0673) (xy 85.856494 -497.086677)
			(xy 85.928283 -497.113943) (xy 85.996719 -497.14878) (xy 86.061006 -497.190783) (xy 86.120397 -497.239464)
			(xy 86.174201 -497.294257) (xy 86.221792 -497.354525) (xy 86.262617 -497.419567) (xy 86.296202 -497.488626)
			(xy 86.322155 -497.5609) (xy 86.340176 -497.635548) (xy 86.350054 -497.711703) (xy 86.351675 -497.788479)
			(xy 86.34502 -497.864982) (xy 86.330166 -497.940325) (xy 86.307285 -498.01363) (xy 86.292436 -498.049042)
			(xy 86.283816 -498.070252) (xy 86.273367 -498.114821) (xy 86.27107 -498.16054) (xy 86.276999 -498.205931)
			(xy 86.290963 -498.249526) (xy 86.31251 -498.289915) (xy 86.340943 -498.325791) (xy 86.375342 -498.355994)
			(xy 86.414594 -498.379548) (xy 86.457431 -498.395689) (xy 86.502466 -498.403897) (xy 86.525354 -498.404388)
			(xy 87.294466 -498.404388) (xy 87.317359 -498.4039) (xy 87.362406 -498.395704) (xy 87.405255 -498.379569)
			(xy 87.444521 -498.356018) (xy 87.478932 -498.325814) (xy 87.507374 -498.289933) (xy 87.528929 -498.249538)
			(xy 87.542897 -498.205934) (xy 87.548827 -498.160533) (xy 87.546528 -498.114805) (xy 87.536073 -498.070228)
			(xy 87.527384 -498.049042) (xy 87.512631 -498.013893) (xy 87.489857 -497.941141) (xy 87.47499 -497.866372)
			(xy 87.4682 -497.790442) (xy 87.469566 -497.714222) (xy 87.479071 -497.638584) (xy 87.496606 -497.564395)
			(xy 87.521971 -497.492506) (xy 87.554875 -497.42374) (xy 87.594941 -497.358885) (xy 87.64171 -497.298685)
			(xy 87.694646 -497.243828) (xy 87.753142 -497.194944) (xy 87.816529 -497.152593) (xy 87.884079 -497.11726)
			(xy 87.955018 -497.08935) (xy 88.028535 -497.069182) (xy 88.103786 -497.056988) (xy 88.17991 -497.052908)
			(xy 88.256034 -497.056988) (xy 88.331285 -497.069182) (xy 88.404802 -497.08935) (xy 88.475741 -497.11726)
			(xy 88.543291 -497.152593) (xy 88.606678 -497.194944) (xy 88.665174 -497.243828) (xy 88.71811 -497.298685)
			(xy 88.764879 -497.358885) (xy 88.804945 -497.42374) (xy 88.837849 -497.492506) (xy 88.863214 -497.564395)
			(xy 88.880749 -497.638584) (xy 88.890254 -497.714222) (xy 88.89162 -497.790442) (xy 88.88483 -497.866372)
			(xy 88.869963 -497.941141) (xy 88.847189 -498.013893) (xy 88.832436 -498.049042) (xy 88.823816 -498.070252)
			(xy 88.813367 -498.114821) (xy 88.81107 -498.16054) (xy 88.816999 -498.205931) (xy 88.830963 -498.249526)
			(xy 88.85251 -498.289915) (xy 88.880943 -498.325791) (xy 88.915342 -498.355994) (xy 88.954594 -498.379548)
			(xy 88.997431 -498.395689) (xy 89.042466 -498.403897) (xy 89.065354 -498.404388) (xy 89.631012 -498.404388)
			(xy 90.015568 -498.020086) (xy 90.033602 -497.95684) (xy 90.026236 -497.924836) (xy 90.018246 -497.887859)
			(xy 90.009184 -497.812749) (xy 90.008138 -497.737103) (xy 90.015122 -497.661771) (xy 90.030056 -497.587606)
			(xy 90.052772 -497.515443) (xy 90.083013 -497.446096) (xy 90.120439 -497.380347) (xy 90.164627 -497.318939)
			(xy 90.215078 -497.262563) (xy 90.271224 -497.211856) (xy 90.332432 -497.167391) (xy 90.39801 -497.129667)
			(xy 90.467219 -497.099112) (xy 90.539278 -497.076069) (xy 90.613375 -497.060798) (xy 90.688674 -497.053473)
			(xy 90.764325 -497.054175) (xy 90.839475 -497.062896) (xy 90.913276 -497.079539) (xy 90.984895 -497.103915)
			(xy 91.053525 -497.135749) (xy 91.118392 -497.174683) (xy 91.178764 -497.220277) (xy 91.23396 -497.272017)
			(xy 91.283356 -497.329319) (xy 91.326397 -497.391536) (xy 91.362596 -497.457968) (xy 91.391545 -497.527864)
			(xy 91.412918 -497.600437) (xy 91.420188 -497.637562) (xy 91.428316 -497.682774) (xy 91.498928 -497.741702)
			(xy 91.624912 -497.741702) (xy 91.655392 -497.711222) (xy 91.655392 -497.195348) (xy 91.65497 -497.179616)
			(xy 91.647308 -497.149101) (xy 91.632392 -497.121399) (xy 91.611133 -497.098205) (xy 91.598242 -497.089176)
			(xy 91.566833 -497.067884) (xy 91.508281 -497.019611) (xy 91.455198 -496.965381) (xy 91.408187 -496.905811)
			(xy 91.367782 -496.841576) (xy 91.334442 -496.773407) (xy 91.308545 -496.702077) (xy 91.290386 -496.628396)
			(xy 91.28017 -496.553201) (xy 91.278014 -496.477346) (xy 91.283942 -496.401692) (xy 91.297887 -496.327099)
			(xy 91.319691 -496.254413) (xy 91.349105 -496.18446) (xy 91.385796 -496.118034) (xy 91.429348 -496.055889)
			(xy 91.479265 -495.998732) (xy 91.534981 -495.947212) (xy 91.595862 -495.901912) (xy 91.661219 -495.863349)
			(xy 91.730308 -495.831959) (xy 91.802345 -495.808099) (xy 91.876512 -495.79204) (xy 91.951967 -495.783965)
			(xy 92.027853 -495.783965) (xy 92.103308 -495.79204) (xy 92.177475 -495.808099) (xy 92.249512 -495.831959)
			(xy 92.318601 -495.863349) (xy 92.383958 -495.901912) (xy 92.444839 -495.947212) (xy 92.500555 -495.998732)
			(xy 92.550472 -496.055889) (xy 92.594024 -496.118034) (xy 92.630715 -496.18446) (xy 92.660129 -496.254413)
			(xy 92.681933 -496.327099) (xy 92.695878 -496.401692) (xy 92.701806 -496.477346) (xy 92.69965 -496.553201)
			(xy 92.689434 -496.628396) (xy 92.671275 -496.702077) (xy 92.645378 -496.773407) (xy 92.612038 -496.841576)
			(xy 92.571633 -496.905811) (xy 92.524622 -496.965381) (xy 92.471539 -497.019611) (xy 92.412987 -497.067884)
			(xy 92.381578 -497.089176) (xy 92.368697 -497.098206) (xy 92.347487 -497.121429) (xy 92.332588 -497.149127)
			(xy 92.324899 -497.179623) (xy 92.324858 -497.180991) (xy 93.154757 -497.180991) (xy 93.160779 -497.064808)
			(xy 93.174802 -496.949317) (xy 93.19676 -496.835069) (xy 93.226547 -496.722608) (xy 93.264022 -496.61247)
			(xy 93.309007 -496.50518) (xy 93.361286 -496.401249) (xy 93.420611 -496.301173) (xy 93.486699 -496.205427)
			(xy 93.559235 -496.11447) (xy 93.637874 -496.028734) (xy 93.72224 -495.948627) (xy 93.811932 -495.874531)
			(xy 93.906522 -495.806801) (xy 94.00556 -495.745757) (xy 94.108573 -495.691692) (xy 94.21507 -495.644862)
			(xy 94.324545 -495.605491) (xy 94.436475 -495.573767) (xy 94.550327 -495.549841) (xy 94.665559 -495.533827)
			(xy 94.781621 -495.5258) (xy 94.83979 -495.525298) (xy 94.897959 -495.5258) (xy 95.014021 -495.533827)
			(xy 95.129253 -495.549841) (xy 95.243105 -495.573767) (xy 95.355035 -495.605491) (xy 95.46451 -495.644862)
			(xy 95.571007 -495.691692) (xy 95.67402 -495.745757) (xy 95.773058 -495.806801) (xy 95.867648 -495.874531)
			(xy 95.95734 -495.948627) (xy 96.041706 -496.028734) (xy 96.120345 -496.11447) (xy 96.192881 -496.205427)
			(xy 96.258969 -496.301173) (xy 96.318294 -496.401249) (xy 96.370573 -496.50518) (xy 96.415558 -496.61247)
			(xy 96.453033 -496.722608) (xy 96.48282 -496.835069) (xy 96.504778 -496.949317) (xy 96.518801 -497.064808)
			(xy 96.524823 -497.180991) (xy 96.522815 -497.297313) (xy 96.512786 -497.413219) (xy 96.494785 -497.528156)
			(xy 96.468897 -497.641579) (xy 96.435246 -497.752944) (xy 96.393992 -497.861723) (xy 96.345331 -497.967397)
			(xy 96.289495 -498.069461) (xy 96.226752 -498.16743) (xy 96.157398 -498.260837) (xy 96.081766 -498.349237)
			(xy 96.000215 -498.432208) (xy 95.913134 -498.509355) (xy 95.820938 -498.58031) (xy 95.724066 -498.644736)
			(xy 95.622981 -498.702325) (xy 95.518163 -498.752802) (xy 95.410112 -498.795928) (xy 95.299344 -498.831497)
			(xy 95.186385 -498.859339) (xy 95.071775 -498.879321) (xy 94.95606 -498.891348) (xy 94.83979 -498.895364)
			(xy 94.72352 -498.891348) (xy 94.607805 -498.879321) (xy 94.493195 -498.859339) (xy 94.380236 -498.831497)
			(xy 94.269468 -498.795928) (xy 94.161417 -498.752802) (xy 94.056599 -498.702325) (xy 93.955514 -498.644736)
			(xy 93.858642 -498.58031) (xy 93.766446 -498.509355) (xy 93.679365 -498.432208) (xy 93.597814 -498.349237)
			(xy 93.522182 -498.260837) (xy 93.452828 -498.16743) (xy 93.390085 -498.069461) (xy 93.334249 -497.967397)
			(xy 93.285588 -497.861723) (xy 93.244334 -497.752944) (xy 93.210683 -497.641579) (xy 93.184795 -497.528156)
			(xy 93.166794 -497.413219) (xy 93.156765 -497.297313) (xy 93.154757 -497.180991) (xy 92.324858 -497.180991)
			(xy 92.324428 -497.195348) (xy 92.324428 -497.988082) (xy 90.770202 -499.542308) (xy 85.220048 -499.542308)
			(xy 83.956652 -498.278658) (xy 83.956652 -494.436146) (xy 90.64625 -487.746294) (xy 90.654328 -487.720002)
			(xy 90.677109 -487.669937) (xy 90.706838 -487.623659) (xy 90.742901 -487.582126) (xy 90.78455 -487.546198)
			(xy 90.830924 -487.516619) (xy 90.881062 -487.494) (xy 90.907362 -487.485944) (xy 90.938858 -487.477054)
			(xy 96.697292 -481.71862) (xy 96.697292 -453.849486) (xy 96.696778 -453.826386) (xy 96.688424 -453.780948)
			(xy 96.671995 -453.737769) (xy 96.648031 -453.69827) (xy 96.617323 -453.663754) (xy 96.58088 -453.635358)
			(xy 96.539906 -453.614016) (xy 96.495748 -453.600433) (xy 96.449863 -453.595055) (xy 96.403761 -453.59806)
			(xy 96.358962 -453.609349) (xy 96.316942 -453.62855) (xy 96.279084 -453.65503) (xy 96.246637 -453.687917)
			(xy 96.233234 -453.706738) (xy 96.200002 -453.754647) (xy 96.127961 -453.846337) (xy 96.049751 -453.932826)
			(xy 95.965747 -454.013699) (xy 95.876352 -454.08857) (xy 95.781993 -454.157079) (xy 95.683122 -454.218898)
			(xy 95.580213 -454.273732) (xy 95.473758 -454.321319) (xy 95.364267 -454.361429) (xy 95.252264 -454.393871)
			(xy 95.138286 -454.418491) (xy 95.022878 -454.435169) (xy 94.906594 -454.443826) (xy 94.789989 -454.444421)
			(xy 94.673621 -454.436951) (xy 94.55805 -454.421451) (xy 94.443826 -454.397995) (xy 94.331498 -454.366697)
			(xy 94.221604 -454.327706) (xy 94.114669 -454.281209) (xy 94.011206 -454.227427) (xy 93.911709 -454.166619)
			(xy 93.816656 -454.099077) (xy 93.726502 -454.025122) (xy 93.641677 -453.94511) (xy 93.562589 -453.859424)
			(xy 93.489616 -453.768473) (xy 93.423107 -453.672694) (xy 93.363381 -453.572544) (xy 93.310724 -453.468504)
			(xy 93.265388 -453.361072) (xy 93.22759 -453.250761) (xy 93.197511 -453.138101) (xy 93.175295 -453.02363)
			(xy 93.161048 -452.907897) (xy 93.154839 -452.791456) (xy 93.156698 -452.674864) (xy 93.166614 -452.55868)
			(xy 93.184542 -452.44346) (xy 93.210395 -452.329755) (xy 93.244049 -452.21811) (xy 93.285344 -452.109061)
			(xy 93.334081 -452.003128) (xy 93.390027 -451.900818) (xy 93.452914 -451.802623) (xy 93.522442 -451.709012)
			(xy 93.598276 -451.620433) (xy 93.680055 -451.537311) (xy 93.767386 -451.460043) (xy 93.859852 -451.388999)
			(xy 93.957009 -451.32452) (xy 94.058393 -451.266914) (xy 94.163518 -451.216458) (xy 94.271881 -451.173392)
			(xy 94.382962 -451.137923) (xy 94.49623 -451.11022) (xy 94.611143 -451.090417) (xy 94.72715 -451.078608)
			(xy 94.843696 -451.07485) (xy 94.960223 -451.079161) (xy 95.076173 -451.09152) (xy 95.133668 -451.101206)
			(xy 95.156396 -451.104659) (xy 95.20236 -451.10441) (xy 95.24753 -451.095899) (xy 95.290434 -451.079404)
			(xy 95.329672 -451.055464) (xy 95.363965 -451.024859) (xy 95.392196 -450.988585) (xy 95.413445 -450.947827)
			(xy 95.427018 -450.903912) (xy 95.432474 -450.858272) (xy 95.429634 -450.812395) (xy 95.41859 -450.767777)
			(xy 95.399704 -450.725872) (xy 95.37359 -450.688045) (xy 95.357696 -450.671438) (xy 88.31072 -443.624462)
			(xy 84.632292 -443.624462) (xy 84.609229 -443.624951) (xy 84.563849 -443.633204) (xy 84.520703 -443.64951)
			(xy 84.481208 -443.673334) (xy 84.44666 -443.703893) (xy 84.418194 -443.740185) (xy 84.396744 -443.781018)
			(xy 84.383013 -443.825051) (xy 84.377454 -443.87084) (xy 84.380249 -443.916879) (xy 84.391305 -443.961659)
			(xy 84.41026 -444.003708) (xy 84.436492 -444.041647) (xy 84.45246 -444.058294) (xy 85.349334 -444.954914)
			(xy 85.38083 -444.963804) (xy 85.407197 -444.971888) (xy 85.457454 -444.994592) (xy 85.503919 -445.024294)
			(xy 85.545626 -445.060374) (xy 85.581706 -445.102081) (xy 85.611408 -445.148546) (xy 85.634112 -445.198803)
			(xy 85.642196 -445.22517) (xy 85.651086 -445.256666) (xy 89.194894 -448.800728) (xy 89.25814 -448.818762)
			(xy 89.290144 -448.811396) (xy 89.326931 -448.803395) (xy 89.401671 -448.794335) (xy 89.47695 -448.793214)
			(xy 89.551927 -448.800045) (xy 89.625765 -448.814752) (xy 89.697637 -448.83717) (xy 89.766742 -448.867049)
			(xy 89.832307 -448.904055) (xy 89.8936 -448.947774) (xy 89.949936 -448.997719) (xy 90.000686 -449.05333)
			(xy 90.045283 -449.113988) (xy 90.083228 -449.179014) (xy 90.114097 -449.247682) (xy 90.137547 -449.319225)
			(xy 90.153314 -449.392843) (xy 90.161223 -449.467714) (xy 90.161214 -449.486111) (xy 91.277949 -449.486111)
			(xy 91.283998 -449.410541) (xy 91.298045 -449.336043) (xy 91.319931 -449.26346) (xy 91.349408 -449.193614)
			(xy 91.386143 -449.127297) (xy 91.429718 -449.065261) (xy 91.47964 -449.008208) (xy 91.535344 -448.956784)
			(xy 91.596199 -448.911573) (xy 91.661514 -448.873086) (xy 91.73055 -448.84176) (xy 91.802525 -448.81795)
			(xy 91.876623 -448.801925) (xy 91.952004 -448.793866) (xy 91.98991 -448.793362) (xy 92.027816 -448.793866)
			(xy 92.103197 -448.801925) (xy 92.177295 -448.81795) (xy 92.24927 -448.84176) (xy 92.318306 -448.873086)
			(xy 92.383621 -448.911573) (xy 92.444476 -448.956784) (xy 92.50018 -449.008208) (xy 92.550102 -449.065261)
			(xy 92.593677 -449.127297) (xy 92.630412 -449.193614) (xy 92.659889 -449.26346) (xy 92.681775 -449.336043)
			(xy 92.695822 -449.410541) (xy 92.701871 -449.486111) (xy 92.699852 -449.561895) (xy 92.68979 -449.637035)
			(xy 92.671798 -449.71068) (xy 92.64608 -449.781996) (xy 92.612928 -449.850173) (xy 92.572716 -449.914441)
			(xy 92.525901 -449.97407) (xy 92.473013 -450.028386) (xy 92.414651 -450.076772) (xy 92.351476 -450.11868)
			(xy 92.284205 -450.153636) (xy 92.2136 -450.181243) (xy 92.140459 -450.201189) (xy 92.065614 -450.213248)
			(xy 91.98991 -450.217283) (xy 91.914206 -450.213248) (xy 91.839361 -450.201189) (xy 91.76622 -450.181243)
			(xy 91.695615 -450.153636) (xy 91.628344 -450.11868) (xy 91.565169 -450.076772) (xy 91.506807 -450.028386)
			(xy 91.453919 -449.97407) (xy 91.407104 -449.914441) (xy 91.366892 -449.850173) (xy 91.33374 -449.781996)
			(xy 91.308022 -449.71068) (xy 91.29003 -449.637035) (xy 91.279968 -449.561895) (xy 91.277949 -449.486111)
			(xy 90.161214 -449.486111) (xy 90.161185 -449.543001) (xy 90.153201 -449.617864) (xy 90.13736 -449.691466)
			(xy 90.113838 -449.762985) (xy 90.0829 -449.831622) (xy 90.044889 -449.89661) (xy 90.000232 -449.957223)
			(xy 89.949426 -450.012784) (xy 89.89304 -450.062672) (xy 89.831703 -450.10633) (xy 89.7661 -450.143269)
			(xy 89.696966 -450.173079) (xy 89.625071 -450.195424) (xy 89.551219 -450.210057) (xy 89.476235 -450.216813)
			(xy 89.400957 -450.215616) (xy 89.326225 -450.206481) (xy 89.252876 -450.189509) (xy 89.181727 -450.164889)
			(xy 89.113575 -450.132898) (xy 89.049179 -450.093892) (xy 88.989261 -450.048307) (xy 88.934489 -449.996652)
			(xy 88.885474 -449.939505) (xy 88.842766 -449.877503) (xy 88.80684 -449.81134) (xy 88.778098 -449.741755)
			(xy 88.756862 -449.669524) (xy 88.749632 -449.632578) (xy 88.741504 -449.587366) (xy 88.670892 -449.528438)
			(xy 88.624664 -449.528438) (xy 88.608005 -449.528864) (xy 88.575823 -449.537497) (xy 88.546973 -449.554164)
			(xy 88.523419 -449.577732) (xy 88.506768 -449.606592) (xy 88.498154 -449.638778) (xy 88.497664 -449.655438)
			(xy 88.497664 -450.064124) (xy 88.498135 -450.080219) (xy 88.506197 -450.111382) (xy 88.521802 -450.139536)
			(xy 88.543957 -450.162888) (xy 88.557354 -450.17182) (xy 88.589812 -450.192775) (xy 88.650485 -450.240609)
			(xy 88.705619 -450.294735) (xy 88.754564 -450.354515) (xy 88.796745 -450.419245) (xy 88.831666 -450.488164)
			(xy 88.858915 -450.560461) (xy 88.878171 -450.635284) (xy 88.889208 -450.711753) (xy 88.890752 -450.756111)
			(xy 90.007949 -450.756111) (xy 90.013998 -450.680541) (xy 90.028045 -450.606043) (xy 90.049931 -450.53346)
			(xy 90.079408 -450.463614) (xy 90.116143 -450.397297) (xy 90.159718 -450.335261) (xy 90.20964 -450.278208)
			(xy 90.265344 -450.226784) (xy 90.326199 -450.181573) (xy 90.391514 -450.143086) (xy 90.46055 -450.11176)
			(xy 90.532525 -450.08795) (xy 90.606623 -450.071925) (xy 90.682004 -450.063866) (xy 90.71991 -450.063362)
			(xy 90.757816 -450.063866) (xy 90.833197 -450.071925) (xy 90.907295 -450.08795) (xy 90.97927 -450.11176)
			(xy 91.048306 -450.143086) (xy 91.113621 -450.181573) (xy 91.174476 -450.226784) (xy 91.23018 -450.278208)
			(xy 91.280102 -450.335261) (xy 91.323677 -450.397297) (xy 91.360412 -450.463614) (xy 91.389889 -450.53346)
			(xy 91.411775 -450.606043) (xy 91.425822 -450.680541) (xy 91.431871 -450.756111) (xy 91.429852 -450.831895)
			(xy 91.41979 -450.907035) (xy 91.401798 -450.98068) (xy 91.37608 -451.051996) (xy 91.342928 -451.120173)
			(xy 91.302716 -451.184441) (xy 91.255901 -451.24407) (xy 91.203013 -451.298386) (xy 91.144651 -451.346772)
			(xy 91.081476 -451.38868) (xy 91.014205 -451.423636) (xy 90.9436 -451.451243) (xy 90.870459 -451.471189)
			(xy 90.795614 -451.483248) (xy 90.71991 -451.487283) (xy 90.644206 -451.483248) (xy 90.569361 -451.471189)
			(xy 90.49622 -451.451243) (xy 90.425615 -451.423636) (xy 90.358344 -451.38868) (xy 90.295169 -451.346772)
			(xy 90.236807 -451.298386) (xy 90.183919 -451.24407) (xy 90.137104 -451.184441) (xy 90.096892 -451.120173)
			(xy 90.06374 -451.051996) (xy 90.038022 -450.98068) (xy 90.02003 -450.907035) (xy 90.009968 -450.831895)
			(xy 90.007949 -450.756111) (xy 88.890752 -450.756111) (xy 88.891896 -450.788968) (xy 88.886204 -450.866019)
			(xy 88.872197 -450.942) (xy 88.850042 -451.016017) (xy 88.819998 -451.087197) (xy 88.782421 -451.154705)
			(xy 88.737751 -451.217744) (xy 88.686515 -451.275572) (xy 88.629315 -451.32751) (xy 88.566826 -451.372946)
			(xy 88.499782 -451.411344) (xy 88.428973 -451.442253) (xy 88.392254 -451.454266) (xy 88.362536 -451.463664)
			(xy 88.340438 -451.485762) (xy 88.328999 -451.497913) (xy 88.312288 -451.526786) (xy 88.303635 -451.559004)
			(xy 88.303631 -451.592365) (xy 88.312276 -451.624585) (xy 88.32898 -451.653462) (xy 88.340438 -451.665594)
			(xy 88.40216 -451.727316) (xy 88.738964 -451.727316) (xy 88.755057 -451.726811) (xy 88.786219 -451.718762)
			(xy 88.814374 -451.703167) (xy 88.837728 -451.68102) (xy 88.84666 -451.667626) (xy 88.866995 -451.6361)
			(xy 88.913263 -451.577041) (xy 88.965487 -451.523178) (xy 89.023089 -451.475108) (xy 89.085428 -451.433366)
			(xy 89.151813 -451.398414) (xy 89.221507 -451.370641) (xy 89.293737 -451.350354) (xy 89.3677 -451.33778)
			(xy 89.442575 -451.333057) (xy 89.517532 -451.336238) (xy 89.591738 -451.347289) (xy 89.664369 -451.366085)
			(xy 89.73462 -451.392418) (xy 89.80171 -451.425997) (xy 89.864895 -451.466448) (xy 89.923473 -451.513323)
			(xy 89.976795 -451.5661) (xy 90.024267 -451.624195) (xy 90.065364 -451.686962) (xy 90.099629 -451.753704)
			(xy 90.126681 -451.823682) (xy 90.146221 -451.896117) (xy 90.158031 -451.970205) (xy 90.160979 -452.026111)
			(xy 91.277949 -452.026111) (xy 91.283998 -451.950541) (xy 91.298045 -451.876043) (xy 91.319931 -451.80346)
			(xy 91.349408 -451.733614) (xy 91.386143 -451.667297) (xy 91.429718 -451.605261) (xy 91.47964 -451.548208)
			(xy 91.535344 -451.496784) (xy 91.596199 -451.451573) (xy 91.661514 -451.413086) (xy 91.73055 -451.38176)
			(xy 91.802525 -451.35795) (xy 91.876623 -451.341925) (xy 91.952004 -451.333866) (xy 91.98991 -451.333362)
			(xy 92.027816 -451.333866) (xy 92.103197 -451.341925) (xy 92.177295 -451.35795) (xy 92.24927 -451.38176)
			(xy 92.318306 -451.413086) (xy 92.383621 -451.451573) (xy 92.444476 -451.496784) (xy 92.50018 -451.548208)
			(xy 92.550102 -451.605261) (xy 92.593677 -451.667297) (xy 92.630412 -451.733614) (xy 92.659889 -451.80346)
			(xy 92.681775 -451.876043) (xy 92.695822 -451.950541) (xy 92.701871 -452.026111) (xy 92.699852 -452.101895)
			(xy 92.68979 -452.177035) (xy 92.671798 -452.25068) (xy 92.64608 -452.321996) (xy 92.612928 -452.390173)
			(xy 92.572716 -452.454441) (xy 92.525901 -452.51407) (xy 92.473013 -452.568386) (xy 92.414651 -452.616772)
			(xy 92.351476 -452.65868) (xy 92.284205 -452.693636) (xy 92.2136 -452.721243) (xy 92.140459 -452.741189)
			(xy 92.065614 -452.753248) (xy 91.98991 -452.757283) (xy 91.914206 -452.753248) (xy 91.839361 -452.741189)
			(xy 91.76622 -452.721243) (xy 91.695615 -452.693636) (xy 91.628344 -452.65868) (xy 91.565169 -452.616772)
			(xy 91.506807 -452.568386) (xy 91.453919 -452.51407) (xy 91.407104 -452.454441) (xy 91.366892 -452.390173)
			(xy 91.33374 -452.321996) (xy 91.308022 -452.25068) (xy 91.29003 -452.177035) (xy 91.279968 -452.101895)
			(xy 91.277949 -452.026111) (xy 90.160979 -452.026111) (xy 90.161981 -452.045125) (xy 90.158026 -452.120045)
			(xy 90.14621 -452.194133) (xy 90.126665 -452.266567) (xy 90.099608 -452.336542) (xy 90.065338 -452.403282)
			(xy 90.024237 -452.466046) (xy 89.976761 -452.524137) (xy 89.923435 -452.576911) (xy 89.864854 -452.623781)
			(xy 89.801666 -452.664228) (xy 89.734573 -452.697802) (xy 89.664321 -452.724131) (xy 89.591688 -452.742922)
			(xy 89.517481 -452.753966) (xy 89.442524 -452.757142) (xy 89.367649 -452.752414) (xy 89.293687 -452.739835)
			(xy 89.221459 -452.719543) (xy 89.151767 -452.691765) (xy 89.085384 -452.656808) (xy 89.023048 -452.615061)
			(xy 88.96545 -452.566988) (xy 88.913229 -452.513121) (xy 88.866966 -452.454058) (xy 88.84666 -452.422514)
			(xy 88.837745 -452.409104) (xy 88.81439 -452.386947) (xy 88.78623 -452.371345) (xy 88.755061 -452.363291)
			(xy 88.738964 -452.362824) (xy 88.330278 -452.362824) (xy 88.31362 -452.363276) (xy 88.281441 -452.371904)
			(xy 88.252592 -452.388567) (xy 88.229039 -452.412129) (xy 88.212386 -452.440984) (xy 88.20377 -452.473166)
			(xy 88.203278 -452.489824) (xy 88.203278 -452.536052) (xy 88.262206 -452.606664) (xy 88.307418 -452.614792)
			(xy 88.344938 -452.622082) (xy 88.418237 -452.643759) (xy 88.48879 -452.673167) (xy 88.555786 -452.709966)
			(xy 88.618452 -452.753734) (xy 88.676066 -452.803966) (xy 88.727965 -452.860082) (xy 88.773552 -452.921438)
			(xy 88.8123 -452.987326) (xy 88.843764 -453.056987) (xy 88.867581 -453.129618) (xy 88.883477 -453.204384)
			(xy 88.891269 -453.280423) (xy 88.891186 -453.296111) (xy 90.007949 -453.296111) (xy 90.013998 -453.220541)
			(xy 90.028045 -453.146043) (xy 90.049931 -453.07346) (xy 90.079408 -453.003614) (xy 90.116143 -452.937297)
			(xy 90.159718 -452.875261) (xy 90.20964 -452.818208) (xy 90.265344 -452.766784) (xy 90.326199 -452.721573)
			(xy 90.391514 -452.683086) (xy 90.46055 -452.65176) (xy 90.532525 -452.62795) (xy 90.606623 -452.611925)
			(xy 90.682004 -452.603866) (xy 90.71991 -452.603362) (xy 90.757816 -452.603866) (xy 90.833197 -452.611925)
			(xy 90.907295 -452.62795) (xy 90.97927 -452.65176) (xy 91.048306 -452.683086) (xy 91.113621 -452.721573)
			(xy 91.174476 -452.766784) (xy 91.23018 -452.818208) (xy 91.280102 -452.875261) (xy 91.323677 -452.937297)
			(xy 91.360412 -453.003614) (xy 91.389889 -453.07346) (xy 91.411775 -453.146043) (xy 91.425822 -453.220541)
			(xy 91.431871 -453.296111) (xy 91.429852 -453.371895) (xy 91.41979 -453.447035) (xy 91.401798 -453.52068)
			(xy 91.37608 -453.591996) (xy 91.342928 -453.660173) (xy 91.302716 -453.724441) (xy 91.255901 -453.78407)
			(xy 91.203013 -453.838386) (xy 91.144651 -453.886772) (xy 91.081476 -453.92868) (xy 91.014205 -453.963636)
			(xy 90.9436 -453.991243) (xy 90.870459 -454.011189) (xy 90.795614 -454.023248) (xy 90.71991 -454.027283)
			(xy 90.644206 -454.023248) (xy 90.569361 -454.011189) (xy 90.49622 -453.991243) (xy 90.425615 -453.963636)
			(xy 90.358344 -453.92868) (xy 90.295169 -453.886772) (xy 90.236807 -453.838386) (xy 90.183919 -453.78407)
			(xy 90.137104 -453.724441) (xy 90.096892 -453.660173) (xy 90.06374 -453.591996) (xy 90.038022 -453.52068)
			(xy 90.02003 -453.447035) (xy 90.009968 -453.371895) (xy 90.007949 -453.296111) (xy 88.891186 -453.296111)
			(xy 88.890867 -453.356859) (xy 88.882276 -453.432812) (xy 88.865594 -453.507407) (xy 88.841014 -453.579784)
			(xy 88.808819 -453.64911) (xy 88.769379 -453.714586) (xy 88.72315 -453.775459) (xy 88.670663 -453.831027)
			(xy 88.612523 -453.880649) (xy 88.5494 -453.923755) (xy 88.482021 -453.959848) (xy 88.411162 -453.988512)
			(xy 88.337639 -454.009417) (xy 88.262299 -454.022321) (xy 88.18601 -454.027078) (xy 88.109651 -454.023631)
			(xy 88.034101 -454.012021) (xy 87.96023 -453.992381) (xy 87.888889 -453.964937) (xy 87.820901 -453.930005)
			(xy 87.757048 -453.887989) (xy 87.698065 -453.839371) (xy 87.644633 -453.784712) (xy 87.597365 -453.724642)
			(xy 87.57666 -453.692514) (xy 87.567745 -453.679104) (xy 87.54439 -453.656947) (xy 87.51623 -453.641345)
			(xy 87.485061 -453.633291) (xy 87.468964 -453.632824) (xy 86.925658 -453.632824) (xy 86.735158 -453.442578)
			(xy 86.718242 -453.426276) (xy 86.679488 -453.399724) (xy 86.636515 -453.380746) (xy 86.590787 -453.369987)
			(xy 86.54386 -453.367814) (xy 86.497333 -453.374301) (xy 86.452791 -453.389228) (xy 86.411749 -453.412085)
			(xy 86.375607 -453.442095) (xy 86.345595 -453.478235) (xy 86.322735 -453.519275) (xy 86.314788 -453.541384)
			(xy 86.302234 -453.577346) (xy 86.270445 -453.64657) (xy 86.231446 -453.712003) (xy 86.185683 -453.772899)
			(xy 86.13368 -453.82856) (xy 86.07603 -453.878349) (xy 86.013393 -453.921699) (xy 85.946486 -453.958112)
			(xy 85.876073 -453.987172) (xy 85.80296 -454.008548) (xy 85.727982 -454.021995) (xy 85.651997 -454.027359)
			(xy 85.575873 -454.024579) (xy 85.500482 -454.013686) (xy 85.426685 -453.994805) (xy 85.355326 -453.968152)
			(xy 85.287221 -453.934032) (xy 85.223148 -453.892834) (xy 85.163841 -453.845031) (xy 85.109977 -453.791168)
			(xy 85.062173 -453.731862) (xy 85.020975 -453.66779) (xy 84.986853 -453.599686) (xy 84.960199 -453.528327)
			(xy 84.941317 -453.45453) (xy 84.930423 -453.379139) (xy 84.927641 -453.303016) (xy 84.933003 -453.227031)
			(xy 84.946449 -453.152053) (xy 84.967823 -453.078939) (xy 84.996883 -453.008525) (xy 85.033295 -452.941617)
			(xy 85.076643 -452.87898) (xy 85.126432 -452.82133) (xy 85.182091 -452.769325) (xy 85.242986 -452.723561)
			(xy 85.308419 -452.684561) (xy 85.377643 -452.652771) (xy 85.413596 -452.640192) (xy 85.435682 -452.632203)
			(xy 85.476699 -452.60934) (xy 85.512819 -452.57933) (xy 85.542811 -452.543196) (xy 85.565653 -452.502167)
			(xy 85.58057 -452.457639) (xy 85.587052 -452.41113) (xy 85.58488 -452.36422) (xy 85.574126 -452.318509)
			(xy 85.555158 -452.275551) (xy 85.528621 -452.236809) (xy 85.512402 -452.219822) (xy 83.279234 -449.986654)
			(xy 83.26337 -449.971468) (xy 83.22745 -449.94621) (xy 83.187722 -449.927504) (xy 83.145369 -449.915907)
			(xy 83.101653 -449.911765) (xy 83.057876 -449.915201) (xy 83.015342 -449.926113) (xy 82.975317 -449.944175)
			(xy 82.938994 -449.96885) (xy 82.907454 -449.999403) (xy 82.881637 -450.034924) (xy 82.862312 -450.074354)
			(xy 82.850054 -450.11652) (xy 82.84718 -450.138292) (xy 82.842559 -450.176085) (xy 82.826162 -450.250444)
			(xy 82.80192 -450.322627) (xy 82.770111 -450.391809) (xy 82.731099 -450.457201) (xy 82.685329 -450.518054)
			(xy 82.633324 -450.573673) (xy 82.575679 -450.623423) (xy 82.513052 -450.666735) (xy 82.44616 -450.703114)
			(xy 82.375766 -450.732144) (xy 82.302675 -450.753494) (xy 82.227724 -450.766919) (xy 82.151767 -450.772266)
			(xy 82.075673 -450.769474) (xy 82.000313 -450.758574) (xy 81.926546 -450.739692) (xy 81.855217 -450.713044)
			(xy 81.78714 -450.678933) (xy 81.723094 -450.637749) (xy 81.663809 -450.589964) (xy 81.609965 -450.536123)
			(xy 81.562177 -450.476842) (xy 81.520989 -450.412798) (xy 81.486874 -450.344724) (xy 81.460221 -450.273396)
			(xy 81.441334 -450.199631) (xy 81.43043 -450.124271) (xy 81.427634 -450.048177) (xy 81.432976 -449.97222)
			(xy 81.446396 -449.897268) (xy 81.467741 -449.824176) (xy 81.496767 -449.75378) (xy 81.533142 -449.686886)
			(xy 81.57645 -449.624256) (xy 81.626196 -449.566608) (xy 81.681812 -449.5146) (xy 81.742663 -449.468826)
			(xy 81.808052 -449.429809) (xy 81.877232 -449.397996) (xy 81.949414 -449.37375) (xy 82.023771 -449.357348)
			(xy 82.061558 -449.35267) (xy 82.083323 -449.349758) (xy 82.125482 -449.337496) (xy 82.164906 -449.318169)
			(xy 82.200421 -449.292353) (xy 82.230969 -449.260816) (xy 82.255641 -449.224497) (xy 82.273702 -449.184477)
			(xy 82.284615 -449.141949) (xy 82.288056 -449.098178) (xy 82.28392 -449.054467) (xy 82.272332 -449.012117)
			(xy 82.253637 -448.97239) (xy 82.228391 -448.936468) (xy 82.213196 -448.920616) (xy 79.200502 -445.907668)
			(xy 79.188379 -445.896287) (xy 79.159575 -445.879696) (xy 79.127461 -445.871117) (xy 79.11084 -445.870584)
			(xy 36.639754 -445.870584) (xy 36.616977 -445.871116) (xy 36.57215 -445.879227) (xy 36.529488 -445.895201)
			(xy 36.490357 -445.918524) (xy 36.45601 -445.94845) (xy 36.427549 -445.98402) (xy 36.405886 -446.024094)
			(xy 36.391713 -446.067387) (xy 36.385486 -446.112514) (xy 36.387404 -446.158029) (xy 36.397405 -446.202472)
			(xy 36.40582 -446.223644) (xy 36.422163 -446.263539) (xy 36.448334 -446.345692) (xy 36.466875 -446.429895)
			(xy 36.47763 -446.515442) (xy 36.480509 -446.601615) (xy 36.475488 -446.687689) (xy 36.462608 -446.772942)
			(xy 36.441978 -446.856658) (xy 36.413772 -446.938134) (xy 36.378226 -447.016687) (xy 36.335638 -447.091655)
			(xy 36.286367 -447.16241) (xy 36.230826 -447.228358) (xy 36.169481 -447.288945) (xy 36.102847 -447.343662)
			(xy 36.031484 -447.392049) (xy 35.955992 -447.433701) (xy 35.877004 -447.468268) (xy 35.795183 -447.495458)
			(xy 35.711217 -447.515045) (xy 35.62581 -447.526863) (xy 35.53968 -447.530814) (xy 35.45355 -447.526863)
			(xy 35.368143 -447.515045) (xy 35.284177 -447.495458) (xy 35.202356 -447.468268) (xy 35.123368 -447.433701)
			(xy 35.047876 -447.392049) (xy 34.976513 -447.343662) (xy 34.909879 -447.288945) (xy 34.848534 -447.228358)
			(xy 34.792993 -447.16241) (xy 34.743722 -447.091655) (xy 34.701134 -447.016687) (xy 34.665588 -446.938134)
			(xy 34.637382 -446.856658) (xy 34.616752 -446.772942) (xy 34.603872 -446.687689) (xy 34.598851 -446.601615)
			(xy 34.60173 -446.515442) (xy 34.612485 -446.429895) (xy 34.631026 -446.345692) (xy 34.657197 -446.263539)
			(xy 34.67354 -446.223644) (xy 34.681928 -446.202462) (xy 34.691926 -446.158021) (xy 34.693842 -446.112509)
			(xy 34.687615 -446.067384) (xy 34.673445 -446.024092) (xy 34.651785 -445.984019) (xy 34.623328 -445.948449)
			(xy 34.588987 -445.918521) (xy 34.549862 -445.895193) (xy 34.507205 -445.879213) (xy 34.462382 -445.871092)
			(xy 34.439606 -445.870584) (xy 32.14116 -445.870584) (xy 25.606756 -439.33618) (xy 25.606756 -380.947168)
			(xy 15.156688 -370.4971) (xy 15.140045 -370.48114) (xy 15.102097 -370.454951) (xy 15.06005 -370.436032)
			(xy 15.01528 -370.425005) (xy 14.969256 -370.422229) (xy 14.923486 -370.427797) (xy 14.87947 -370.441525)
			(xy 14.83865 -370.462965) (xy 14.802364 -370.491412) (xy 14.771802 -370.525935) (xy 14.747965 -370.565403)
			(xy 14.731634 -370.608522) (xy 14.723345 -370.653878) (xy 14.722856 -370.676932) (xy 14.722856 -379.19025)
			(xy 14.429232 -379.484128) (xy 14.413254 -379.500816) (xy 14.387019 -379.538839) (xy 14.368087 -379.580978)
			(xy 14.357083 -379.625844) (xy 14.354368 -379.671961) (xy 14.360032 -379.717808) (xy 14.373889 -379.761877)
			(xy 14.395482 -379.802716) (xy 14.4241 -379.838981) (xy 14.458801 -379.869476) (xy 14.498441 -379.893197)
			(xy 14.541716 -379.909365) (xy 14.5872 -379.917445) (xy 14.633396 -379.917172) (xy 14.678781 -379.908555)
			(xy 14.700504 -379.900688) (xy 14.801382 -379.862147) (xy 15.005783 -379.792387) (xy 15.212878 -379.731084)
			(xy 15.422316 -379.678341) (xy 15.633745 -379.634249) (xy 15.846806 -379.598881) (xy 16.061141 -379.572298)
			(xy 16.276387 -379.554543) (xy 16.492181 -379.545647) (xy 16.60017 -379.545088) (xy 16.70335 -379.545595)
			(xy 16.909551 -379.553696) (xy 17.115275 -379.569887) (xy 17.320205 -379.594142) (xy 17.524025 -379.626424)
			(xy 17.72642 -379.666683) (xy 17.927079 -379.714857) (xy 18.125691 -379.770871) (xy 18.321951 -379.83464)
			(xy 18.515557 -379.906065) (xy 18.706209 -379.985035) (xy 18.893613 -380.07143) (xy 19.077482 -380.165116)
			(xy 19.25753 -380.265948) (xy 19.433481 -380.373771) (xy 19.605064 -380.488418) (xy 19.772012 -380.609714)
			(xy 19.934071 -380.73747) (xy 20.090988 -380.871491) (xy 20.242523 -381.011568) (xy 20.388442 -381.157487)
			(xy 20.528519 -381.309022) (xy 20.66254 -381.465939) (xy 20.790296 -381.627998) (xy 20.911592 -381.794946)
			(xy 21.026239 -381.966529) (xy 21.134062 -382.14248) (xy 21.234894 -382.322528) (xy 21.32858 -382.506397)
			(xy 21.414975 -382.693801) (xy 21.493945 -382.884453) (xy 21.56537 -383.078059) (xy 21.629139 -383.274319)
			(xy 21.685153 -383.472931) (xy 21.733327 -383.67359) (xy 21.773586 -383.875985) (xy 21.805868 -384.079805)
			(xy 21.830123 -384.284735) (xy 21.846314 -384.490459) (xy 21.854415 -384.69666) (xy 21.854922 -384.79984)
			(xy 21.854422 -384.902185) (xy 21.846451 -385.106721) (xy 21.83052 -385.310791) (xy 21.806655 -385.514086)
			(xy 21.77489 -385.716297) (xy 21.735276 -385.917118) (xy 21.687871 -386.116244) (xy 21.632747 -386.313373)
			(xy 21.569988 -386.508206) (xy 21.49969 -386.700447) (xy 21.421959 -386.889804) (xy 21.336913 -387.075991)
			(xy 21.244681 -387.258725) (xy 21.145402 -387.437728) (xy 21.039229 -387.612729) (xy 20.92632 -387.783463)
			(xy 20.806849 -387.949671) (xy 20.680995 -388.1111) (xy 20.548951 -388.267505) (xy 20.410916 -388.41865)
			(xy 20.2671 -388.564304) (xy 20.117721 -388.704248) (xy 19.963005 -388.838268) (xy 19.803188 -388.966162)
			(xy 19.638511 -389.087735) (xy 19.469225 -389.202803) (xy 19.295586 -389.311191) (xy 19.117858 -389.412735)
			(xy 18.936311 -389.50728) (xy 18.751219 -389.594685) (xy 18.562864 -389.674815) (xy 18.371532 -389.747549)
			(xy 18.177512 -389.812777) (xy 17.981099 -389.8704) (xy 17.782591 -389.92033) (xy 17.58229 -389.962492)
			(xy 17.380498 -389.996822) (xy 17.177523 -390.023268) (xy 16.973672 -390.04179) (xy 16.769254 -390.052358)
			(xy 16.564579 -390.054959) (xy 16.359959 -390.049586) (xy 16.155703 -390.03625) (xy 15.952121 -390.014969)
			(xy 15.749523 -389.985777) (xy 15.548215 -389.948717) (xy 15.348502 -389.903845) (xy 15.150689 -389.851231)
			(xy 14.955075 -389.790953) (xy 14.761956 -389.723103) (xy 14.571627 -389.647784) (xy 14.384374 -389.56511)
			(xy 14.200484 -389.475207) (xy 14.020233 -389.378211) (xy 13.843897 -389.274269) (xy 13.671742 -389.163539)
			(xy 13.50403 -389.046189) (xy 13.341015 -388.922397) (xy 13.182945 -388.79235) (xy 13.030059 -388.656247)
			(xy 12.882589 -388.514293) (xy 12.740758 -388.366703) (xy 12.604783 -388.213703) (xy 12.474869 -388.055523)
			(xy 12.351214 -387.892404) (xy 12.234005 -387.724594) (xy 12.123419 -387.552346) (xy 12.019626 -387.375923)
			(xy 11.970766 -387.285992) (xy 11.959769 -387.26642) (xy 11.931919 -387.231211) (xy 11.898316 -387.201443)
			(xy 11.860006 -387.178041) (xy 11.818181 -387.161734) (xy 11.774141 -387.15303) (xy 11.729257 -387.152198)
			(xy 11.684924 -387.159264) (xy 11.642523 -387.17401) (xy 11.603372 -387.195976) (xy 11.56869 -387.224478)
			(xy 11.539554 -387.25863) (xy 11.516872 -387.297371) (xy 11.501348 -387.339493) (xy 11.493467 -387.383688)
			(xy 11.492992 -387.406134) (xy 11.492992 -389.337296) (xy 11.493525 -389.353913) (xy 11.502127 -389.386016)
			(xy 11.518724 -389.414811) (xy 11.530076 -389.426958) (xy 21.16836 -399.064988) (xy 21.16836 -410.586428)
			(xy 19.940524 -411.81401) (xy 19.929147 -411.826136) (xy 19.912552 -411.854938) (xy 19.903972 -411.887052)
			(xy 19.90344 -411.903672) (xy 19.90344 -446.633362) (xy 29.519874 -446.633362) (xy 29.519874 -446.546462)
			(xy 29.527892 -446.459933) (xy 29.54386 -446.374513) (xy 29.567641 -446.290931) (xy 29.599033 -446.209899)
			(xy 29.637767 -446.13211) (xy 29.683514 -446.058226) (xy 29.735883 -445.988879) (xy 29.794427 -445.924659)
			(xy 29.858647 -445.866115) (xy 29.927994 -445.813746) (xy 30.001878 -445.767999) (xy 30.079667 -445.729265)
			(xy 30.160699 -445.697873) (xy 30.244281 -445.674092) (xy 30.329701 -445.658124) (xy 30.41623 -445.650106)
			(xy 30.45968 -445.649604) (xy 30.50313 -445.650106) (xy 30.589659 -445.658124) (xy 30.675079 -445.674092)
			(xy 30.758661 -445.697873) (xy 30.839693 -445.729265) (xy 30.917482 -445.767999) (xy 30.991366 -445.813746)
			(xy 31.060713 -445.866115) (xy 31.124933 -445.924659) (xy 31.183477 -445.988879) (xy 31.235846 -446.058226)
			(xy 31.281593 -446.13211) (xy 31.320327 -446.209899) (xy 31.351719 -446.290931) (xy 31.3755 -446.374513)
			(xy 31.391468 -446.459933) (xy 31.399486 -446.546462) (xy 31.399486 -446.633362) (xy 31.391468 -446.719891)
			(xy 31.3755 -446.805311) (xy 31.351719 -446.888893) (xy 31.320327 -446.969925) (xy 31.281593 -447.047714)
			(xy 31.235846 -447.121598) (xy 31.183477 -447.190945) (xy 31.124933 -447.255165) (xy 31.060713 -447.313709)
			(xy 30.991366 -447.366078) (xy 30.917482 -447.411825) (xy 30.839693 -447.450559) (xy 30.758661 -447.481951)
			(xy 30.675079 -447.505732) (xy 30.589659 -447.5217) (xy 30.50313 -447.529718) (xy 30.41623 -447.529718)
			(xy 30.329701 -447.5217) (xy 30.244281 -447.505732) (xy 30.160699 -447.481951) (xy 30.079667 -447.450559)
			(xy 30.001878 -447.411825) (xy 29.927994 -447.366078) (xy 29.858647 -447.313709) (xy 29.794427 -447.255165)
			(xy 29.735883 -447.190945) (xy 29.683514 -447.121598) (xy 29.637767 -447.047714) (xy 29.599033 -446.969925)
			(xy 29.567641 -446.888893) (xy 29.54386 -446.805311) (xy 29.527892 -446.719891) (xy 29.519874 -446.633362)
			(xy 19.90344 -446.633362) (xy 19.90344 -449.173362) (xy 29.519874 -449.173362) (xy 29.519874 -449.086462)
			(xy 29.527892 -448.999933) (xy 29.54386 -448.914513) (xy 29.567641 -448.830931) (xy 29.599033 -448.749899)
			(xy 29.637767 -448.67211) (xy 29.683514 -448.598226) (xy 29.735883 -448.528879) (xy 29.794427 -448.464659)
			(xy 29.858647 -448.406115) (xy 29.927994 -448.353746) (xy 30.001878 -448.307999) (xy 30.079667 -448.269265)
			(xy 30.160699 -448.237873) (xy 30.244281 -448.214092) (xy 30.329701 -448.198124) (xy 30.41623 -448.190106)
			(xy 30.45968 -448.189604) (xy 30.50313 -448.190106) (xy 30.589659 -448.198124) (xy 30.675079 -448.214092)
			(xy 30.758661 -448.237873) (xy 30.839693 -448.269265) (xy 30.917482 -448.307999) (xy 30.991366 -448.353746)
			(xy 31.060713 -448.406115) (xy 31.124933 -448.464659) (xy 31.183477 -448.528879) (xy 31.235846 -448.598226)
			(xy 31.281593 -448.67211) (xy 31.320327 -448.749899) (xy 31.351719 -448.830931) (xy 31.3755 -448.914513)
			(xy 31.391468 -448.999933) (xy 31.399486 -449.086462) (xy 31.399486 -449.173362) (xy 34.599874 -449.173362)
			(xy 34.599874 -449.086462) (xy 34.607892 -448.999933) (xy 34.62386 -448.914513) (xy 34.647641 -448.830931)
			(xy 34.679033 -448.749899) (xy 34.717767 -448.67211) (xy 34.763514 -448.598226) (xy 34.815883 -448.528879)
			(xy 34.874427 -448.464659) (xy 34.938647 -448.406115) (xy 35.007994 -448.353746) (xy 35.081878 -448.307999)
			(xy 35.159667 -448.269265) (xy 35.240699 -448.237873) (xy 35.324281 -448.214092) (xy 35.409701 -448.198124)
			(xy 35.49623 -448.190106) (xy 35.53968 -448.189604) (xy 35.58313 -448.190106) (xy 35.669659 -448.198124)
			(xy 35.755079 -448.214092) (xy 35.838661 -448.237873) (xy 35.919693 -448.269265) (xy 35.997482 -448.307999)
			(xy 36.071366 -448.353746) (xy 36.140713 -448.406115) (xy 36.204933 -448.464659) (xy 36.263477 -448.528879)
			(xy 36.315846 -448.598226) (xy 36.361593 -448.67211) (xy 36.400327 -448.749899) (xy 36.431719 -448.830931)
			(xy 36.4555 -448.914513) (xy 36.471468 -448.999933) (xy 36.479486 -449.086462) (xy 36.479486 -449.173362)
			(xy 36.471468 -449.259891) (xy 36.4555 -449.345311) (xy 36.431719 -449.428893) (xy 36.400327 -449.509925)
			(xy 36.361593 -449.587714) (xy 36.315846 -449.661598) (xy 36.263477 -449.730945) (xy 36.204933 -449.795165)
			(xy 36.140713 -449.853709) (xy 36.071366 -449.906078) (xy 35.997482 -449.951825) (xy 35.919693 -449.990559)
			(xy 35.838661 -450.021951) (xy 35.755079 -450.045732) (xy 35.669659 -450.0617) (xy 35.58313 -450.069718)
			(xy 35.49623 -450.069718) (xy 35.409701 -450.0617) (xy 35.324281 -450.045732) (xy 35.240699 -450.021951)
			(xy 35.159667 -449.990559) (xy 35.081878 -449.951825) (xy 35.007994 -449.906078) (xy 34.938647 -449.853709)
			(xy 34.874427 -449.795165) (xy 34.815883 -449.730945) (xy 34.763514 -449.661598) (xy 34.717767 -449.587714)
			(xy 34.679033 -449.509925) (xy 34.647641 -449.428893) (xy 34.62386 -449.345311) (xy 34.607892 -449.259891)
			(xy 34.599874 -449.173362) (xy 31.399486 -449.173362) (xy 31.391468 -449.259891) (xy 31.3755 -449.345311)
			(xy 31.351719 -449.428893) (xy 31.320327 -449.509925) (xy 31.281593 -449.587714) (xy 31.235846 -449.661598)
			(xy 31.183477 -449.730945) (xy 31.124933 -449.795165) (xy 31.060713 -449.853709) (xy 30.991366 -449.906078)
			(xy 30.917482 -449.951825) (xy 30.839693 -449.990559) (xy 30.758661 -450.021951) (xy 30.675079 -450.045732)
			(xy 30.589659 -450.0617) (xy 30.50313 -450.069718) (xy 30.41623 -450.069718) (xy 30.329701 -450.0617)
			(xy 30.244281 -450.045732) (xy 30.160699 -450.021951) (xy 30.079667 -449.990559) (xy 30.001878 -449.951825)
			(xy 29.927994 -449.906078) (xy 29.858647 -449.853709) (xy 29.794427 -449.795165) (xy 29.735883 -449.730945)
			(xy 29.683514 -449.661598) (xy 29.637767 -449.587714) (xy 29.599033 -449.509925) (xy 29.567641 -449.428893)
			(xy 29.54386 -449.345311) (xy 29.527892 -449.259891) (xy 29.519874 -449.173362) (xy 19.90344 -449.173362)
			(xy 19.90344 -449.677046) (xy 26.886407 -449.677046) (xy 26.892507 -449.621609) (xy 26.906613 -449.567652)
			(xy 26.928425 -449.516323) (xy 26.957479 -449.468717) (xy 26.993154 -449.425849) (xy 27.034691 -449.388632)
			(xy 27.081204 -449.357859) (xy 27.131701 -449.334187) (xy 27.185108 -449.318119) (xy 27.240284 -449.309999)
			(xy 27.26817 -449.30949) (xy 27.296056 -449.309999) (xy 27.351232 -449.318119) (xy 27.404639 -449.334187)
			(xy 27.455136 -449.357859) (xy 27.501649 -449.388632) (xy 27.543186 -449.425849) (xy 27.578861 -449.468717)
			(xy 27.607915 -449.516323) (xy 27.629727 -449.567652) (xy 27.643833 -449.621609) (xy 27.649933 -449.677046)
			(xy 27.647896 -449.73278) (xy 27.637766 -449.787623) (xy 27.619759 -449.840407) (xy 27.594258 -449.890007)
			(xy 27.561807 -449.935365) (xy 27.523098 -449.975514) (xy 27.478955 -450.0096) (xy 27.43032 -450.036896)
			(xy 27.378229 -450.056819) (xy 27.323792 -450.068945) (xy 27.26817 -450.073016) (xy 27.212548 -450.068945)
			(xy 27.158111 -450.056819) (xy 27.10602 -450.036896) (xy 27.057385 -450.0096) (xy 27.013242 -449.975514)
			(xy 26.974533 -449.935365) (xy 26.942082 -449.890007) (xy 26.916581 -449.840407) (xy 26.898574 -449.787623)
			(xy 26.888444 -449.73278) (xy 26.886407 -449.677046) (xy 19.90344 -449.677046) (xy 19.90344 -451.713362)
			(xy 29.519874 -451.713362) (xy 29.519874 -451.626462) (xy 29.527892 -451.539933) (xy 29.54386 -451.454513)
			(xy 29.567641 -451.370931) (xy 29.599033 -451.289899) (xy 29.637767 -451.21211) (xy 29.683514 -451.138226)
			(xy 29.735883 -451.068879) (xy 29.794427 -451.004659) (xy 29.858647 -450.946115) (xy 29.927994 -450.893746)
			(xy 30.001878 -450.847999) (xy 30.079667 -450.809265) (xy 30.160699 -450.777873) (xy 30.244281 -450.754092)
			(xy 30.329701 -450.738124) (xy 30.41623 -450.730106) (xy 30.45968 -450.729604) (xy 30.50313 -450.730106)
			(xy 30.589659 -450.738124) (xy 30.675079 -450.754092) (xy 30.758661 -450.777873) (xy 30.839693 -450.809265)
			(xy 30.917482 -450.847999) (xy 30.991366 -450.893746) (xy 31.060713 -450.946115) (xy 31.124933 -451.004659)
			(xy 31.183477 -451.068879) (xy 31.235846 -451.138226) (xy 31.281593 -451.21211) (xy 31.320327 -451.289899)
			(xy 31.351719 -451.370931) (xy 31.3755 -451.454513) (xy 31.391468 -451.539933) (xy 31.399486 -451.626462)
			(xy 31.399486 -451.713362) (xy 34.599874 -451.713362) (xy 34.599874 -451.626462) (xy 34.607892 -451.539933)
			(xy 34.62386 -451.454513) (xy 34.647641 -451.370931) (xy 34.679033 -451.289899) (xy 34.717767 -451.21211)
			(xy 34.763514 -451.138226) (xy 34.815883 -451.068879) (xy 34.874427 -451.004659) (xy 34.938647 -450.946115)
			(xy 35.007994 -450.893746) (xy 35.081878 -450.847999) (xy 35.159667 -450.809265) (xy 35.240699 -450.777873)
			(xy 35.324281 -450.754092) (xy 35.409701 -450.738124) (xy 35.49623 -450.730106) (xy 35.53968 -450.729604)
			(xy 35.58313 -450.730106) (xy 35.669659 -450.738124) (xy 35.755079 -450.754092) (xy 35.838661 -450.777873)
			(xy 35.919693 -450.809265) (xy 35.997482 -450.847999) (xy 36.071366 -450.893746) (xy 36.140713 -450.946115)
			(xy 36.204933 -451.004659) (xy 36.263477 -451.068879) (xy 36.315846 -451.138226) (xy 36.361593 -451.21211)
			(xy 36.400327 -451.289899) (xy 36.431719 -451.370931) (xy 36.434596 -451.381042) (xy 39.818314 -451.381042)
			(xy 39.824323 -451.265104) (xy 39.838316 -451.149857) (xy 39.860227 -451.035851) (xy 39.889952 -450.923627)
			(xy 39.927348 -450.813721) (xy 39.972237 -450.706658) (xy 40.024406 -450.602946) (xy 40.083606 -450.503081)
			(xy 40.149555 -450.407538) (xy 40.221938 -450.316772) (xy 40.300411 -450.231217) (xy 40.384599 -450.151279)
			(xy 40.474101 -450.07734) (xy 40.568492 -450.009752) (xy 40.66732 -449.948838) (xy 40.770116 -449.894886)
			(xy 40.876389 -449.848156) (xy 40.985633 -449.808868) (xy 41.097326 -449.777211) (xy 41.210938 -449.753335)
			(xy 41.325926 -449.737354) (xy 41.441743 -449.729345) (xy 41.49979 -449.728844) (xy 41.557837 -449.729345)
			(xy 41.673654 -449.737354) (xy 41.788642 -449.753335) (xy 41.902254 -449.777211) (xy 42.013947 -449.808868)
			(xy 42.123191 -449.848156) (xy 42.229464 -449.894886) (xy 42.33226 -449.948838) (xy 42.431088 -450.009752)
			(xy 42.474869 -450.041101) (xy 63.647829 -450.041101) (xy 63.653878 -449.965531) (xy 63.667925 -449.891033)
			(xy 63.689811 -449.81845) (xy 63.719288 -449.748604) (xy 63.756023 -449.682287) (xy 63.799598 -449.620251)
			(xy 63.84952 -449.563198) (xy 63.905224 -449.511774) (xy 63.966079 -449.466563) (xy 64.031394 -449.428076)
			(xy 64.10043 -449.39675) (xy 64.172405 -449.37294) (xy 64.246503 -449.356915) (xy 64.321884 -449.348856)
			(xy 64.35979 -449.348352) (xy 64.397696 -449.348856) (xy 64.473077 -449.356915) (xy 64.547175 -449.37294)
			(xy 64.61915 -449.39675) (xy 64.688186 -449.428076) (xy 64.753501 -449.466563) (xy 64.814356 -449.511774)
			(xy 64.87006 -449.563198) (xy 64.919982 -449.620251) (xy 64.963557 -449.682287) (xy 65.000292 -449.748604)
			(xy 65.029769 -449.81845) (xy 65.051655 -449.891033) (xy 65.065702 -449.965531) (xy 65.071751 -450.041101)
			(xy 66.187829 -450.041101) (xy 66.193878 -449.965531) (xy 66.207925 -449.891033) (xy 66.229811 -449.81845)
			(xy 66.259288 -449.748604) (xy 66.296023 -449.682287) (xy 66.339598 -449.620251) (xy 66.38952 -449.563198)
			(xy 66.445224 -449.511774) (xy 66.506079 -449.466563) (xy 66.571394 -449.428076) (xy 66.64043 -449.39675)
			(xy 66.712405 -449.37294) (xy 66.786503 -449.356915) (xy 66.861884 -449.348856) (xy 66.89979 -449.348352)
			(xy 66.937696 -449.348856) (xy 67.013077 -449.356915) (xy 67.087175 -449.37294) (xy 67.15915 -449.39675)
			(xy 67.228186 -449.428076) (xy 67.293501 -449.466563) (xy 67.354356 -449.511774) (xy 67.41006 -449.563198)
			(xy 67.459982 -449.620251) (xy 67.503557 -449.682287) (xy 67.540292 -449.748604) (xy 67.569769 -449.81845)
			(xy 67.591655 -449.891033) (xy 67.605702 -449.965531) (xy 67.611751 -450.041101) (xy 68.727829 -450.041101)
			(xy 68.733878 -449.965531) (xy 68.747925 -449.891033) (xy 68.769811 -449.81845) (xy 68.799288 -449.748604)
			(xy 68.836023 -449.682287) (xy 68.879598 -449.620251) (xy 68.92952 -449.563198) (xy 68.985224 -449.511774)
			(xy 69.046079 -449.466563) (xy 69.111394 -449.428076) (xy 69.18043 -449.39675) (xy 69.252405 -449.37294)
			(xy 69.326503 -449.356915) (xy 69.401884 -449.348856) (xy 69.43979 -449.348352) (xy 69.477696 -449.348856)
			(xy 69.553077 -449.356915) (xy 69.627175 -449.37294) (xy 69.69915 -449.39675) (xy 69.768186 -449.428076)
			(xy 69.833501 -449.466563) (xy 69.894356 -449.511774) (xy 69.95006 -449.563198) (xy 69.999982 -449.620251)
			(xy 70.043557 -449.682287) (xy 70.080292 -449.748604) (xy 70.109769 -449.81845) (xy 70.131655 -449.891033)
			(xy 70.145702 -449.965531) (xy 70.151751 -450.041101) (xy 71.267829 -450.041101) (xy 71.273878 -449.965531)
			(xy 71.287925 -449.891033) (xy 71.309811 -449.81845) (xy 71.339288 -449.748604) (xy 71.376023 -449.682287)
			(xy 71.419598 -449.620251) (xy 71.46952 -449.563198) (xy 71.525224 -449.511774) (xy 71.586079 -449.466563)
			(xy 71.651394 -449.428076) (xy 71.72043 -449.39675) (xy 71.792405 -449.37294) (xy 71.866503 -449.356915)
			(xy 71.941884 -449.348856) (xy 71.97979 -449.348352) (xy 72.017696 -449.348856) (xy 72.093077 -449.356915)
			(xy 72.167175 -449.37294) (xy 72.23915 -449.39675) (xy 72.308186 -449.428076) (xy 72.373501 -449.466563)
			(xy 72.434356 -449.511774) (xy 72.49006 -449.563198) (xy 72.539982 -449.620251) (xy 72.583557 -449.682287)
			(xy 72.620292 -449.748604) (xy 72.649769 -449.81845) (xy 72.671655 -449.891033) (xy 72.685702 -449.965531)
			(xy 72.691751 -450.041101) (xy 73.807829 -450.041101) (xy 73.813878 -449.965531) (xy 73.827925 -449.891033)
			(xy 73.849811 -449.81845) (xy 73.879288 -449.748604) (xy 73.916023 -449.682287) (xy 73.959598 -449.620251)
			(xy 74.00952 -449.563198) (xy 74.065224 -449.511774) (xy 74.126079 -449.466563) (xy 74.191394 -449.428076)
			(xy 74.26043 -449.39675) (xy 74.332405 -449.37294) (xy 74.406503 -449.356915) (xy 74.481884 -449.348856)
			(xy 74.51979 -449.348352) (xy 74.557696 -449.348856) (xy 74.633077 -449.356915) (xy 74.707175 -449.37294)
			(xy 74.77915 -449.39675) (xy 74.848186 -449.428076) (xy 74.913501 -449.466563) (xy 74.974356 -449.511774)
			(xy 75.03006 -449.563198) (xy 75.079982 -449.620251) (xy 75.123557 -449.682287) (xy 75.160292 -449.748604)
			(xy 75.189769 -449.81845) (xy 75.211655 -449.891033) (xy 75.225702 -449.965531) (xy 75.231751 -450.041101)
			(xy 76.347829 -450.041101) (xy 76.353878 -449.965531) (xy 76.367925 -449.891033) (xy 76.389811 -449.81845)
			(xy 76.419288 -449.748604) (xy 76.456023 -449.682287) (xy 76.499598 -449.620251) (xy 76.54952 -449.563198)
			(xy 76.605224 -449.511774) (xy 76.666079 -449.466563) (xy 76.731394 -449.428076) (xy 76.80043 -449.39675)
			(xy 76.872405 -449.37294) (xy 76.946503 -449.356915) (xy 77.021884 -449.348856) (xy 77.05979 -449.348352)
			(xy 77.097696 -449.348856) (xy 77.173077 -449.356915) (xy 77.247175 -449.37294) (xy 77.31915 -449.39675)
			(xy 77.388186 -449.428076) (xy 77.453501 -449.466563) (xy 77.514356 -449.511774) (xy 77.57006 -449.563198)
			(xy 77.619982 -449.620251) (xy 77.663557 -449.682287) (xy 77.700292 -449.748604) (xy 77.729769 -449.81845)
			(xy 77.751655 -449.891033) (xy 77.765702 -449.965531) (xy 77.771751 -450.041101) (xy 78.887829 -450.041101)
			(xy 78.893878 -449.965531) (xy 78.907925 -449.891033) (xy 78.929811 -449.81845) (xy 78.959288 -449.748604)
			(xy 78.996023 -449.682287) (xy 79.039598 -449.620251) (xy 79.08952 -449.563198) (xy 79.145224 -449.511774)
			(xy 79.206079 -449.466563) (xy 79.271394 -449.428076) (xy 79.34043 -449.39675) (xy 79.412405 -449.37294)
			(xy 79.486503 -449.356915) (xy 79.561884 -449.348856) (xy 79.59979 -449.348352) (xy 79.637696 -449.348856)
			(xy 79.713077 -449.356915) (xy 79.787175 -449.37294) (xy 79.85915 -449.39675) (xy 79.928186 -449.428076)
			(xy 79.993501 -449.466563) (xy 80.054356 -449.511774) (xy 80.11006 -449.563198) (xy 80.159982 -449.620251)
			(xy 80.203557 -449.682287) (xy 80.240292 -449.748604) (xy 80.269769 -449.81845) (xy 80.291655 -449.891033)
			(xy 80.305702 -449.965531) (xy 80.311751 -450.041101) (xy 80.309732 -450.116885) (xy 80.29967 -450.192025)
			(xy 80.281678 -450.26567) (xy 80.25596 -450.336986) (xy 80.222808 -450.405163) (xy 80.182596 -450.469431)
			(xy 80.135781 -450.52906) (xy 80.082893 -450.583376) (xy 80.024531 -450.631762) (xy 79.961356 -450.67367)
			(xy 79.894085 -450.708626) (xy 79.82348 -450.736233) (xy 79.750339 -450.756179) (xy 79.675494 -450.768238)
			(xy 79.59979 -450.772273) (xy 79.524086 -450.768238) (xy 79.449241 -450.756179) (xy 79.3761 -450.736233)
			(xy 79.305495 -450.708626) (xy 79.238224 -450.67367) (xy 79.175049 -450.631762) (xy 79.116687 -450.583376)
			(xy 79.063799 -450.52906) (xy 79.016984 -450.469431) (xy 78.976772 -450.405163) (xy 78.94362 -450.336986)
			(xy 78.917902 -450.26567) (xy 78.89991 -450.192025) (xy 78.889848 -450.116885) (xy 78.887829 -450.041101)
			(xy 77.771751 -450.041101) (xy 77.769732 -450.116885) (xy 77.75967 -450.192025) (xy 77.741678 -450.26567)
			(xy 77.71596 -450.336986) (xy 77.682808 -450.405163) (xy 77.642596 -450.469431) (xy 77.595781 -450.52906)
			(xy 77.542893 -450.583376) (xy 77.484531 -450.631762) (xy 77.421356 -450.67367) (xy 77.354085 -450.708626)
			(xy 77.28348 -450.736233) (xy 77.210339 -450.756179) (xy 77.135494 -450.768238) (xy 77.05979 -450.772273)
			(xy 76.984086 -450.768238) (xy 76.909241 -450.756179) (xy 76.8361 -450.736233) (xy 76.765495 -450.708626)
			(xy 76.698224 -450.67367) (xy 76.635049 -450.631762) (xy 76.576687 -450.583376) (xy 76.523799 -450.52906)
			(xy 76.476984 -450.469431) (xy 76.436772 -450.405163) (xy 76.40362 -450.336986) (xy 76.377902 -450.26567)
			(xy 76.35991 -450.192025) (xy 76.349848 -450.116885) (xy 76.347829 -450.041101) (xy 75.231751 -450.041101)
			(xy 75.229732 -450.116885) (xy 75.21967 -450.192025) (xy 75.201678 -450.26567) (xy 75.17596 -450.336986)
			(xy 75.142808 -450.405163) (xy 75.102596 -450.469431) (xy 75.055781 -450.52906) (xy 75.002893 -450.583376)
			(xy 74.944531 -450.631762) (xy 74.881356 -450.67367) (xy 74.814085 -450.708626) (xy 74.74348 -450.736233)
			(xy 74.670339 -450.756179) (xy 74.595494 -450.768238) (xy 74.51979 -450.772273) (xy 74.444086 -450.768238)
			(xy 74.369241 -450.756179) (xy 74.2961 -450.736233) (xy 74.225495 -450.708626) (xy 74.158224 -450.67367)
			(xy 74.095049 -450.631762) (xy 74.036687 -450.583376) (xy 73.983799 -450.52906) (xy 73.936984 -450.469431)
			(xy 73.896772 -450.405163) (xy 73.86362 -450.336986) (xy 73.837902 -450.26567) (xy 73.81991 -450.192025)
			(xy 73.809848 -450.116885) (xy 73.807829 -450.041101) (xy 72.691751 -450.041101) (xy 72.689732 -450.116885)
			(xy 72.67967 -450.192025) (xy 72.661678 -450.26567) (xy 72.63596 -450.336986) (xy 72.602808 -450.405163)
			(xy 72.562596 -450.469431) (xy 72.515781 -450.52906) (xy 72.462893 -450.583376) (xy 72.404531 -450.631762)
			(xy 72.341356 -450.67367) (xy 72.274085 -450.708626) (xy 72.20348 -450.736233) (xy 72.130339 -450.756179)
			(xy 72.055494 -450.768238) (xy 71.97979 -450.772273) (xy 71.904086 -450.768238) (xy 71.829241 -450.756179)
			(xy 71.7561 -450.736233) (xy 71.685495 -450.708626) (xy 71.618224 -450.67367) (xy 71.555049 -450.631762)
			(xy 71.496687 -450.583376) (xy 71.443799 -450.52906) (xy 71.396984 -450.469431) (xy 71.356772 -450.405163)
			(xy 71.32362 -450.336986) (xy 71.297902 -450.26567) (xy 71.27991 -450.192025) (xy 71.269848 -450.116885)
			(xy 71.267829 -450.041101) (xy 70.151751 -450.041101) (xy 70.149732 -450.116885) (xy 70.13967 -450.192025)
			(xy 70.121678 -450.26567) (xy 70.09596 -450.336986) (xy 70.062808 -450.405163) (xy 70.022596 -450.469431)
			(xy 69.975781 -450.52906) (xy 69.922893 -450.583376) (xy 69.864531 -450.631762) (xy 69.801356 -450.67367)
			(xy 69.734085 -450.708626) (xy 69.66348 -450.736233) (xy 69.590339 -450.756179) (xy 69.515494 -450.768238)
			(xy 69.43979 -450.772273) (xy 69.364086 -450.768238) (xy 69.289241 -450.756179) (xy 69.2161 -450.736233)
			(xy 69.145495 -450.708626) (xy 69.078224 -450.67367) (xy 69.015049 -450.631762) (xy 68.956687 -450.583376)
			(xy 68.903799 -450.52906) (xy 68.856984 -450.469431) (xy 68.816772 -450.405163) (xy 68.78362 -450.336986)
			(xy 68.757902 -450.26567) (xy 68.73991 -450.192025) (xy 68.729848 -450.116885) (xy 68.727829 -450.041101)
			(xy 67.611751 -450.041101) (xy 67.609732 -450.116885) (xy 67.59967 -450.192025) (xy 67.581678 -450.26567)
			(xy 67.55596 -450.336986) (xy 67.522808 -450.405163) (xy 67.482596 -450.469431) (xy 67.435781 -450.52906)
			(xy 67.382893 -450.583376) (xy 67.324531 -450.631762) (xy 67.261356 -450.67367) (xy 67.194085 -450.708626)
			(xy 67.12348 -450.736233) (xy 67.050339 -450.756179) (xy 66.975494 -450.768238) (xy 66.89979 -450.772273)
			(xy 66.824086 -450.768238) (xy 66.749241 -450.756179) (xy 66.6761 -450.736233) (xy 66.605495 -450.708626)
			(xy 66.538224 -450.67367) (xy 66.475049 -450.631762) (xy 66.416687 -450.583376) (xy 66.363799 -450.52906)
			(xy 66.316984 -450.469431) (xy 66.276772 -450.405163) (xy 66.24362 -450.336986) (xy 66.217902 -450.26567)
			(xy 66.19991 -450.192025) (xy 66.189848 -450.116885) (xy 66.187829 -450.041101) (xy 65.071751 -450.041101)
			(xy 65.069732 -450.116885) (xy 65.05967 -450.192025) (xy 65.041678 -450.26567) (xy 65.01596 -450.336986)
			(xy 64.982808 -450.405163) (xy 64.942596 -450.469431) (xy 64.895781 -450.52906) (xy 64.842893 -450.583376)
			(xy 64.784531 -450.631762) (xy 64.721356 -450.67367) (xy 64.654085 -450.708626) (xy 64.58348 -450.736233)
			(xy 64.510339 -450.756179) (xy 64.435494 -450.768238) (xy 64.35979 -450.772273) (xy 64.284086 -450.768238)
			(xy 64.209241 -450.756179) (xy 64.1361 -450.736233) (xy 64.065495 -450.708626) (xy 63.998224 -450.67367)
			(xy 63.935049 -450.631762) (xy 63.876687 -450.583376) (xy 63.823799 -450.52906) (xy 63.776984 -450.469431)
			(xy 63.736772 -450.405163) (xy 63.70362 -450.336986) (xy 63.677902 -450.26567) (xy 63.65991 -450.192025)
			(xy 63.649848 -450.116885) (xy 63.647829 -450.041101) (xy 42.474869 -450.041101) (xy 42.525479 -450.07734)
			(xy 42.614981 -450.151279) (xy 42.699169 -450.231217) (xy 42.777642 -450.316772) (xy 42.850025 -450.407538)
			(xy 42.915974 -450.503081) (xy 42.975174 -450.602946) (xy 43.027343 -450.706658) (xy 43.072232 -450.813721)
			(xy 43.109628 -450.923627) (xy 43.139353 -451.035851) (xy 43.161264 -451.149857) (xy 43.175257 -451.265104)
			(xy 43.181266 -451.381042) (xy 43.179263 -451.497118) (xy 43.169255 -451.61278) (xy 43.151292 -451.727475)
			(xy 43.125459 -451.840658) (xy 43.091879 -451.951789) (xy 43.050711 -452.060338) (xy 43.002153 -452.165788)
			(xy 42.946436 -452.267637) (xy 42.883824 -452.3654) (xy 42.814617 -452.45861) (xy 42.739144 -452.546823)
			(xy 42.657765 -452.629619) (xy 42.570868 -452.706603) (xy 42.526017 -452.741121) (xy 63.647829 -452.741121)
			(xy 63.653878 -452.665551) (xy 63.667925 -452.591053) (xy 63.689811 -452.51847) (xy 63.719288 -452.448624)
			(xy 63.756023 -452.382307) (xy 63.799598 -452.320271) (xy 63.84952 -452.263218) (xy 63.905224 -452.211794)
			(xy 63.966079 -452.166583) (xy 64.031394 -452.128096) (xy 64.10043 -452.09677) (xy 64.172405 -452.07296)
			(xy 64.246503 -452.056935) (xy 64.321884 -452.048876) (xy 64.35979 -452.048372) (xy 64.397696 -452.048876)
			(xy 64.473077 -452.056935) (xy 64.547175 -452.07296) (xy 64.61915 -452.09677) (xy 64.688186 -452.128096)
			(xy 64.753501 -452.166583) (xy 64.814356 -452.211794) (xy 64.87006 -452.263218) (xy 64.919982 -452.320271)
			(xy 64.963557 -452.382307) (xy 65.000292 -452.448624) (xy 65.029769 -452.51847) (xy 65.051655 -452.591053)
			(xy 65.065702 -452.665551) (xy 65.071751 -452.741121) (xy 66.187829 -452.741121) (xy 66.193878 -452.665551)
			(xy 66.207925 -452.591053) (xy 66.229811 -452.51847) (xy 66.259288 -452.448624) (xy 66.296023 -452.382307)
			(xy 66.339598 -452.320271) (xy 66.38952 -452.263218) (xy 66.445224 -452.211794) (xy 66.506079 -452.166583)
			(xy 66.571394 -452.128096) (xy 66.64043 -452.09677) (xy 66.712405 -452.07296) (xy 66.786503 -452.056935)
			(xy 66.861884 -452.048876) (xy 66.89979 -452.048372) (xy 66.937696 -452.048876) (xy 67.013077 -452.056935)
			(xy 67.087175 -452.07296) (xy 67.15915 -452.09677) (xy 67.228186 -452.128096) (xy 67.293501 -452.166583)
			(xy 67.354356 -452.211794) (xy 67.41006 -452.263218) (xy 67.459982 -452.320271) (xy 67.503557 -452.382307)
			(xy 67.540292 -452.448624) (xy 67.569769 -452.51847) (xy 67.591655 -452.591053) (xy 67.605702 -452.665551)
			(xy 67.611751 -452.741121) (xy 68.727829 -452.741121) (xy 68.733878 -452.665551) (xy 68.747925 -452.591053)
			(xy 68.769811 -452.51847) (xy 68.799288 -452.448624) (xy 68.836023 -452.382307) (xy 68.879598 -452.320271)
			(xy 68.92952 -452.263218) (xy 68.985224 -452.211794) (xy 69.046079 -452.166583) (xy 69.111394 -452.128096)
			(xy 69.18043 -452.09677) (xy 69.252405 -452.07296) (xy 69.326503 -452.056935) (xy 69.401884 -452.048876)
			(xy 69.43979 -452.048372) (xy 69.477696 -452.048876) (xy 69.553077 -452.056935) (xy 69.627175 -452.07296)
			(xy 69.69915 -452.09677) (xy 69.768186 -452.128096) (xy 69.833501 -452.166583) (xy 69.894356 -452.211794)
			(xy 69.95006 -452.263218) (xy 69.999982 -452.320271) (xy 70.043557 -452.382307) (xy 70.080292 -452.448624)
			(xy 70.109769 -452.51847) (xy 70.131655 -452.591053) (xy 70.145702 -452.665551) (xy 70.151751 -452.741121)
			(xy 71.267829 -452.741121) (xy 71.273878 -452.665551) (xy 71.287925 -452.591053) (xy 71.309811 -452.51847)
			(xy 71.339288 -452.448624) (xy 71.376023 -452.382307) (xy 71.419598 -452.320271) (xy 71.46952 -452.263218)
			(xy 71.525224 -452.211794) (xy 71.586079 -452.166583) (xy 71.651394 -452.128096) (xy 71.72043 -452.09677)
			(xy 71.792405 -452.07296) (xy 71.866503 -452.056935) (xy 71.941884 -452.048876) (xy 71.97979 -452.048372)
			(xy 72.017696 -452.048876) (xy 72.093077 -452.056935) (xy 72.167175 -452.07296) (xy 72.23915 -452.09677)
			(xy 72.308186 -452.128096) (xy 72.373501 -452.166583) (xy 72.434356 -452.211794) (xy 72.49006 -452.263218)
			(xy 72.539982 -452.320271) (xy 72.583557 -452.382307) (xy 72.620292 -452.448624) (xy 72.649769 -452.51847)
			(xy 72.671655 -452.591053) (xy 72.685702 -452.665551) (xy 72.691751 -452.741121) (xy 73.807829 -452.741121)
			(xy 73.813878 -452.665551) (xy 73.827925 -452.591053) (xy 73.849811 -452.51847) (xy 73.879288 -452.448624)
			(xy 73.916023 -452.382307) (xy 73.959598 -452.320271) (xy 74.00952 -452.263218) (xy 74.065224 -452.211794)
			(xy 74.126079 -452.166583) (xy 74.191394 -452.128096) (xy 74.26043 -452.09677) (xy 74.332405 -452.07296)
			(xy 74.406503 -452.056935) (xy 74.481884 -452.048876) (xy 74.51979 -452.048372) (xy 74.557696 -452.048876)
			(xy 74.633077 -452.056935) (xy 74.707175 -452.07296) (xy 74.77915 -452.09677) (xy 74.848186 -452.128096)
			(xy 74.913501 -452.166583) (xy 74.974356 -452.211794) (xy 75.03006 -452.263218) (xy 75.079982 -452.320271)
			(xy 75.123557 -452.382307) (xy 75.160292 -452.448624) (xy 75.189769 -452.51847) (xy 75.211655 -452.591053)
			(xy 75.225702 -452.665551) (xy 75.231751 -452.741121) (xy 76.347829 -452.741121) (xy 76.353878 -452.665551)
			(xy 76.367925 -452.591053) (xy 76.389811 -452.51847) (xy 76.419288 -452.448624) (xy 76.456023 -452.382307)
			(xy 76.499598 -452.320271) (xy 76.54952 -452.263218) (xy 76.605224 -452.211794) (xy 76.666079 -452.166583)
			(xy 76.731394 -452.128096) (xy 76.80043 -452.09677) (xy 76.872405 -452.07296) (xy 76.946503 -452.056935)
			(xy 77.021884 -452.048876) (xy 77.05979 -452.048372) (xy 77.097696 -452.048876) (xy 77.173077 -452.056935)
			(xy 77.247175 -452.07296) (xy 77.31915 -452.09677) (xy 77.388186 -452.128096) (xy 77.453501 -452.166583)
			(xy 77.514356 -452.211794) (xy 77.57006 -452.263218) (xy 77.619982 -452.320271) (xy 77.663557 -452.382307)
			(xy 77.700292 -452.448624) (xy 77.729769 -452.51847) (xy 77.751655 -452.591053) (xy 77.765702 -452.665551)
			(xy 77.771751 -452.741121) (xy 78.887829 -452.741121) (xy 78.893878 -452.665551) (xy 78.907925 -452.591053)
			(xy 78.929811 -452.51847) (xy 78.959288 -452.448624) (xy 78.996023 -452.382307) (xy 79.039598 -452.320271)
			(xy 79.08952 -452.263218) (xy 79.145224 -452.211794) (xy 79.206079 -452.166583) (xy 79.271394 -452.128096)
			(xy 79.34043 -452.09677) (xy 79.412405 -452.07296) (xy 79.486503 -452.056935) (xy 79.561884 -452.048876)
			(xy 79.59979 -452.048372) (xy 79.637696 -452.048876) (xy 79.713077 -452.056935) (xy 79.787175 -452.07296)
			(xy 79.85915 -452.09677) (xy 79.928186 -452.128096) (xy 79.993501 -452.166583) (xy 80.054356 -452.211794)
			(xy 80.11006 -452.263218) (xy 80.159982 -452.320271) (xy 80.203557 -452.382307) (xy 80.240292 -452.448624)
			(xy 80.269769 -452.51847) (xy 80.291655 -452.591053) (xy 80.305702 -452.665551) (xy 80.311751 -452.741121)
			(xy 81.427829 -452.741121) (xy 81.433878 -452.665551) (xy 81.447925 -452.591053) (xy 81.469811 -452.51847)
			(xy 81.499288 -452.448624) (xy 81.536023 -452.382307) (xy 81.579598 -452.320271) (xy 81.62952 -452.263218)
			(xy 81.685224 -452.211794) (xy 81.746079 -452.166583) (xy 81.811394 -452.128096) (xy 81.88043 -452.09677)
			(xy 81.952405 -452.07296) (xy 82.026503 -452.056935) (xy 82.101884 -452.048876) (xy 82.13979 -452.048372)
			(xy 82.177696 -452.048876) (xy 82.253077 -452.056935) (xy 82.327175 -452.07296) (xy 82.39915 -452.09677)
			(xy 82.468186 -452.128096) (xy 82.533501 -452.166583) (xy 82.594356 -452.211794) (xy 82.65006 -452.263218)
			(xy 82.699982 -452.320271) (xy 82.743557 -452.382307) (xy 82.780292 -452.448624) (xy 82.809769 -452.51847)
			(xy 82.831655 -452.591053) (xy 82.845702 -452.665551) (xy 82.851751 -452.741121) (xy 82.849732 -452.816905)
			(xy 82.83967 -452.892045) (xy 82.821678 -452.96569) (xy 82.79596 -453.037006) (xy 82.762808 -453.105183)
			(xy 82.722596 -453.169451) (xy 82.675781 -453.22908) (xy 82.622893 -453.283396) (xy 82.564531 -453.331782)
			(xy 82.501356 -453.37369) (xy 82.434085 -453.408646) (xy 82.36348 -453.436253) (xy 82.290339 -453.456199)
			(xy 82.215494 -453.468258) (xy 82.13979 -453.472293) (xy 82.064086 -453.468258) (xy 81.989241 -453.456199)
			(xy 81.9161 -453.436253) (xy 81.845495 -453.408646) (xy 81.778224 -453.37369) (xy 81.715049 -453.331782)
			(xy 81.656687 -453.283396) (xy 81.603799 -453.22908) (xy 81.556984 -453.169451) (xy 81.516772 -453.105183)
			(xy 81.48362 -453.037006) (xy 81.457902 -452.96569) (xy 81.43991 -452.892045) (xy 81.429848 -452.816905)
			(xy 81.427829 -452.741121) (xy 80.311751 -452.741121) (xy 80.309732 -452.816905) (xy 80.29967 -452.892045)
			(xy 80.281678 -452.96569) (xy 80.25596 -453.037006) (xy 80.222808 -453.105183) (xy 80.182596 -453.169451)
			(xy 80.135781 -453.22908) (xy 80.082893 -453.283396) (xy 80.024531 -453.331782) (xy 79.961356 -453.37369)
			(xy 79.894085 -453.408646) (xy 79.82348 -453.436253) (xy 79.750339 -453.456199) (xy 79.675494 -453.468258)
			(xy 79.59979 -453.472293) (xy 79.524086 -453.468258) (xy 79.449241 -453.456199) (xy 79.3761 -453.436253)
			(xy 79.305495 -453.408646) (xy 79.238224 -453.37369) (xy 79.175049 -453.331782) (xy 79.116687 -453.283396)
			(xy 79.063799 -453.22908) (xy 79.016984 -453.169451) (xy 78.976772 -453.105183) (xy 78.94362 -453.037006)
			(xy 78.917902 -452.96569) (xy 78.89991 -452.892045) (xy 78.889848 -452.816905) (xy 78.887829 -452.741121)
			(xy 77.771751 -452.741121) (xy 77.769732 -452.816905) (xy 77.75967 -452.892045) (xy 77.741678 -452.96569)
			(xy 77.71596 -453.037006) (xy 77.682808 -453.105183) (xy 77.642596 -453.169451) (xy 77.595781 -453.22908)
			(xy 77.542893 -453.283396) (xy 77.484531 -453.331782) (xy 77.421356 -453.37369) (xy 77.354085 -453.408646)
			(xy 77.28348 -453.436253) (xy 77.210339 -453.456199) (xy 77.135494 -453.468258) (xy 77.05979 -453.472293)
			(xy 76.984086 -453.468258) (xy 76.909241 -453.456199) (xy 76.8361 -453.436253) (xy 76.765495 -453.408646)
			(xy 76.698224 -453.37369) (xy 76.635049 -453.331782) (xy 76.576687 -453.283396) (xy 76.523799 -453.22908)
			(xy 76.476984 -453.169451) (xy 76.436772 -453.105183) (xy 76.40362 -453.037006) (xy 76.377902 -452.96569)
			(xy 76.35991 -452.892045) (xy 76.349848 -452.816905) (xy 76.347829 -452.741121) (xy 75.231751 -452.741121)
			(xy 75.229732 -452.816905) (xy 75.21967 -452.892045) (xy 75.201678 -452.96569) (xy 75.17596 -453.037006)
			(xy 75.142808 -453.105183) (xy 75.102596 -453.169451) (xy 75.055781 -453.22908) (xy 75.002893 -453.283396)
			(xy 74.944531 -453.331782) (xy 74.881356 -453.37369) (xy 74.814085 -453.408646) (xy 74.74348 -453.436253)
			(xy 74.670339 -453.456199) (xy 74.595494 -453.468258) (xy 74.51979 -453.472293) (xy 74.444086 -453.468258)
			(xy 74.369241 -453.456199) (xy 74.2961 -453.436253) (xy 74.225495 -453.408646) (xy 74.158224 -453.37369)
			(xy 74.095049 -453.331782) (xy 74.036687 -453.283396) (xy 73.983799 -453.22908) (xy 73.936984 -453.169451)
			(xy 73.896772 -453.105183) (xy 73.86362 -453.037006) (xy 73.837902 -452.96569) (xy 73.81991 -452.892045)
			(xy 73.809848 -452.816905) (xy 73.807829 -452.741121) (xy 72.691751 -452.741121) (xy 72.689732 -452.816905)
			(xy 72.67967 -452.892045) (xy 72.661678 -452.96569) (xy 72.63596 -453.037006) (xy 72.602808 -453.105183)
			(xy 72.562596 -453.169451) (xy 72.515781 -453.22908) (xy 72.462893 -453.283396) (xy 72.404531 -453.331782)
			(xy 72.341356 -453.37369) (xy 72.274085 -453.408646) (xy 72.20348 -453.436253) (xy 72.130339 -453.456199)
			(xy 72.055494 -453.468258) (xy 71.97979 -453.472293) (xy 71.904086 -453.468258) (xy 71.829241 -453.456199)
			(xy 71.7561 -453.436253) (xy 71.685495 -453.408646) (xy 71.618224 -453.37369) (xy 71.555049 -453.331782)
			(xy 71.496687 -453.283396) (xy 71.443799 -453.22908) (xy 71.396984 -453.169451) (xy 71.356772 -453.105183)
			(xy 71.32362 -453.037006) (xy 71.297902 -452.96569) (xy 71.27991 -452.892045) (xy 71.269848 -452.816905)
			(xy 71.267829 -452.741121) (xy 70.151751 -452.741121) (xy 70.149732 -452.816905) (xy 70.13967 -452.892045)
			(xy 70.121678 -452.96569) (xy 70.09596 -453.037006) (xy 70.062808 -453.105183) (xy 70.022596 -453.169451)
			(xy 69.975781 -453.22908) (xy 69.922893 -453.283396) (xy 69.864531 -453.331782) (xy 69.801356 -453.37369)
			(xy 69.734085 -453.408646) (xy 69.66348 -453.436253) (xy 69.590339 -453.456199) (xy 69.515494 -453.468258)
			(xy 69.43979 -453.472293) (xy 69.364086 -453.468258) (xy 69.289241 -453.456199) (xy 69.2161 -453.436253)
			(xy 69.145495 -453.408646) (xy 69.078224 -453.37369) (xy 69.015049 -453.331782) (xy 68.956687 -453.283396)
			(xy 68.903799 -453.22908) (xy 68.856984 -453.169451) (xy 68.816772 -453.105183) (xy 68.78362 -453.037006)
			(xy 68.757902 -452.96569) (xy 68.73991 -452.892045) (xy 68.729848 -452.816905) (xy 68.727829 -452.741121)
			(xy 67.611751 -452.741121) (xy 67.609732 -452.816905) (xy 67.59967 -452.892045) (xy 67.581678 -452.96569)
			(xy 67.55596 -453.037006) (xy 67.522808 -453.105183) (xy 67.482596 -453.169451) (xy 67.435781 -453.22908)
			(xy 67.382893 -453.283396) (xy 67.324531 -453.331782) (xy 67.261356 -453.37369) (xy 67.194085 -453.408646)
			(xy 67.12348 -453.436253) (xy 67.050339 -453.456199) (xy 66.975494 -453.468258) (xy 66.89979 -453.472293)
			(xy 66.824086 -453.468258) (xy 66.749241 -453.456199) (xy 66.6761 -453.436253) (xy 66.605495 -453.408646)
			(xy 66.538224 -453.37369) (xy 66.475049 -453.331782) (xy 66.416687 -453.283396) (xy 66.363799 -453.22908)
			(xy 66.316984 -453.169451) (xy 66.276772 -453.105183) (xy 66.24362 -453.037006) (xy 66.217902 -452.96569)
			(xy 66.19991 -452.892045) (xy 66.189848 -452.816905) (xy 66.187829 -452.741121) (xy 65.071751 -452.741121)
			(xy 65.069732 -452.816905) (xy 65.05967 -452.892045) (xy 65.041678 -452.96569) (xy 65.01596 -453.037006)
			(xy 64.982808 -453.105183) (xy 64.942596 -453.169451) (xy 64.895781 -453.22908) (xy 64.842893 -453.283396)
			(xy 64.784531 -453.331782) (xy 64.721356 -453.37369) (xy 64.654085 -453.408646) (xy 64.58348 -453.436253)
			(xy 64.510339 -453.456199) (xy 64.435494 -453.468258) (xy 64.35979 -453.472293) (xy 64.284086 -453.468258)
			(xy 64.209241 -453.456199) (xy 64.1361 -453.436253) (xy 64.065495 -453.408646) (xy 63.998224 -453.37369)
			(xy 63.935049 -453.331782) (xy 63.876687 -453.283396) (xy 63.823799 -453.22908) (xy 63.776984 -453.169451)
			(xy 63.736772 -453.105183) (xy 63.70362 -453.037006) (xy 63.677902 -452.96569) (xy 63.65991 -452.892045)
			(xy 63.649848 -452.816905) (xy 63.647829 -452.741121) (xy 42.526017 -452.741121) (xy 42.478867 -452.777408)
			(xy 42.3822 -452.841698) (xy 42.281328 -452.899165) (xy 42.176731 -452.949536) (xy 42.068908 -452.992571)
			(xy 41.958374 -453.028065) (xy 41.845654 -453.055848) (xy 41.731286 -453.075788) (xy 41.615814 -453.08779)
			(xy 41.49979 -453.091797) (xy 41.383766 -453.08779) (xy 41.268294 -453.075788) (xy 41.153926 -453.055848)
			(xy 41.041206 -453.028065) (xy 40.930672 -452.992571) (xy 40.822849 -452.949536) (xy 40.718252 -452.899165)
			(xy 40.61738 -452.841698) (xy 40.520713 -452.777408) (xy 40.428712 -452.706603) (xy 40.341815 -452.629619)
			(xy 40.260436 -452.546823) (xy 40.184963 -452.45861) (xy 40.115756 -452.3654) (xy 40.053144 -452.267637)
			(xy 39.997427 -452.165788) (xy 39.948869 -452.060338) (xy 39.907701 -451.951789) (xy 39.874121 -451.840658)
			(xy 39.848288 -451.727475) (xy 39.830325 -451.61278) (xy 39.820317 -451.497118) (xy 39.818314 -451.381042)
			(xy 36.434596 -451.381042) (xy 36.4555 -451.454513) (xy 36.471468 -451.539933) (xy 36.479486 -451.626462)
			(xy 36.479486 -451.713362) (xy 36.471468 -451.799891) (xy 36.4555 -451.885311) (xy 36.431719 -451.968893)
			(xy 36.400327 -452.049925) (xy 36.361593 -452.127714) (xy 36.315846 -452.201598) (xy 36.263477 -452.270945)
			(xy 36.204933 -452.335165) (xy 36.140713 -452.393709) (xy 36.071366 -452.446078) (xy 35.997482 -452.491825)
			(xy 35.919693 -452.530559) (xy 35.838661 -452.561951) (xy 35.755079 -452.585732) (xy 35.669659 -452.6017)
			(xy 35.58313 -452.609718) (xy 35.49623 -452.609718) (xy 35.409701 -452.6017) (xy 35.324281 -452.585732)
			(xy 35.240699 -452.561951) (xy 35.159667 -452.530559) (xy 35.081878 -452.491825) (xy 35.007994 -452.446078)
			(xy 34.938647 -452.393709) (xy 34.874427 -452.335165) (xy 34.815883 -452.270945) (xy 34.763514 -452.201598)
			(xy 34.717767 -452.127714) (xy 34.679033 -452.049925) (xy 34.647641 -451.968893) (xy 34.62386 -451.885311)
			(xy 34.607892 -451.799891) (xy 34.599874 -451.713362) (xy 31.399486 -451.713362) (xy 31.391468 -451.799891)
			(xy 31.3755 -451.885311) (xy 31.351719 -451.968893) (xy 31.320327 -452.049925) (xy 31.281593 -452.127714)
			(xy 31.235846 -452.201598) (xy 31.183477 -452.270945) (xy 31.124933 -452.335165) (xy 31.060713 -452.393709)
			(xy 30.991366 -452.446078) (xy 30.917482 -452.491825) (xy 30.839693 -452.530559) (xy 30.758661 -452.561951)
			(xy 30.675079 -452.585732) (xy 30.589659 -452.6017) (xy 30.50313 -452.609718) (xy 30.41623 -452.609718)
			(xy 30.329701 -452.6017) (xy 30.244281 -452.585732) (xy 30.160699 -452.561951) (xy 30.079667 -452.530559)
			(xy 30.001878 -452.491825) (xy 29.927994 -452.446078) (xy 29.858647 -452.393709) (xy 29.794427 -452.335165)
			(xy 29.735883 -452.270945) (xy 29.683514 -452.201598) (xy 29.637767 -452.127714) (xy 29.599033 -452.049925)
			(xy 29.567641 -451.968893) (xy 29.54386 -451.885311) (xy 29.527892 -451.799891) (xy 29.519874 -451.713362)
			(xy 19.90344 -451.713362) (xy 19.90344 -452.244224) (xy 26.890979 -452.244224) (xy 26.897079 -452.188787)
			(xy 26.911185 -452.13483) (xy 26.932997 -452.083501) (xy 26.962051 -452.035895) (xy 26.997726 -451.993027)
			(xy 27.039263 -451.95581) (xy 27.085776 -451.925037) (xy 27.136273 -451.901365) (xy 27.18968 -451.885297)
			(xy 27.244856 -451.877177) (xy 27.272742 -451.876668) (xy 27.300628 -451.877177) (xy 27.355804 -451.885297)
			(xy 27.409211 -451.901365) (xy 27.459708 -451.925037) (xy 27.506221 -451.95581) (xy 27.547758 -451.993027)
			(xy 27.583433 -452.035895) (xy 27.612487 -452.083501) (xy 27.634299 -452.13483) (xy 27.648405 -452.188787)
			(xy 27.654505 -452.244224) (xy 27.652468 -452.299958) (xy 27.642338 -452.354801) (xy 27.624331 -452.407585)
			(xy 27.59883 -452.457185) (xy 27.566379 -452.502543) (xy 27.52767 -452.542692) (xy 27.483527 -452.576778)
			(xy 27.434892 -452.604074) (xy 27.382801 -452.623997) (xy 27.328364 -452.636123) (xy 27.272742 -452.640194)
			(xy 27.21712 -452.636123) (xy 27.162683 -452.623997) (xy 27.110592 -452.604074) (xy 27.061957 -452.576778)
			(xy 27.017814 -452.542692) (xy 26.979105 -452.502543) (xy 26.946654 -452.457185) (xy 26.921153 -452.407585)
			(xy 26.903146 -452.354801) (xy 26.893016 -452.299958) (xy 26.890979 -452.244224) (xy 19.90344 -452.244224)
			(xy 19.90344 -454.253362) (xy 29.519874 -454.253362) (xy 29.519874 -454.166462) (xy 29.527892 -454.079933)
			(xy 29.54386 -453.994513) (xy 29.567641 -453.910931) (xy 29.599033 -453.829899) (xy 29.637767 -453.75211)
			(xy 29.683514 -453.678226) (xy 29.735883 -453.608879) (xy 29.794427 -453.544659) (xy 29.858647 -453.486115)
			(xy 29.927994 -453.433746) (xy 30.001878 -453.387999) (xy 30.079667 -453.349265) (xy 30.160699 -453.317873)
			(xy 30.244281 -453.294092) (xy 30.329701 -453.278124) (xy 30.41623 -453.270106) (xy 30.45968 -453.269604)
			(xy 30.50313 -453.270106) (xy 30.589659 -453.278124) (xy 30.675079 -453.294092) (xy 30.758661 -453.317873)
			(xy 30.839693 -453.349265) (xy 30.917482 -453.387999) (xy 30.991366 -453.433746) (xy 31.060713 -453.486115)
			(xy 31.124933 -453.544659) (xy 31.183477 -453.608879) (xy 31.235846 -453.678226) (xy 31.281593 -453.75211)
			(xy 31.320327 -453.829899) (xy 31.351719 -453.910931) (xy 31.3755 -453.994513) (xy 31.391468 -454.079933)
			(xy 31.399486 -454.166462) (xy 31.399486 -454.253362) (xy 34.599874 -454.253362) (xy 34.599874 -454.166462)
			(xy 34.607892 -454.079933) (xy 34.62386 -453.994513) (xy 34.647641 -453.910931) (xy 34.679033 -453.829899)
			(xy 34.717767 -453.75211) (xy 34.763514 -453.678226) (xy 34.815883 -453.608879) (xy 34.874427 -453.544659)
			(xy 34.938647 -453.486115) (xy 35.007994 -453.433746) (xy 35.081878 -453.387999) (xy 35.159667 -453.349265)
			(xy 35.240699 -453.317873) (xy 35.324281 -453.294092) (xy 35.409701 -453.278124) (xy 35.49623 -453.270106)
			(xy 35.53968 -453.269604) (xy 35.58313 -453.270106) (xy 35.669659 -453.278124) (xy 35.755079 -453.294092)
			(xy 35.838661 -453.317873) (xy 35.919693 -453.349265) (xy 35.997482 -453.387999) (xy 36.071366 -453.433746)
			(xy 36.140713 -453.486115) (xy 36.204933 -453.544659) (xy 36.263477 -453.608879) (xy 36.315846 -453.678226)
			(xy 36.361593 -453.75211) (xy 36.400327 -453.829899) (xy 36.431719 -453.910931) (xy 36.4555 -453.994513)
			(xy 36.471468 -454.079933) (xy 36.479486 -454.166462) (xy 36.479486 -454.253362) (xy 36.471468 -454.339891)
			(xy 36.4555 -454.425311) (xy 36.431719 -454.508893) (xy 36.400327 -454.589925) (xy 36.361593 -454.667714)
			(xy 36.315846 -454.741598) (xy 36.263477 -454.810945) (xy 36.204933 -454.875165) (xy 36.140713 -454.933709)
			(xy 36.071366 -454.986078) (xy 35.997482 -455.031825) (xy 35.919693 -455.070559) (xy 35.838661 -455.101951)
			(xy 35.755079 -455.125732) (xy 35.669659 -455.1417) (xy 35.58313 -455.149718) (xy 35.49623 -455.149718)
			(xy 35.409701 -455.1417) (xy 35.324281 -455.125732) (xy 35.240699 -455.101951) (xy 35.159667 -455.070559)
			(xy 35.081878 -455.031825) (xy 35.007994 -454.986078) (xy 34.938647 -454.933709) (xy 34.874427 -454.875165)
			(xy 34.815883 -454.810945) (xy 34.763514 -454.741598) (xy 34.717767 -454.667714) (xy 34.679033 -454.589925)
			(xy 34.647641 -454.508893) (xy 34.62386 -454.425311) (xy 34.607892 -454.339891) (xy 34.599874 -454.253362)
			(xy 31.399486 -454.253362) (xy 31.391468 -454.339891) (xy 31.3755 -454.425311) (xy 31.351719 -454.508893)
			(xy 31.320327 -454.589925) (xy 31.281593 -454.667714) (xy 31.235846 -454.741598) (xy 31.183477 -454.810945)
			(xy 31.124933 -454.875165) (xy 31.060713 -454.933709) (xy 30.991366 -454.986078) (xy 30.917482 -455.031825)
			(xy 30.839693 -455.070559) (xy 30.758661 -455.101951) (xy 30.675079 -455.125732) (xy 30.589659 -455.1417)
			(xy 30.50313 -455.149718) (xy 30.41623 -455.149718) (xy 30.329701 -455.1417) (xy 30.244281 -455.125732)
			(xy 30.160699 -455.101951) (xy 30.079667 -455.070559) (xy 30.001878 -455.031825) (xy 29.927994 -454.986078)
			(xy 29.858647 -454.933709) (xy 29.794427 -454.875165) (xy 29.735883 -454.810945) (xy 29.683514 -454.741598)
			(xy 29.637767 -454.667714) (xy 29.599033 -454.589925) (xy 29.567641 -454.508893) (xy 29.54386 -454.425311)
			(xy 29.527892 -454.339891) (xy 29.519874 -454.253362) (xy 19.90344 -454.253362) (xy 19.90344 -455.070073)
			(xy 26.851826 -455.070073) (xy 26.854933 -455.014607) (xy 26.866051 -454.960178) (xy 26.884946 -454.907936)
			(xy 26.911217 -454.858987) (xy 26.944309 -454.814366) (xy 26.983523 -454.775016) (xy 27.02803 -454.741769)
			(xy 27.076887 -454.715328) (xy 27.129063 -454.696252) (xy 27.183453 -454.684945) (xy 27.238908 -454.681646)
			(xy 27.294256 -454.686424) (xy 27.348325 -454.699179) (xy 27.399973 -454.71964) (xy 27.448107 -454.747375)
			(xy 27.491711 -454.781798) (xy 27.52986 -454.822181) (xy 27.56175 -454.867669) (xy 27.586706 -454.917302)
			(xy 27.604199 -454.970029) (xy 27.613861 -455.024736) (xy 27.615487 -455.080265) (xy 27.609042 -455.135443)
			(xy 27.594662 -455.189104) (xy 27.572653 -455.240111) (xy 27.558492 -455.264012) (xy 27.547184 -455.283157)
			(xy 27.530785 -455.324484) (xy 27.521838 -455.368037) (xy 27.520619 -455.412482) (xy 27.527165 -455.456459)
			(xy 27.541275 -455.498623) (xy 27.562517 -455.537682) (xy 27.576018 -455.55535) (xy 27.592935 -455.577387)
			(xy 27.62084 -455.625427) (xy 27.641483 -455.677005) (xy 27.654428 -455.731032) (xy 27.6594 -455.786365)
			(xy 27.656294 -455.841834) (xy 27.645177 -455.896266) (xy 27.626283 -455.94851) (xy 27.600012 -455.997462)
			(xy 27.566919 -456.042086) (xy 27.527705 -456.081439) (xy 27.483197 -456.114689) (xy 27.434338 -456.141132)
			(xy 27.382161 -456.16021) (xy 27.327768 -456.171519) (xy 27.27231 -456.17482) (xy 27.21696 -456.170043)
			(xy 27.162888 -456.157289) (xy 27.111237 -456.136828) (xy 27.0631 -456.109092) (xy 27.019494 -456.074669)
			(xy 26.981342 -456.034285) (xy 26.94945 -455.988795) (xy 26.924492 -455.93916) (xy 26.906997 -455.886431)
			(xy 26.897334 -455.831722) (xy 26.895707 -455.77619) (xy 26.902152 -455.721009) (xy 26.916531 -455.667346)
			(xy 26.938541 -455.616336) (xy 26.952702 -455.592434) (xy 26.963957 -455.573261) (xy 26.980355 -455.531941)
			(xy 26.989303 -455.488396) (xy 26.990528 -455.443958) (xy 26.983992 -455.399986) (xy 26.969895 -455.357825)
			(xy 26.948669 -455.318766) (xy 26.935176 -455.301096) (xy 26.91828 -455.279043) (xy 26.890378 -455.231005)
			(xy 26.869738 -455.179429) (xy 26.856796 -455.125404) (xy 26.851826 -455.070073) (xy 19.90344 -455.070073)
			(xy 19.90344 -456.793362) (xy 29.519874 -456.793362) (xy 29.519874 -456.706462) (xy 29.527892 -456.619933)
			(xy 29.54386 -456.534513) (xy 29.567641 -456.450931) (xy 29.599033 -456.369899) (xy 29.637767 -456.29211)
			(xy 29.683514 -456.218226) (xy 29.735883 -456.148879) (xy 29.794427 -456.084659) (xy 29.858647 -456.026115)
			(xy 29.927994 -455.973746) (xy 30.001878 -455.927999) (xy 30.079667 -455.889265) (xy 30.160699 -455.857873)
			(xy 30.244281 -455.834092) (xy 30.329701 -455.818124) (xy 30.41623 -455.810106) (xy 30.45968 -455.809604)
			(xy 30.50313 -455.810106) (xy 30.589659 -455.818124) (xy 30.675079 -455.834092) (xy 30.758661 -455.857873)
			(xy 30.839693 -455.889265) (xy 30.917482 -455.927999) (xy 30.991366 -455.973746) (xy 31.060713 -456.026115)
			(xy 31.124933 -456.084659) (xy 31.183477 -456.148879) (xy 31.235846 -456.218226) (xy 31.281593 -456.29211)
			(xy 31.320327 -456.369899) (xy 31.351719 -456.450931) (xy 31.3755 -456.534513) (xy 31.391468 -456.619933)
			(xy 31.399486 -456.706462) (xy 31.399486 -456.793362) (xy 34.599874 -456.793362) (xy 34.599874 -456.706462)
			(xy 34.607892 -456.619933) (xy 34.62386 -456.534513) (xy 34.647641 -456.450931) (xy 34.679033 -456.369899)
			(xy 34.717767 -456.29211) (xy 34.763514 -456.218226) (xy 34.815883 -456.148879) (xy 34.874427 -456.084659)
			(xy 34.938647 -456.026115) (xy 35.007994 -455.973746) (xy 35.081878 -455.927999) (xy 35.159667 -455.889265)
			(xy 35.240699 -455.857873) (xy 35.324281 -455.834092) (xy 35.409701 -455.818124) (xy 35.49623 -455.810106)
			(xy 35.53968 -455.809604) (xy 35.58313 -455.810106) (xy 35.669659 -455.818124) (xy 35.755079 -455.834092)
			(xy 35.838661 -455.857873) (xy 35.919693 -455.889265) (xy 35.997482 -455.927999) (xy 36.071366 -455.973746)
			(xy 36.140713 -456.026115) (xy 36.204933 -456.084659) (xy 36.263477 -456.148879) (xy 36.315846 -456.218226)
			(xy 36.361593 -456.29211) (xy 36.400327 -456.369899) (xy 36.431719 -456.450931) (xy 36.4555 -456.534513)
			(xy 36.471468 -456.619933) (xy 36.479486 -456.706462) (xy 36.479486 -456.793362) (xy 36.471468 -456.879891)
			(xy 36.4555 -456.965311) (xy 36.431719 -457.048893) (xy 36.400327 -457.129925) (xy 36.361593 -457.207714)
			(xy 36.315846 -457.281598) (xy 36.263477 -457.350945) (xy 36.223697 -457.394582) (xy 39.357045 -457.394582)
			(xy 39.363145 -457.339145) (xy 39.377251 -457.285188) (xy 39.399063 -457.233859) (xy 39.428117 -457.186253)
			(xy 39.463792 -457.143385) (xy 39.505329 -457.106168) (xy 39.551842 -457.075395) (xy 39.602339 -457.051723)
			(xy 39.655746 -457.035655) (xy 39.710922 -457.027535) (xy 39.738808 -457.027026) (xy 39.766694 -457.027535)
			(xy 39.82187 -457.035655) (xy 39.875277 -457.051723) (xy 39.925774 -457.075395) (xy 39.972287 -457.106168)
			(xy 40.013824 -457.143385) (xy 40.049499 -457.186253) (xy 40.078553 -457.233859) (xy 40.100365 -457.285188)
			(xy 40.114471 -457.339145) (xy 40.120571 -457.394582) (xy 40.118534 -457.450316) (xy 40.108404 -457.505159)
			(xy 40.090397 -457.557943) (xy 40.064896 -457.607543) (xy 40.032445 -457.652901) (xy 39.993736 -457.69305)
			(xy 39.949593 -457.727136) (xy 39.900958 -457.754432) (xy 39.848867 -457.774355) (xy 39.79443 -457.786481)
			(xy 39.738808 -457.790552) (xy 39.683186 -457.786481) (xy 39.628749 -457.774355) (xy 39.576658 -457.754432)
			(xy 39.528023 -457.727136) (xy 39.48388 -457.69305) (xy 39.445171 -457.652901) (xy 39.41272 -457.607543)
			(xy 39.387219 -457.557943) (xy 39.369212 -457.505159) (xy 39.359082 -457.450316) (xy 39.357045 -457.394582)
			(xy 36.223697 -457.394582) (xy 36.204933 -457.415165) (xy 36.140713 -457.473709) (xy 36.071366 -457.526078)
			(xy 35.997482 -457.571825) (xy 35.919693 -457.610559) (xy 35.838661 -457.641951) (xy 35.755079 -457.665732)
			(xy 35.669659 -457.6817) (xy 35.58313 -457.689718) (xy 35.49623 -457.689718) (xy 35.409701 -457.6817)
			(xy 35.324281 -457.665732) (xy 35.240699 -457.641951) (xy 35.159667 -457.610559) (xy 35.081878 -457.571825)
			(xy 35.007994 -457.526078) (xy 34.938647 -457.473709) (xy 34.874427 -457.415165) (xy 34.815883 -457.350945)
			(xy 34.763514 -457.281598) (xy 34.717767 -457.207714) (xy 34.679033 -457.129925) (xy 34.647641 -457.048893)
			(xy 34.62386 -456.965311) (xy 34.607892 -456.879891) (xy 34.599874 -456.793362) (xy 31.399486 -456.793362)
			(xy 31.391468 -456.879891) (xy 31.3755 -456.965311) (xy 31.351719 -457.048893) (xy 31.320327 -457.129925)
			(xy 31.281593 -457.207714) (xy 31.235846 -457.281598) (xy 31.183477 -457.350945) (xy 31.124933 -457.415165)
			(xy 31.060713 -457.473709) (xy 30.991366 -457.526078) (xy 30.917482 -457.571825) (xy 30.839693 -457.610559)
			(xy 30.758661 -457.641951) (xy 30.675079 -457.665732) (xy 30.589659 -457.6817) (xy 30.50313 -457.689718)
			(xy 30.41623 -457.689718) (xy 30.329701 -457.6817) (xy 30.244281 -457.665732) (xy 30.160699 -457.641951)
			(xy 30.079667 -457.610559) (xy 30.001878 -457.571825) (xy 29.927994 -457.526078) (xy 29.858647 -457.473709)
			(xy 29.794427 -457.415165) (xy 29.735883 -457.350945) (xy 29.683514 -457.281598) (xy 29.637767 -457.207714)
			(xy 29.599033 -457.129925) (xy 29.567641 -457.048893) (xy 29.54386 -456.965311) (xy 29.527892 -456.879891)
			(xy 29.519874 -456.793362) (xy 19.90344 -456.793362) (xy 19.90344 -457.752468) (xy 26.750263 -457.752468)
			(xy 26.756363 -457.697031) (xy 26.770469 -457.643074) (xy 26.792281 -457.591745) (xy 26.821335 -457.544139)
			(xy 26.85701 -457.501271) (xy 26.898547 -457.464054) (xy 26.94506 -457.433281) (xy 26.995557 -457.409609)
			(xy 27.048964 -457.393541) (xy 27.10414 -457.385421) (xy 27.132026 -457.384912) (xy 27.159912 -457.385421)
			(xy 27.215088 -457.393541) (xy 27.268495 -457.409609) (xy 27.318992 -457.433281) (xy 27.365505 -457.464054)
			(xy 27.407042 -457.501271) (xy 27.442717 -457.544139) (xy 27.471771 -457.591745) (xy 27.493583 -457.643074)
			(xy 27.507689 -457.697031) (xy 27.513789 -457.752468) (xy 27.511752 -457.808202) (xy 27.501622 -457.863045)
			(xy 27.483615 -457.915829) (xy 27.458114 -457.965429) (xy 27.425663 -458.010787) (xy 27.386954 -458.050936)
			(xy 27.342811 -458.085022) (xy 27.294176 -458.112318) (xy 27.242085 -458.132241) (xy 27.187648 -458.144367)
			(xy 27.132026 -458.148438) (xy 27.076404 -458.144367) (xy 27.021967 -458.132241) (xy 26.969876 -458.112318)
			(xy 26.921241 -458.085022) (xy 26.877098 -458.050936) (xy 26.838389 -458.010787) (xy 26.805938 -457.965429)
			(xy 26.780437 -457.915829) (xy 26.76243 -457.863045) (xy 26.7523 -457.808202) (xy 26.750263 -457.752468)
			(xy 19.90344 -457.752468) (xy 19.90344 -460.309635) (xy 27.157359 -460.309635) (xy 27.157359 -460.246365)
			(xy 27.165618 -460.183636) (xy 27.181994 -460.122522) (xy 27.206207 -460.064069) (xy 27.237843 -460.009276)
			(xy 27.276361 -459.959081) (xy 27.321101 -459.914343) (xy 27.371297 -459.875829) (xy 27.426092 -459.844196)
			(xy 27.484547 -459.819986) (xy 27.545662 -459.803613) (xy 27.608391 -459.795357) (xy 27.640026 -459.794864)
			(xy 28.449778 -459.794864) (xy 28.72867 -460.073756) (xy 29.389324 -460.073756) (xy 29.412764 -460.073118)
			(xy 29.458845 -460.064497) (xy 29.502564 -460.04757) (xy 29.542436 -460.022912) (xy 29.577108 -459.991358)
			(xy 29.605406 -459.953981) (xy 29.626367 -459.912047) (xy 29.639281 -459.86698) (xy 29.643711 -459.820309)
			(xy 29.639505 -459.773617) (xy 29.626806 -459.728489) (xy 29.616908 -459.707234) (xy 29.598093 -459.668112)
			(xy 29.566902 -459.587091) (xy 29.543312 -459.503541) (xy 29.527523 -459.418172) (xy 29.519669 -459.331711)
			(xy 29.519818 -459.244894) (xy 29.527968 -459.15846) (xy 29.544049 -459.073145) (xy 29.567925 -458.989676)
			(xy 29.599393 -458.908763) (xy 29.638185 -458.831094) (xy 29.68397 -458.757332) (xy 29.736359 -458.688103)
			(xy 29.794905 -458.623998) (xy 29.859111 -458.565561) (xy 29.928429 -458.513291) (xy 30.00227 -458.467632)
			(xy 30.080005 -458.428974) (xy 30.160972 -458.397645) (xy 30.244482 -458.373911) (xy 30.329824 -458.357976)
			(xy 30.416271 -458.349974) (xy 30.503089 -458.349974) (xy 30.589536 -458.357976) (xy 30.674878 -458.373911)
			(xy 30.758388 -458.397645) (xy 30.839355 -458.428974) (xy 30.91709 -458.467632) (xy 30.990931 -458.513291)
			(xy 31.060249 -458.565561) (xy 31.124455 -458.623998) (xy 31.183001 -458.688103) (xy 31.23539 -458.757332)
			(xy 31.281175 -458.831094) (xy 31.319967 -458.908763) (xy 31.351435 -458.989676) (xy 31.375311 -459.073145)
			(xy 31.391392 -459.15846) (xy 31.399542 -459.244894) (xy 31.399691 -459.331711) (xy 31.391837 -459.418172)
			(xy 31.376048 -459.503541) (xy 31.352458 -459.587091) (xy 31.321267 -459.668112) (xy 31.302452 -459.707234)
			(xy 31.292581 -459.728512) (xy 31.27984 -459.773646) (xy 31.2756 -459.820351) (xy 31.280006 -459.867041)
			(xy 31.292907 -459.91213) (xy 31.313865 -459.954083) (xy 31.342169 -459.991477) (xy 31.376855 -460.02304)
			(xy 31.416746 -460.0477) (xy 31.460485 -460.064618) (xy 31.506587 -460.07322) (xy 31.530036 -460.073756)
			(xy 34.469324 -460.073756) (xy 34.492764 -460.073118) (xy 34.538845 -460.064497) (xy 34.582564 -460.04757)
			(xy 34.622436 -460.022912) (xy 34.657108 -459.991358) (xy 34.685406 -459.953981) (xy 34.706367 -459.912047)
			(xy 34.719281 -459.86698) (xy 34.723711 -459.820309) (xy 34.719505 -459.773617) (xy 34.706806 -459.728489)
			(xy 34.696908 -459.707234) (xy 34.678093 -459.668112) (xy 34.646902 -459.587091) (xy 34.623312 -459.503541)
			(xy 34.607523 -459.418172) (xy 34.599669 -459.331711) (xy 34.599818 -459.244894) (xy 34.607968 -459.15846)
			(xy 34.624049 -459.073145) (xy 34.647925 -458.989676) (xy 34.679393 -458.908763) (xy 34.718185 -458.831094)
			(xy 34.76397 -458.757332) (xy 34.816359 -458.688103) (xy 34.874905 -458.623998) (xy 34.939111 -458.565561)
			(xy 35.008429 -458.513291) (xy 35.08227 -458.467632) (xy 35.160005 -458.428974) (xy 35.240972 -458.397645)
			(xy 35.324482 -458.373911) (xy 35.409824 -458.357976) (xy 35.496271 -458.349974) (xy 35.583089 -458.349974)
			(xy 35.669536 -458.357976) (xy 35.754878 -458.373911) (xy 35.838388 -458.397645) (xy 35.919355 -458.428974)
			(xy 35.99709 -458.467632) (xy 36.070931 -458.513291) (xy 36.129192 -458.557223) (xy 62.983864 -458.557223)
			(xy 62.983864 -458.485901) (xy 62.99185 -458.415027) (xy 63.00772 -458.345492) (xy 63.031277 -458.278172)
			(xy 63.062222 -458.213913) (xy 63.100168 -458.153522) (xy 63.144637 -458.09776) (xy 63.19507 -458.047327)
			(xy 63.250832 -458.002858) (xy 63.311223 -457.964912) (xy 63.375482 -457.933967) (xy 63.442802 -457.91041)
			(xy 63.512337 -457.89454) (xy 63.583211 -457.886554) (xy 63.618872 -457.886054) (xy 63.654533 -457.886554)
			(xy 63.725407 -457.89454) (xy 63.794942 -457.91041) (xy 63.862262 -457.933967) (xy 63.926521 -457.964912)
			(xy 63.986912 -458.002858) (xy 64.042674 -458.047327) (xy 64.093107 -458.09776) (xy 64.137576 -458.153522)
			(xy 64.175522 -458.213913) (xy 64.206467 -458.278172) (xy 64.230024 -458.345492) (xy 64.245894 -458.415027)
			(xy 64.25388 -458.485901) (xy 64.25388 -458.557223) (xy 65.059298 -458.557223) (xy 65.059298 -458.485901)
			(xy 65.067284 -458.415027) (xy 65.083154 -458.345492) (xy 65.106711 -458.278172) (xy 65.137656 -458.213913)
			(xy 65.175602 -458.153522) (xy 65.220071 -458.09776) (xy 65.270504 -458.047327) (xy 65.326266 -458.002858)
			(xy 65.386657 -457.964912) (xy 65.450916 -457.933967) (xy 65.518236 -457.91041) (xy 65.587771 -457.89454)
			(xy 65.658645 -457.886554) (xy 65.694306 -457.886054) (xy 65.729967 -457.886554) (xy 65.800841 -457.89454)
			(xy 65.870376 -457.91041) (xy 65.937696 -457.933967) (xy 66.001955 -457.964912) (xy 66.062346 -458.002858)
			(xy 66.118108 -458.047327) (xy 66.168541 -458.09776) (xy 66.21301 -458.153522) (xy 66.250956 -458.213913)
			(xy 66.281901 -458.278172) (xy 66.305458 -458.345492) (xy 66.321328 -458.415027) (xy 66.329314 -458.485901)
			(xy 66.329314 -458.557223) (xy 66.329228 -458.557985) (xy 67.283576 -458.557985) (xy 67.283576 -458.486663)
			(xy 67.291562 -458.415789) (xy 67.307432 -458.346254) (xy 67.330989 -458.278934) (xy 67.361934 -458.214675)
			(xy 67.39988 -458.154284) (xy 67.444349 -458.098522) (xy 67.494782 -458.048089) (xy 67.550544 -458.00362)
			(xy 67.610935 -457.965674) (xy 67.675194 -457.934729) (xy 67.742514 -457.911172) (xy 67.812049 -457.895302)
			(xy 67.882923 -457.887316) (xy 67.918584 -457.886816) (xy 67.954245 -457.887316) (xy 68.025119 -457.895302)
			(xy 68.094654 -457.911172) (xy 68.161974 -457.934729) (xy 68.226233 -457.965674) (xy 68.286624 -458.00362)
			(xy 68.342386 -458.048089) (xy 68.392819 -458.098522) (xy 68.437288 -458.154284) (xy 68.475234 -458.214675)
			(xy 68.506179 -458.278934) (xy 68.529736 -458.346254) (xy 68.545606 -458.415789) (xy 68.553592 -458.486663)
			(xy 68.553592 -458.557985) (xy 68.545606 -458.628859) (xy 68.529736 -458.698394) (xy 68.506179 -458.765714)
			(xy 68.475234 -458.829973) (xy 68.437288 -458.890364) (xy 68.392819 -458.946126) (xy 68.342386 -458.996559)
			(xy 68.286624 -459.041028) (xy 68.226233 -459.078974) (xy 68.161974 -459.109919) (xy 68.094654 -459.133476)
			(xy 68.025119 -459.149346) (xy 67.954245 -459.157332) (xy 67.882923 -459.157332) (xy 67.812049 -459.149346)
			(xy 67.742514 -459.133476) (xy 67.675194 -459.109919) (xy 67.610935 -459.078974) (xy 67.550544 -459.041028)
			(xy 67.494782 -458.996559) (xy 67.444349 -458.946126) (xy 67.39988 -458.890364) (xy 67.361934 -458.829973)
			(xy 67.330989 -458.765714) (xy 67.307432 -458.698394) (xy 67.291562 -458.628859) (xy 67.283576 -458.557985)
			(xy 66.329228 -458.557985) (xy 66.321328 -458.628097) (xy 66.305458 -458.697632) (xy 66.281901 -458.764952)
			(xy 66.250956 -458.829211) (xy 66.21301 -458.889602) (xy 66.168541 -458.945364) (xy 66.118108 -458.995797)
			(xy 66.062346 -459.040266) (xy 66.001955 -459.078212) (xy 65.937696 -459.109157) (xy 65.870376 -459.132714)
			(xy 65.800841 -459.148584) (xy 65.729967 -459.15657) (xy 65.658645 -459.15657) (xy 65.587771 -459.148584)
			(xy 65.518236 -459.132714) (xy 65.450916 -459.109157) (xy 65.386657 -459.078212) (xy 65.326266 -459.040266)
			(xy 65.270504 -458.995797) (xy 65.220071 -458.945364) (xy 65.175602 -458.889602) (xy 65.137656 -458.829211)
			(xy 65.106711 -458.764952) (xy 65.083154 -458.697632) (xy 65.067284 -458.628097) (xy 65.059298 -458.557223)
			(xy 64.25388 -458.557223) (xy 64.245894 -458.628097) (xy 64.230024 -458.697632) (xy 64.206467 -458.764952)
			(xy 64.175522 -458.829211) (xy 64.137576 -458.889602) (xy 64.093107 -458.945364) (xy 64.042674 -458.995797)
			(xy 63.986912 -459.040266) (xy 63.926521 -459.078212) (xy 63.862262 -459.109157) (xy 63.794942 -459.132714)
			(xy 63.725407 -459.148584) (xy 63.654533 -459.15657) (xy 63.583211 -459.15657) (xy 63.512337 -459.148584)
			(xy 63.442802 -459.132714) (xy 63.375482 -459.109157) (xy 63.311223 -459.078212) (xy 63.250832 -459.040266)
			(xy 63.19507 -458.995797) (xy 63.144637 -458.945364) (xy 63.100168 -458.889602) (xy 63.062222 -458.829211)
			(xy 63.031277 -458.764952) (xy 63.00772 -458.697632) (xy 62.99185 -458.628097) (xy 62.983864 -458.557223)
			(xy 36.129192 -458.557223) (xy 36.140249 -458.565561) (xy 36.204455 -458.623998) (xy 36.263001 -458.688103)
			(xy 36.31539 -458.757332) (xy 36.361175 -458.831094) (xy 36.399967 -458.908763) (xy 36.431435 -458.989676)
			(xy 36.455311 -459.073145) (xy 36.471392 -459.15846) (xy 36.479542 -459.244894) (xy 36.479691 -459.331711)
			(xy 36.471837 -459.418172) (xy 36.456048 -459.503541) (xy 36.432458 -459.587091) (xy 36.401267 -459.668112)
			(xy 36.382452 -459.707234) (xy 36.372581 -459.728512) (xy 36.35984 -459.773646) (xy 36.3556 -459.820351)
			(xy 36.360006 -459.867041) (xy 36.372907 -459.91213) (xy 36.393865 -459.954083) (xy 36.422169 -459.991477)
			(xy 36.456855 -460.02304) (xy 36.496746 -460.0477) (xy 36.540485 -460.064618) (xy 36.586587 -460.07322)
			(xy 36.610036 -460.073756) (xy 42.636186 -460.073756) (xy 42.876306 -460.313887) (xy 62.983864 -460.313887)
			(xy 62.983864 -460.242565) (xy 62.99185 -460.171691) (xy 63.00772 -460.102156) (xy 63.031277 -460.034836)
			(xy 63.062222 -459.970577) (xy 63.100168 -459.910186) (xy 63.144637 -459.854424) (xy 63.19507 -459.803991)
			(xy 63.250832 -459.759522) (xy 63.311223 -459.721576) (xy 63.375482 -459.690631) (xy 63.442802 -459.667074)
			(xy 63.512337 -459.651204) (xy 63.583211 -459.643218) (xy 63.618872 -459.642718) (xy 63.654533 -459.643218)
			(xy 63.725407 -459.651204) (xy 63.794942 -459.667074) (xy 63.862262 -459.690631) (xy 63.926521 -459.721576)
			(xy 63.986912 -459.759522) (xy 64.042674 -459.803991) (xy 64.093107 -459.854424) (xy 64.137576 -459.910186)
			(xy 64.175522 -459.970577) (xy 64.206467 -460.034836) (xy 64.230024 -460.102156) (xy 64.245894 -460.171691)
			(xy 64.25388 -460.242565) (xy 64.25388 -460.313887) (xy 65.059298 -460.313887) (xy 65.059298 -460.242565)
			(xy 65.067284 -460.171691) (xy 65.083154 -460.102156) (xy 65.106711 -460.034836) (xy 65.137656 -459.970577)
			(xy 65.175602 -459.910186) (xy 65.220071 -459.854424) (xy 65.270504 -459.803991) (xy 65.326266 -459.759522)
			(xy 65.386657 -459.721576) (xy 65.450916 -459.690631) (xy 65.518236 -459.667074) (xy 65.587771 -459.651204)
			(xy 65.658645 -459.643218) (xy 65.694306 -459.642718) (xy 65.729967 -459.643218) (xy 65.800841 -459.651204)
			(xy 65.870376 -459.667074) (xy 65.937696 -459.690631) (xy 66.001955 -459.721576) (xy 66.062346 -459.759522)
			(xy 66.118108 -459.803991) (xy 66.168541 -459.854424) (xy 66.21301 -459.910186) (xy 66.250956 -459.970577)
			(xy 66.281901 -460.034836) (xy 66.305458 -460.102156) (xy 66.321328 -460.171691) (xy 66.329314 -460.242565)
			(xy 66.329314 -460.313887) (xy 66.329228 -460.314649) (xy 67.283576 -460.314649) (xy 67.283576 -460.243327)
			(xy 67.291562 -460.172453) (xy 67.307432 -460.102918) (xy 67.330989 -460.035598) (xy 67.361934 -459.971339)
			(xy 67.39988 -459.910948) (xy 67.444349 -459.855186) (xy 67.494782 -459.804753) (xy 67.550544 -459.760284)
			(xy 67.610935 -459.722338) (xy 67.675194 -459.691393) (xy 67.742514 -459.667836) (xy 67.812049 -459.651966)
			(xy 67.882923 -459.64398) (xy 67.918584 -459.64348) (xy 67.954245 -459.64398) (xy 68.025119 -459.651966)
			(xy 68.094654 -459.667836) (xy 68.161974 -459.691393) (xy 68.226233 -459.722338) (xy 68.286624 -459.760284)
			(xy 68.342386 -459.804753) (xy 68.392819 -459.855186) (xy 68.437288 -459.910948) (xy 68.475234 -459.971339)
			(xy 68.506179 -460.035598) (xy 68.529736 -460.102918) (xy 68.545606 -460.172453) (xy 68.553592 -460.243327)
			(xy 68.553592 -460.314649) (xy 68.545606 -460.385523) (xy 68.529736 -460.455058) (xy 68.506179 -460.522378)
			(xy 68.475234 -460.586637) (xy 68.437288 -460.647028) (xy 68.392819 -460.70279) (xy 68.342386 -460.753223)
			(xy 68.286624 -460.797692) (xy 68.226233 -460.835638) (xy 68.161974 -460.866583) (xy 68.094654 -460.89014)
			(xy 68.025119 -460.90601) (xy 67.954245 -460.913996) (xy 67.882923 -460.913996) (xy 67.812049 -460.90601)
			(xy 67.742514 -460.89014) (xy 67.675194 -460.866583) (xy 67.610935 -460.835638) (xy 67.550544 -460.797692)
			(xy 67.494782 -460.753223) (xy 67.444349 -460.70279) (xy 67.39988 -460.647028) (xy 67.361934 -460.586637)
			(xy 67.330989 -460.522378) (xy 67.307432 -460.455058) (xy 67.291562 -460.385523) (xy 67.283576 -460.314649)
			(xy 66.329228 -460.314649) (xy 66.321328 -460.384761) (xy 66.305458 -460.454296) (xy 66.281901 -460.521616)
			(xy 66.250956 -460.585875) (xy 66.21301 -460.646266) (xy 66.168541 -460.702028) (xy 66.118108 -460.752461)
			(xy 66.062346 -460.79693) (xy 66.001955 -460.834876) (xy 65.937696 -460.865821) (xy 65.870376 -460.889378)
			(xy 65.800841 -460.905248) (xy 65.729967 -460.913234) (xy 65.658645 -460.913234) (xy 65.587771 -460.905248)
			(xy 65.518236 -460.889378) (xy 65.450916 -460.865821) (xy 65.386657 -460.834876) (xy 65.326266 -460.79693)
			(xy 65.270504 -460.752461) (xy 65.220071 -460.702028) (xy 65.175602 -460.646266) (xy 65.137656 -460.585875)
			(xy 65.106711 -460.521616) (xy 65.083154 -460.454296) (xy 65.067284 -460.384761) (xy 65.059298 -460.313887)
			(xy 64.25388 -460.313887) (xy 64.245894 -460.384761) (xy 64.230024 -460.454296) (xy 64.206467 -460.521616)
			(xy 64.175522 -460.585875) (xy 64.137576 -460.646266) (xy 64.093107 -460.702028) (xy 64.042674 -460.752461)
			(xy 63.986912 -460.79693) (xy 63.926521 -460.834876) (xy 63.862262 -460.865821) (xy 63.794942 -460.889378)
			(xy 63.725407 -460.905248) (xy 63.654533 -460.913234) (xy 63.583211 -460.913234) (xy 63.512337 -460.905248)
			(xy 63.442802 -460.889378) (xy 63.375482 -460.865821) (xy 63.311223 -460.834876) (xy 63.250832 -460.79693)
			(xy 63.19507 -460.752461) (xy 63.144637 -460.702028) (xy 63.100168 -460.646266) (xy 63.062222 -460.585875)
			(xy 63.031277 -460.521616) (xy 63.00772 -460.454296) (xy 62.99185 -460.384761) (xy 62.983864 -460.313887)
			(xy 42.876306 -460.313887) (xy 44.642795 -462.080457) (xy 62.983864 -462.080457) (xy 62.983864 -462.009135)
			(xy 62.99185 -461.938261) (xy 63.00772 -461.868726) (xy 63.031277 -461.801406) (xy 63.062222 -461.737147)
			(xy 63.100168 -461.676756) (xy 63.144637 -461.620994) (xy 63.19507 -461.570561) (xy 63.250832 -461.526092)
			(xy 63.311223 -461.488146) (xy 63.375482 -461.457201) (xy 63.442802 -461.433644) (xy 63.512337 -461.417774)
			(xy 63.583211 -461.409788) (xy 63.618872 -461.409288) (xy 63.654533 -461.409788) (xy 63.725407 -461.417774)
			(xy 63.794942 -461.433644) (xy 63.862262 -461.457201) (xy 63.926521 -461.488146) (xy 63.986912 -461.526092)
			(xy 64.042674 -461.570561) (xy 64.093107 -461.620994) (xy 64.137576 -461.676756) (xy 64.175522 -461.737147)
			(xy 64.206467 -461.801406) (xy 64.230024 -461.868726) (xy 64.245894 -461.938261) (xy 64.25388 -462.009135)
			(xy 64.25388 -462.080457) (xy 65.059298 -462.080457) (xy 65.059298 -462.009135) (xy 65.067284 -461.938261)
			(xy 65.083154 -461.868726) (xy 65.106711 -461.801406) (xy 65.137656 -461.737147) (xy 65.175602 -461.676756)
			(xy 65.220071 -461.620994) (xy 65.270504 -461.570561) (xy 65.326266 -461.526092) (xy 65.386657 -461.488146)
			(xy 65.450916 -461.457201) (xy 65.518236 -461.433644) (xy 65.587771 -461.417774) (xy 65.658645 -461.409788)
			(xy 65.694306 -461.409288) (xy 65.729967 -461.409788) (xy 65.800841 -461.417774) (xy 65.870376 -461.433644)
			(xy 65.937696 -461.457201) (xy 66.001955 -461.488146) (xy 66.062346 -461.526092) (xy 66.118108 -461.570561)
			(xy 66.168541 -461.620994) (xy 66.21301 -461.676756) (xy 66.250956 -461.737147) (xy 66.281901 -461.801406)
			(xy 66.305458 -461.868726) (xy 66.321328 -461.938261) (xy 66.329314 -462.009135) (xy 66.329314 -462.080457)
			(xy 66.329228 -462.081219) (xy 67.283576 -462.081219) (xy 67.283576 -462.009897) (xy 67.291562 -461.939023)
			(xy 67.307432 -461.869488) (xy 67.330989 -461.802168) (xy 67.361934 -461.737909) (xy 67.39988 -461.677518)
			(xy 67.444349 -461.621756) (xy 67.494782 -461.571323) (xy 67.550544 -461.526854) (xy 67.610935 -461.488908)
			(xy 67.675194 -461.457963) (xy 67.742514 -461.434406) (xy 67.812049 -461.418536) (xy 67.882923 -461.41055)
			(xy 67.918584 -461.41005) (xy 67.954245 -461.41055) (xy 68.025119 -461.418536) (xy 68.094654 -461.434406)
			(xy 68.161974 -461.457963) (xy 68.226233 -461.488908) (xy 68.286624 -461.526854) (xy 68.342386 -461.571323)
			(xy 68.392819 -461.621756) (xy 68.437288 -461.677518) (xy 68.475234 -461.737909) (xy 68.506179 -461.802168)
			(xy 68.529736 -461.869488) (xy 68.545606 -461.939023) (xy 68.553592 -462.009897) (xy 68.553592 -462.081219)
			(xy 68.545606 -462.152093) (xy 68.529736 -462.221628) (xy 68.506179 -462.288948) (xy 68.475234 -462.353207)
			(xy 68.437288 -462.413598) (xy 68.392819 -462.46936) (xy 68.342386 -462.519793) (xy 68.286624 -462.564262)
			(xy 68.226233 -462.602208) (xy 68.161974 -462.633153) (xy 68.094654 -462.65671) (xy 68.025119 -462.67258)
			(xy 67.954245 -462.680566) (xy 67.882923 -462.680566) (xy 67.812049 -462.67258) (xy 67.742514 -462.65671)
			(xy 67.675194 -462.633153) (xy 67.610935 -462.602208) (xy 67.550544 -462.564262) (xy 67.494782 -462.519793)
			(xy 67.444349 -462.46936) (xy 67.39988 -462.413598) (xy 67.361934 -462.353207) (xy 67.330989 -462.288948)
			(xy 67.307432 -462.221628) (xy 67.291562 -462.152093) (xy 67.283576 -462.081219) (xy 66.329228 -462.081219)
			(xy 66.321328 -462.151331) (xy 66.305458 -462.220866) (xy 66.281901 -462.288186) (xy 66.250956 -462.352445)
			(xy 66.21301 -462.412836) (xy 66.168541 -462.468598) (xy 66.118108 -462.519031) (xy 66.062346 -462.5635)
			(xy 66.001955 -462.601446) (xy 65.937696 -462.632391) (xy 65.870376 -462.655948) (xy 65.800841 -462.671818)
			(xy 65.729967 -462.679804) (xy 65.658645 -462.679804) (xy 65.587771 -462.671818) (xy 65.518236 -462.655948)
			(xy 65.450916 -462.632391) (xy 65.386657 -462.601446) (xy 65.326266 -462.5635) (xy 65.270504 -462.519031)
			(xy 65.220071 -462.468598) (xy 65.175602 -462.412836) (xy 65.137656 -462.352445) (xy 65.106711 -462.288186)
			(xy 65.083154 -462.220866) (xy 65.067284 -462.151331) (xy 65.059298 -462.080457) (xy 64.25388 -462.080457)
			(xy 64.245894 -462.151331) (xy 64.230024 -462.220866) (xy 64.206467 -462.288186) (xy 64.175522 -462.352445)
			(xy 64.137576 -462.412836) (xy 64.093107 -462.468598) (xy 64.042674 -462.519031) (xy 63.986912 -462.5635)
			(xy 63.926521 -462.601446) (xy 63.862262 -462.632391) (xy 63.794942 -462.655948) (xy 63.725407 -462.671818)
			(xy 63.654533 -462.679804) (xy 63.583211 -462.679804) (xy 63.512337 -462.671818) (xy 63.442802 -462.655948)
			(xy 63.375482 -462.632391) (xy 63.311223 -462.601446) (xy 63.250832 -462.5635) (xy 63.19507 -462.519031)
			(xy 63.144637 -462.468598) (xy 63.100168 -462.412836) (xy 63.062222 -462.352445) (xy 63.031277 -462.288186)
			(xy 63.00772 -462.220866) (xy 62.99185 -462.151331) (xy 62.983864 -462.080457) (xy 44.642795 -462.080457)
			(xy 45.702503 -463.140213) (xy 51.32323 -463.140213) (xy 51.32323 -463.059103) (xy 51.33118 -462.978384)
			(xy 51.347003 -462.898833) (xy 51.370548 -462.821217) (xy 51.401587 -462.746281) (xy 51.439822 -462.674749)
			(xy 51.484884 -462.607309) (xy 51.536339 -462.54461) (xy 51.593692 -462.487257) (xy 51.656391 -462.435802)
			(xy 51.723831 -462.39074) (xy 51.795363 -462.352505) (xy 51.870299 -462.321466) (xy 51.947915 -462.297921)
			(xy 52.027466 -462.282098) (xy 52.108185 -462.274148) (xy 52.14874 -462.27365) (xy 52.189295 -462.274148)
			(xy 52.270014 -462.282098) (xy 52.349565 -462.297921) (xy 52.427181 -462.321466) (xy 52.502117 -462.352505)
			(xy 52.573649 -462.39074) (xy 52.641089 -462.435802) (xy 52.703788 -462.487257) (xy 52.761141 -462.54461)
			(xy 52.812596 -462.607309) (xy 52.857658 -462.674749) (xy 52.895893 -462.746281) (xy 52.926932 -462.821217)
			(xy 52.950477 -462.898833) (xy 52.9663 -462.978384) (xy 52.97425 -463.059103) (xy 52.97425 -463.140213)
			(xy 52.9663 -463.220932) (xy 52.950477 -463.300483) (xy 52.926932 -463.378099) (xy 52.895893 -463.453035)
			(xy 52.857658 -463.524567) (xy 52.812596 -463.592007) (xy 52.761141 -463.654706) (xy 52.703788 -463.712059)
			(xy 52.641089 -463.763514) (xy 52.573649 -463.808576) (xy 52.502117 -463.846811) (xy 52.427181 -463.87785)
			(xy 52.3697 -463.895287) (xy 62.938144 -463.895287) (xy 62.938144 -463.823965) (xy 62.94613 -463.753091)
			(xy 62.962 -463.683556) (xy 62.985557 -463.616236) (xy 63.016502 -463.551977) (xy 63.054448 -463.491586)
			(xy 63.098917 -463.435824) (xy 63.14935 -463.385391) (xy 63.205112 -463.340922) (xy 63.265503 -463.302976)
			(xy 63.329762 -463.272031) (xy 63.397082 -463.248474) (xy 63.466617 -463.232604) (xy 63.537491 -463.224618)
			(xy 63.573152 -463.224118) (xy 63.608813 -463.224618) (xy 63.679687 -463.232604) (xy 63.749222 -463.248474)
			(xy 63.816542 -463.272031) (xy 63.880801 -463.302976) (xy 63.941192 -463.340922) (xy 63.996954 -463.385391)
			(xy 64.047387 -463.435824) (xy 64.091856 -463.491586) (xy 64.129802 -463.551977) (xy 64.160747 -463.616236)
			(xy 64.184304 -463.683556) (xy 64.200174 -463.753091) (xy 64.20816 -463.823965) (xy 64.20816 -463.895287)
			(xy 65.013578 -463.895287) (xy 65.013578 -463.823965) (xy 65.021564 -463.753091) (xy 65.037434 -463.683556)
			(xy 65.060991 -463.616236) (xy 65.091936 -463.551977) (xy 65.129882 -463.491586) (xy 65.174351 -463.435824)
			(xy 65.224784 -463.385391) (xy 65.280546 -463.340922) (xy 65.340937 -463.302976) (xy 65.405196 -463.272031)
			(xy 65.472516 -463.248474) (xy 65.542051 -463.232604) (xy 65.612925 -463.224618) (xy 65.648586 -463.224118)
			(xy 65.684247 -463.224618) (xy 65.755121 -463.232604) (xy 65.824656 -463.248474) (xy 65.891976 -463.272031)
			(xy 65.956235 -463.302976) (xy 66.016626 -463.340922) (xy 66.072388 -463.385391) (xy 66.122821 -463.435824)
			(xy 66.16729 -463.491586) (xy 66.205236 -463.551977) (xy 66.236181 -463.616236) (xy 66.259738 -463.683556)
			(xy 66.275608 -463.753091) (xy 66.283594 -463.823965) (xy 66.283594 -463.895287) (xy 66.283508 -463.896049)
			(xy 67.19239 -463.896049) (xy 67.19239 -463.824727) (xy 67.200376 -463.753853) (xy 67.216246 -463.684318)
			(xy 67.239803 -463.616998) (xy 67.270748 -463.552739) (xy 67.308694 -463.492348) (xy 67.353163 -463.436586)
			(xy 67.403596 -463.386153) (xy 67.459358 -463.341684) (xy 67.519749 -463.303738) (xy 67.584008 -463.272793)
			(xy 67.651328 -463.249236) (xy 67.720863 -463.233366) (xy 67.791737 -463.22538) (xy 67.827398 -463.22488)
			(xy 67.863059 -463.22538) (xy 67.933933 -463.233366) (xy 68.003468 -463.249236) (xy 68.070788 -463.272793)
			(xy 68.135047 -463.303738) (xy 68.195438 -463.341684) (xy 68.2512 -463.386153) (xy 68.301633 -463.436586)
			(xy 68.346102 -463.492348) (xy 68.384048 -463.552739) (xy 68.414993 -463.616998) (xy 68.43855 -463.684318)
			(xy 68.45442 -463.753853) (xy 68.462406 -463.824727) (xy 68.462406 -463.896049) (xy 68.45442 -463.966923)
			(xy 68.43855 -464.036458) (xy 68.414993 -464.103778) (xy 68.384048 -464.168037) (xy 68.346102 -464.228428)
			(xy 68.301633 -464.28419) (xy 68.2512 -464.334623) (xy 68.195438 -464.379092) (xy 68.135047 -464.417038)
			(xy 68.070788 -464.447983) (xy 68.003468 -464.47154) (xy 67.933933 -464.48741) (xy 67.863059 -464.495396)
			(xy 67.791737 -464.495396) (xy 67.720863 -464.48741) (xy 67.651328 -464.47154) (xy 67.584008 -464.447983)
			(xy 67.519749 -464.417038) (xy 67.459358 -464.379092) (xy 67.403596 -464.334623) (xy 67.353163 -464.28419)
			(xy 67.308694 -464.228428) (xy 67.270748 -464.168037) (xy 67.239803 -464.103778) (xy 67.216246 -464.036458)
			(xy 67.200376 -463.966923) (xy 67.19239 -463.896049) (xy 66.283508 -463.896049) (xy 66.275608 -463.966161)
			(xy 66.259738 -464.035696) (xy 66.236181 -464.103016) (xy 66.205236 -464.167275) (xy 66.16729 -464.227666)
			(xy 66.122821 -464.283428) (xy 66.072388 -464.333861) (xy 66.016626 -464.37833) (xy 65.956235 -464.416276)
			(xy 65.891976 -464.447221) (xy 65.824656 -464.470778) (xy 65.755121 -464.486648) (xy 65.684247 -464.494634)
			(xy 65.612925 -464.494634) (xy 65.542051 -464.486648) (xy 65.472516 -464.470778) (xy 65.405196 -464.447221)
			(xy 65.340937 -464.416276) (xy 65.280546 -464.37833) (xy 65.224784 -464.333861) (xy 65.174351 -464.283428)
			(xy 65.129882 -464.227666) (xy 65.091936 -464.167275) (xy 65.060991 -464.103016) (xy 65.037434 -464.035696)
			(xy 65.021564 -463.966161) (xy 65.013578 -463.895287) (xy 64.20816 -463.895287) (xy 64.200174 -463.966161)
			(xy 64.184304 -464.035696) (xy 64.160747 -464.103016) (xy 64.129802 -464.167275) (xy 64.091856 -464.227666)
			(xy 64.047387 -464.283428) (xy 63.996954 -464.333861) (xy 63.941192 -464.37833) (xy 63.880801 -464.416276)
			(xy 63.816542 -464.447221) (xy 63.749222 -464.470778) (xy 63.679687 -464.486648) (xy 63.608813 -464.494634)
			(xy 63.537491 -464.494634) (xy 63.466617 -464.486648) (xy 63.397082 -464.470778) (xy 63.329762 -464.447221)
			(xy 63.265503 -464.416276) (xy 63.205112 -464.37833) (xy 63.14935 -464.333861) (xy 63.098917 -464.283428)
			(xy 63.054448 -464.227666) (xy 63.016502 -464.167275) (xy 62.985557 -464.103016) (xy 62.962 -464.035696)
			(xy 62.94613 -463.966161) (xy 62.938144 -463.895287) (xy 52.3697 -463.895287) (xy 52.349565 -463.901395)
			(xy 52.270014 -463.917218) (xy 52.189295 -463.925168) (xy 52.108185 -463.925168) (xy 52.027466 -463.917218)
			(xy 51.947915 -463.901395) (xy 51.870299 -463.87785) (xy 51.795363 -463.846811) (xy 51.723831 -463.808576)
			(xy 51.656391 -463.763514) (xy 51.593692 -463.712059) (xy 51.536339 -463.654706) (xy 51.484884 -463.592007)
			(xy 51.439822 -463.524567) (xy 51.401587 -463.453035) (xy 51.370548 -463.378099) (xy 51.347003 -463.300483)
			(xy 51.33118 -463.220932) (xy 51.32323 -463.140213) (xy 45.702503 -463.140213) (xy 47.119767 -464.557542)
			(xy 86.877655 -464.557542) (xy 86.879665 -464.366859) (xy 86.889712 -464.17643) (xy 86.907778 -463.986594)
			(xy 86.933831 -463.797688) (xy 86.967824 -463.610049) (xy 87.009697 -463.424009) (xy 87.059376 -463.2399)
			(xy 87.116772 -463.058049) (xy 87.181783 -462.878779) (xy 87.254294 -462.702409) (xy 87.334175 -462.529253)
			(xy 87.421285 -462.359618) (xy 87.515469 -462.193806) (xy 87.61656 -462.032112) (xy 87.724376 -461.874824)
			(xy 87.838728 -461.722221) (xy 87.959411 -461.574573) (xy 88.086212 -461.432145) (xy 88.218903 -461.295189)
			(xy 88.357251 -461.163948) (xy 88.501008 -461.038656) (xy 88.649919 -460.919536) (xy 88.80372 -460.8068)
			(xy 88.962136 -460.700647) (xy 89.124887 -460.601267) (xy 89.291682 -460.508837) (xy 89.462226 -460.42352)
			(xy 89.636214 -460.345468) (xy 89.813339 -460.274821) (xy 89.993284 -460.211703) (xy 90.17573 -460.156227)
			(xy 90.360353 -460.108492) (xy 90.546823 -460.068582) (xy 90.734811 -460.036569) (xy 90.923981 -460.012509)
			(xy 91.113997 -459.996446) (xy 91.304521 -459.988407) (xy 91.399868 -459.987904) (xy 91.495215 -459.988407)
			(xy 91.685739 -459.996446) (xy 91.875755 -460.012509) (xy 92.064925 -460.036569) (xy 92.252913 -460.068582)
			(xy 92.439383 -460.108492) (xy 92.624006 -460.156227) (xy 92.806452 -460.211703) (xy 92.986397 -460.274821)
			(xy 93.163522 -460.345468) (xy 93.33751 -460.42352) (xy 93.508054 -460.508837) (xy 93.674849 -460.601267)
			(xy 93.8376 -460.700647) (xy 93.996016 -460.8068) (xy 94.149817 -460.919536) (xy 94.298728 -461.038656)
			(xy 94.442485 -461.163948) (xy 94.580833 -461.295189) (xy 94.713524 -461.432145) (xy 94.840325 -461.574573)
			(xy 94.961008 -461.722221) (xy 95.07536 -461.874824) (xy 95.183176 -462.032112) (xy 95.284267 -462.193806)
			(xy 95.378451 -462.359618) (xy 95.465561 -462.529253) (xy 95.545442 -462.702409) (xy 95.617953 -462.878779)
			(xy 95.682964 -463.058049) (xy 95.74036 -463.2399) (xy 95.790039 -463.424009) (xy 95.831912 -463.610049)
			(xy 95.865905 -463.797688) (xy 95.891958 -463.986594) (xy 95.910024 -464.17643) (xy 95.920071 -464.366859)
			(xy 95.922081 -464.557542) (xy 95.916051 -464.748141) (xy 95.901992 -464.938315) (xy 95.879927 -465.127728)
			(xy 95.849898 -465.316043) (xy 95.811956 -465.502924) (xy 95.76617 -465.68804) (xy 95.712621 -465.87106)
			(xy 95.651403 -466.051661) (xy 95.582627 -466.22952) (xy 95.506414 -466.404322) (xy 95.4229 -466.575756)
			(xy 95.332233 -466.743516) (xy 95.234574 -466.907305) (xy 95.130097 -467.066832) (xy 95.018988 -467.221813)
			(xy 94.901445 -467.371971) (xy 94.777675 -467.517041) (xy 94.6479 -467.656765) (xy 94.512351 -467.790893)
			(xy 94.371267 -467.919187) (xy 94.2249 -468.041421) (xy 94.073511 -468.157375) (xy 93.917368 -468.266844)
			(xy 93.756749 -468.369633) (xy 93.591939 -468.465559) (xy 93.423232 -468.554453) (xy 93.250927 -468.636155)
			(xy 93.075332 -468.710521) (xy 92.896757 -468.777419) (xy 92.715521 -468.836729) (xy 92.531946 -468.888346)
			(xy 92.346358 -468.932178) (xy 92.159088 -468.968147) (xy 91.970467 -468.99619) (xy 91.780832 -469.016256)
			(xy 91.590519 -469.02831) (xy 91.399868 -469.032331) (xy 91.209217 -469.02831) (xy 91.018904 -469.016256)
			(xy 90.829269 -468.99619) (xy 90.640648 -468.968147) (xy 90.453378 -468.932178) (xy 90.26779 -468.888346)
			(xy 90.084215 -468.836729) (xy 89.902979 -468.777419) (xy 89.724404 -468.710521) (xy 89.548809 -468.636155)
			(xy 89.376504 -468.554453) (xy 89.207797 -468.465559) (xy 89.042987 -468.369633) (xy 88.882368 -468.266844)
			(xy 88.726225 -468.157375) (xy 88.574836 -468.041421) (xy 88.428469 -467.919187) (xy 88.287385 -467.790893)
			(xy 88.151836 -467.656765) (xy 88.022061 -467.517041) (xy 87.898291 -467.371971) (xy 87.780748 -467.221813)
			(xy 87.669639 -467.066832) (xy 87.565162 -466.907305) (xy 87.467503 -466.743516) (xy 87.376836 -466.575756)
			(xy 87.293322 -466.404322) (xy 87.217109 -466.22952) (xy 87.148333 -466.051661) (xy 87.087115 -465.87106)
			(xy 87.033566 -465.68804) (xy 86.98778 -465.502924) (xy 86.949838 -465.316043) (xy 86.919809 -465.127728)
			(xy 86.897744 -464.938315) (xy 86.883685 -464.748141) (xy 86.877655 -464.557542) (xy 47.119767 -464.557542)
			(xy 48.183292 -465.621116) (xy 48.19542 -465.632491) (xy 48.224221 -465.649085) (xy 48.234947 -465.651951)
			(xy 62.938144 -465.651951) (xy 62.938144 -465.580629) (xy 62.94613 -465.509755) (xy 62.962 -465.44022)
			(xy 62.985557 -465.3729) (xy 63.016502 -465.308641) (xy 63.054448 -465.24825) (xy 63.098917 -465.192488)
			(xy 63.14935 -465.142055) (xy 63.205112 -465.097586) (xy 63.265503 -465.05964) (xy 63.329762 -465.028695)
			(xy 63.397082 -465.005138) (xy 63.466617 -464.989268) (xy 63.537491 -464.981282) (xy 63.573152 -464.980782)
			(xy 63.608813 -464.981282) (xy 63.679687 -464.989268) (xy 63.749222 -465.005138) (xy 63.816542 -465.028695)
			(xy 63.880801 -465.05964) (xy 63.941192 -465.097586) (xy 63.996954 -465.142055) (xy 64.047387 -465.192488)
			(xy 64.091856 -465.24825) (xy 64.129802 -465.308641) (xy 64.160747 -465.3729) (xy 64.184304 -465.44022)
			(xy 64.200174 -465.509755) (xy 64.20816 -465.580629) (xy 64.20816 -465.651951) (xy 65.013578 -465.651951)
			(xy 65.013578 -465.580629) (xy 65.021564 -465.509755) (xy 65.037434 -465.44022) (xy 65.060991 -465.3729)
			(xy 65.091936 -465.308641) (xy 65.129882 -465.24825) (xy 65.174351 -465.192488) (xy 65.224784 -465.142055)
			(xy 65.280546 -465.097586) (xy 65.340937 -465.05964) (xy 65.405196 -465.028695) (xy 65.472516 -465.005138)
			(xy 65.542051 -464.989268) (xy 65.612925 -464.981282) (xy 65.648586 -464.980782) (xy 65.684247 -464.981282)
			(xy 65.755121 -464.989268) (xy 65.824656 -465.005138) (xy 65.891976 -465.028695) (xy 65.956235 -465.05964)
			(xy 66.016626 -465.097586) (xy 66.072388 -465.142055) (xy 66.122821 -465.192488) (xy 66.16729 -465.24825)
			(xy 66.205236 -465.308641) (xy 66.236181 -465.3729) (xy 66.259738 -465.44022) (xy 66.275608 -465.509755)
			(xy 66.283594 -465.580629) (xy 66.283594 -465.651951) (xy 66.283508 -465.652713) (xy 67.19239 -465.652713)
			(xy 67.19239 -465.581391) (xy 67.200376 -465.510517) (xy 67.216246 -465.440982) (xy 67.239803 -465.373662)
			(xy 67.270748 -465.309403) (xy 67.308694 -465.249012) (xy 67.353163 -465.19325) (xy 67.403596 -465.142817)
			(xy 67.459358 -465.098348) (xy 67.519749 -465.060402) (xy 67.584008 -465.029457) (xy 67.651328 -465.0059)
			(xy 67.720863 -464.99003) (xy 67.791737 -464.982044) (xy 67.827398 -464.981544) (xy 67.863059 -464.982044)
			(xy 67.933933 -464.99003) (xy 68.003468 -465.0059) (xy 68.070788 -465.029457) (xy 68.135047 -465.060402)
			(xy 68.195438 -465.098348) (xy 68.2512 -465.142817) (xy 68.301633 -465.19325) (xy 68.346102 -465.249012)
			(xy 68.384048 -465.309403) (xy 68.414993 -465.373662) (xy 68.43855 -465.440982) (xy 68.45442 -465.510517)
			(xy 68.462406 -465.581391) (xy 68.462406 -465.652713) (xy 68.45442 -465.723587) (xy 68.43855 -465.793122)
			(xy 68.414993 -465.860442) (xy 68.384048 -465.924701) (xy 68.346102 -465.985092) (xy 68.301633 -466.040854)
			(xy 68.2512 -466.091287) (xy 68.195438 -466.135756) (xy 68.135047 -466.173702) (xy 68.070788 -466.204647)
			(xy 68.003468 -466.228204) (xy 67.933933 -466.244074) (xy 67.863059 -466.25206) (xy 67.791737 -466.25206)
			(xy 67.720863 -466.244074) (xy 67.651328 -466.228204) (xy 67.584008 -466.204647) (xy 67.519749 -466.173702)
			(xy 67.459358 -466.135756) (xy 67.403596 -466.091287) (xy 67.353163 -466.040854) (xy 67.308694 -465.985092)
			(xy 67.270748 -465.924701) (xy 67.239803 -465.860442) (xy 67.216246 -465.793122) (xy 67.200376 -465.723587)
			(xy 67.19239 -465.652713) (xy 66.283508 -465.652713) (xy 66.275608 -465.722825) (xy 66.259738 -465.79236)
			(xy 66.236181 -465.85968) (xy 66.205236 -465.923939) (xy 66.16729 -465.98433) (xy 66.122821 -466.040092)
			(xy 66.072388 -466.090525) (xy 66.016626 -466.134994) (xy 65.956235 -466.17294) (xy 65.891976 -466.203885)
			(xy 65.824656 -466.227442) (xy 65.755121 -466.243312) (xy 65.684247 -466.251298) (xy 65.612925 -466.251298)
			(xy 65.542051 -466.243312) (xy 65.472516 -466.227442) (xy 65.405196 -466.203885) (xy 65.340937 -466.17294)
			(xy 65.280546 -466.134994) (xy 65.224784 -466.090525) (xy 65.174351 -466.040092) (xy 65.129882 -465.98433)
			(xy 65.091936 -465.923939) (xy 65.060991 -465.85968) (xy 65.037434 -465.79236) (xy 65.021564 -465.722825)
			(xy 65.013578 -465.651951) (xy 64.20816 -465.651951) (xy 64.200174 -465.722825) (xy 64.184304 -465.79236)
			(xy 64.160747 -465.85968) (xy 64.129802 -465.923939) (xy 64.091856 -465.98433) (xy 64.047387 -466.040092)
			(xy 63.996954 -466.090525) (xy 63.941192 -466.134994) (xy 63.880801 -466.17294) (xy 63.816542 -466.203885)
			(xy 63.749222 -466.227442) (xy 63.679687 -466.243312) (xy 63.608813 -466.251298) (xy 63.537491 -466.251298)
			(xy 63.466617 -466.243312) (xy 63.397082 -466.227442) (xy 63.329762 -466.203885) (xy 63.265503 -466.17294)
			(xy 63.205112 -466.134994) (xy 63.14935 -466.090525) (xy 63.098917 -466.040092) (xy 63.054448 -465.98433)
			(xy 63.016502 -465.923939) (xy 62.985557 -465.85968) (xy 62.962 -465.79236) (xy 62.94613 -465.722825)
			(xy 62.938144 -465.651951) (xy 48.234947 -465.651951) (xy 48.256334 -465.657666) (xy 48.272954 -465.6582)
			(xy 59.412886 -465.6582) (xy 61.173278 -467.418521) (xy 62.938144 -467.418521) (xy 62.938144 -467.347199)
			(xy 62.94613 -467.276325) (xy 62.962 -467.20679) (xy 62.985557 -467.13947) (xy 63.016502 -467.075211)
			(xy 63.054448 -467.01482) (xy 63.098917 -466.959058) (xy 63.14935 -466.908625) (xy 63.205112 -466.864156)
			(xy 63.265503 -466.82621) (xy 63.329762 -466.795265) (xy 63.397082 -466.771708) (xy 63.466617 -466.755838)
			(xy 63.537491 -466.747852) (xy 63.573152 -466.747352) (xy 63.608813 -466.747852) (xy 63.679687 -466.755838)
			(xy 63.749222 -466.771708) (xy 63.816542 -466.795265) (xy 63.880801 -466.82621) (xy 63.941192 -466.864156)
			(xy 63.996954 -466.908625) (xy 64.047387 -466.959058) (xy 64.091856 -467.01482) (xy 64.129802 -467.075211)
			(xy 64.160747 -467.13947) (xy 64.184304 -467.20679) (xy 64.200174 -467.276325) (xy 64.20816 -467.347199)
			(xy 64.20816 -467.418521) (xy 65.013578 -467.418521) (xy 65.013578 -467.347199) (xy 65.021564 -467.276325)
			(xy 65.037434 -467.20679) (xy 65.060991 -467.13947) (xy 65.091936 -467.075211) (xy 65.129882 -467.01482)
			(xy 65.174351 -466.959058) (xy 65.224784 -466.908625) (xy 65.280546 -466.864156) (xy 65.340937 -466.82621)
			(xy 65.405196 -466.795265) (xy 65.472516 -466.771708) (xy 65.542051 -466.755838) (xy 65.612925 -466.747852)
			(xy 65.648586 -466.747352) (xy 65.684247 -466.747852) (xy 65.755121 -466.755838) (xy 65.824656 -466.771708)
			(xy 65.891976 -466.795265) (xy 65.956235 -466.82621) (xy 66.016626 -466.864156) (xy 66.072388 -466.908625)
			(xy 66.122821 -466.959058) (xy 66.16729 -467.01482) (xy 66.205236 -467.075211) (xy 66.236181 -467.13947)
			(xy 66.259738 -467.20679) (xy 66.275608 -467.276325) (xy 66.283594 -467.347199) (xy 66.283594 -467.418521)
			(xy 66.283508 -467.419283) (xy 67.19239 -467.419283) (xy 67.19239 -467.347961) (xy 67.200376 -467.277087)
			(xy 67.216246 -467.207552) (xy 67.239803 -467.140232) (xy 67.270748 -467.075973) (xy 67.308694 -467.015582)
			(xy 67.353163 -466.95982) (xy 67.403596 -466.909387) (xy 67.459358 -466.864918) (xy 67.519749 -466.826972)
			(xy 67.584008 -466.796027) (xy 67.651328 -466.77247) (xy 67.720863 -466.7566) (xy 67.791737 -466.748614)
			(xy 67.827398 -466.748114) (xy 67.863059 -466.748614) (xy 67.933933 -466.7566) (xy 68.003468 -466.77247)
			(xy 68.070788 -466.796027) (xy 68.135047 -466.826972) (xy 68.195438 -466.864918) (xy 68.2512 -466.909387)
			(xy 68.301633 -466.95982) (xy 68.346102 -467.015582) (xy 68.384048 -467.075973) (xy 68.414993 -467.140232)
			(xy 68.43855 -467.207552) (xy 68.45442 -467.277087) (xy 68.462406 -467.347961) (xy 68.462406 -467.419283)
			(xy 68.45442 -467.490157) (xy 68.43855 -467.559692) (xy 68.414993 -467.627012) (xy 68.384048 -467.691271)
			(xy 68.346102 -467.751662) (xy 68.301633 -467.807424) (xy 68.2512 -467.857857) (xy 68.195438 -467.902326)
			(xy 68.135047 -467.940272) (xy 68.070788 -467.971217) (xy 68.003468 -467.994774) (xy 67.933933 -468.010644)
			(xy 67.863059 -468.01863) (xy 67.791737 -468.01863) (xy 67.720863 -468.010644) (xy 67.651328 -467.994774)
			(xy 67.584008 -467.971217) (xy 67.519749 -467.940272) (xy 67.459358 -467.902326) (xy 67.403596 -467.857857)
			(xy 67.353163 -467.807424) (xy 67.308694 -467.751662) (xy 67.270748 -467.691271) (xy 67.239803 -467.627012)
			(xy 67.216246 -467.559692) (xy 67.200376 -467.490157) (xy 67.19239 -467.419283) (xy 66.283508 -467.419283)
			(xy 66.275608 -467.489395) (xy 66.259738 -467.55893) (xy 66.236181 -467.62625) (xy 66.205236 -467.690509)
			(xy 66.16729 -467.7509) (xy 66.122821 -467.806662) (xy 66.072388 -467.857095) (xy 66.016626 -467.901564)
			(xy 65.956235 -467.93951) (xy 65.891976 -467.970455) (xy 65.824656 -467.994012) (xy 65.755121 -468.009882)
			(xy 65.684247 -468.017868) (xy 65.612925 -468.017868) (xy 65.542051 -468.009882) (xy 65.472516 -467.994012)
			(xy 65.405196 -467.970455) (xy 65.340937 -467.93951) (xy 65.280546 -467.901564) (xy 65.224784 -467.857095)
			(xy 65.174351 -467.806662) (xy 65.129882 -467.7509) (xy 65.091936 -467.690509) (xy 65.060991 -467.62625)
			(xy 65.037434 -467.55893) (xy 65.021564 -467.489395) (xy 65.013578 -467.418521) (xy 64.20816 -467.418521)
			(xy 64.200174 -467.489395) (xy 64.184304 -467.55893) (xy 64.160747 -467.62625) (xy 64.129802 -467.690509)
			(xy 64.091856 -467.7509) (xy 64.047387 -467.806662) (xy 63.996954 -467.857095) (xy 63.941192 -467.901564)
			(xy 63.880801 -467.93951) (xy 63.816542 -467.970455) (xy 63.749222 -467.994012) (xy 63.679687 -468.009882)
			(xy 63.608813 -468.017868) (xy 63.537491 -468.017868) (xy 63.466617 -468.009882) (xy 63.397082 -467.994012)
			(xy 63.329762 -467.970455) (xy 63.265503 -467.93951) (xy 63.205112 -467.901564) (xy 63.14935 -467.857095)
			(xy 63.098917 -467.806662) (xy 63.054448 -467.7509) (xy 63.016502 -467.690509) (xy 62.985557 -467.62625)
			(xy 62.962 -467.55893) (xy 62.94613 -467.489395) (xy 62.938144 -467.418521) (xy 61.173278 -467.418521)
			(xy 65.678304 -471.923364) (xy 70.676008 -471.923364) (xy 70.83933 -471.760042) (xy 70.862063 -471.73804)
			(xy 70.912255 -471.699527) (xy 70.967044 -471.667894) (xy 71.025494 -471.643683) (xy 71.086603 -471.627309)
			(xy 71.149327 -471.619051) (xy 71.212593 -471.619051) (xy 71.275317 -471.627309) (xy 71.336426 -471.643683)
			(xy 71.394876 -471.667894) (xy 71.449665 -471.699527) (xy 71.499857 -471.73804) (xy 71.544592 -471.782775)
			(xy 71.583105 -471.832967) (xy 71.614738 -471.887756) (xy 71.638949 -471.946206) (xy 71.655323 -472.007315)
			(xy 71.663581 -472.070039) (xy 71.663581 -472.133305) (xy 71.655323 -472.196029) (xy 71.638949 -472.257138)
			(xy 71.614738 -472.315588) (xy 71.583105 -472.370377) (xy 71.544592 -472.420569) (xy 71.52259 -472.443302)
			(xy 71.171562 -472.794076) (xy 71.160107 -472.806214) (xy 71.143394 -472.83509) (xy 71.134741 -472.867312)
			(xy 71.134739 -472.900676) (xy 71.14339 -472.932899) (xy 71.1601 -472.961777) (xy 71.171562 -472.973908)
			(xy 71.455534 -473.25788) (xy 71.477536 -473.280613) (xy 71.516049 -473.330805) (xy 71.547682 -473.385594)
			(xy 71.571893 -473.444044) (xy 71.588267 -473.505153) (xy 71.596525 -473.567877) (xy 71.596525 -473.585558)
			(xy 73.942193 -473.585558) (xy 73.948293 -473.530121) (xy 73.962399 -473.476164) (xy 73.984211 -473.424835)
			(xy 74.013265 -473.377229) (xy 74.04894 -473.334361) (xy 74.090477 -473.297144) (xy 74.13699 -473.266371)
			(xy 74.187487 -473.242699) (xy 74.240894 -473.226631) (xy 74.29607 -473.218511) (xy 74.323956 -473.218002)
			(xy 74.351842 -473.218511) (xy 74.407018 -473.226631) (xy 74.460425 -473.242699) (xy 74.510922 -473.266371)
			(xy 74.557435 -473.297144) (xy 74.598972 -473.334361) (xy 74.634647 -473.377229) (xy 74.663701 -473.424835)
			(xy 74.685513 -473.476164) (xy 74.699619 -473.530121) (xy 74.705719 -473.585558) (xy 74.703682 -473.641292)
			(xy 74.693552 -473.696135) (xy 74.675545 -473.748919) (xy 74.650044 -473.798519) (xy 74.617593 -473.843877)
			(xy 74.578884 -473.884026) (xy 74.534741 -473.918112) (xy 74.486106 -473.945408) (xy 74.434015 -473.965331)
			(xy 74.379578 -473.977457) (xy 74.323956 -473.981528) (xy 74.268334 -473.977457) (xy 74.213897 -473.965331)
			(xy 74.161806 -473.945408) (xy 74.113171 -473.918112) (xy 74.069028 -473.884026) (xy 74.030319 -473.843877)
			(xy 73.997868 -473.798519) (xy 73.972367 -473.748919) (xy 73.95436 -473.696135) (xy 73.94423 -473.641292)
			(xy 73.942193 -473.585558) (xy 71.596525 -473.585558) (xy 71.596525 -473.631143) (xy 71.588267 -473.693867)
			(xy 71.571893 -473.754976) (xy 71.547682 -473.813426) (xy 71.516049 -473.868215) (xy 71.477536 -473.918407)
			(xy 71.432801 -473.963142) (xy 71.382609 -474.001655) (xy 71.32782 -474.033288) (xy 71.26937 -474.057499)
			(xy 71.208261 -474.073873) (xy 71.145537 -474.082131) (xy 71.082271 -474.082131) (xy 71.019547 -474.073873)
			(xy 70.958438 -474.057499) (xy 70.899988 -474.033288) (xy 70.845199 -474.001655) (xy 70.795007 -473.963142)
			(xy 70.772274 -473.94114) (xy 70.58787 -473.756736) (xy 64.91859 -473.756736) (xy 58.690256 -467.528148)
			(xy 58.6781 -467.516805) (xy 58.649313 -467.500199) (xy 58.617211 -467.491605) (xy 58.600594 -467.491064)
			(xy 46.970442 -467.491064) (xy 43.53433 -464.054952) (xy 41.74109 -464.054952) (xy 41.717553 -464.055448)
			(xy 41.671277 -464.064082) (xy 41.627383 -464.08109) (xy 41.587373 -464.105891) (xy 41.552613 -464.137636)
			(xy 41.524294 -464.175239) (xy 41.503384 -464.217415) (xy 41.490599 -464.262719) (xy 41.486375 -464.309603)
			(xy 41.488106 -464.333082) (xy 41.490312 -464.361839) (xy 41.487068 -464.41942) (xy 41.475191 -464.475856)
			(xy 41.454953 -464.529861) (xy 41.426816 -464.580204) (xy 41.39142 -464.625736) (xy 41.349572 -464.665421)
			(xy 41.302227 -464.698354) (xy 41.250464 -464.723783) (xy 41.195462 -464.741129) (xy 41.16705 -464.746086)
			(xy 41.145863 -464.749832) (xy 41.105075 -464.763516) (xy 41.067176 -464.783878) (xy 41.033251 -464.810335)
			(xy 41.004268 -464.84213) (xy 40.981058 -464.878355) (xy 40.964284 -464.917972) (xy 40.954425 -464.95985)
			(xy 40.951763 -465.002789) (xy 40.956376 -465.045564) (xy 40.961818 -465.06638) (xy 40.968935 -465.093419)
			(xy 40.976179 -465.148858) (xy 40.975253 -465.204761) (xy 40.966177 -465.259929) (xy 40.949144 -465.313182)
			(xy 40.924521 -465.363378) (xy 40.892835 -465.409442) (xy 40.854763 -465.450388) (xy 40.811123 -465.485337)
			(xy 40.762848 -465.513542) (xy 40.710974 -465.534398) (xy 40.65661 -465.547458) (xy 40.600923 -465.552443)
			(xy 40.545104 -465.549246) (xy 40.49035 -465.537935) (xy 40.437833 -465.518752) (xy 40.38868 -465.492109)
			(xy 40.343941 -465.458577) (xy 40.304577 -465.418873) (xy 40.27143 -465.373848) (xy 40.245211 -465.324467)
			(xy 40.226481 -465.271787) (xy 40.215641 -465.216938) (xy 40.212923 -465.161094) (xy 40.218387 -465.105451)
			(xy 40.231914 -465.051202) (xy 40.253215 -464.999508) (xy 40.281834 -464.951478) (xy 40.317158 -464.90814)
			(xy 40.358429 -464.870422) (xy 40.404764 -464.839133) (xy 40.45517 -464.814942) (xy 40.508567 -464.798368)
			(xy 40.536114 -464.793584) (xy 40.557292 -464.789799) (xy 40.598071 -464.77611) (xy 40.635962 -464.755747)
			(xy 40.669881 -464.729293) (xy 40.69886 -464.697503) (xy 40.722069 -464.661285) (xy 40.738845 -464.621676)
			(xy 40.74871 -464.579807) (xy 40.75138 -464.536874) (xy 40.746781 -464.494105) (xy 40.741346 -464.47329)
			(xy 40.735251 -464.45048) (xy 40.72809 -464.403812) (xy 40.726749 -464.356616) (xy 40.728646 -464.333082)
			(xy 40.730426 -464.309612) (xy 40.726155 -464.262741) (xy 40.713337 -464.217454) (xy 40.692409 -464.175297)
			(xy 40.664085 -464.137708) (xy 40.629332 -464.105969) (xy 40.589334 -464.081163) (xy 40.545456 -464.064136)
			(xy 40.499195 -464.055469) (xy 40.475662 -464.054952) (xy 40.40505 -464.054952) (xy 40.373438 -464.054436)
			(xy 40.310755 -464.046178) (xy 40.249687 -464.029809) (xy 40.191277 -464.005609) (xy 40.136526 -463.973993)
			(xy 40.086369 -463.935502) (xy 40.041665 -463.890793) (xy 40.003179 -463.840633) (xy 39.971569 -463.785878)
			(xy 39.947375 -463.727466) (xy 39.931013 -463.666395) (xy 39.922761 -463.603712) (xy 39.922761 -463.540488)
			(xy 39.931013 -463.477805) (xy 39.947375 -463.416734) (xy 39.971569 -463.358322) (xy 40.003179 -463.303567)
			(xy 40.041665 -463.253407) (xy 40.086369 -463.208698) (xy 40.136526 -463.170207) (xy 40.191277 -463.138591)
			(xy 40.249687 -463.114391) (xy 40.310755 -463.098022) (xy 40.373438 -463.089764) (xy 40.40505 -463.089244)
			(xy 43.671998 -463.089244) (xy 43.69505 -463.088746) (xy 43.740401 -463.080449) (xy 43.783512 -463.064109)
			(xy 43.822969 -463.040262) (xy 43.857478 -463.00969) (xy 43.885908 -462.973396) (xy 43.907326 -462.932569)
			(xy 43.921029 -462.88855) (xy 43.926569 -462.84278) (xy 43.923764 -462.796762) (xy 43.912705 -462.752004)
			(xy 43.893755 -462.709975) (xy 43.867536 -462.672053) (xy 43.851576 -462.655412) (xy 42.235882 -461.039972)
			(xy 36.606988 -461.039972) (xy 36.583472 -461.040522) (xy 36.537243 -461.049176) (xy 36.493395 -461.066187)
			(xy 36.453425 -461.090974) (xy 36.418697 -461.12269) (xy 36.390396 -461.160255) (xy 36.369489 -461.202384)
			(xy 36.356689 -461.247641) (xy 36.352432 -461.294479) (xy 36.356865 -461.341302) (xy 36.369836 -461.38651)
			(xy 36.379912 -461.407764) (xy 36.399016 -461.446878) (xy 36.430741 -461.527947) (xy 36.454837 -461.611601)
			(xy 36.471098 -461.697124) (xy 36.479384 -461.783784) (xy 36.479625 -461.870838) (xy 36.471819 -461.957543)
			(xy 36.456031 -462.043154) (xy 36.432399 -462.12694) (xy 36.401122 -462.208183) (xy 36.362471 -462.286187)
			(xy 36.316775 -462.360285) (xy 36.264426 -462.429842) (xy 36.205871 -462.494262) (xy 36.141613 -462.552995)
			(xy 36.072202 -462.605536) (xy 35.998231 -462.651437) (xy 35.920334 -462.690304) (xy 35.839178 -462.721805)
			(xy 35.755458 -462.74567) (xy 35.66989 -462.761694) (xy 35.583208 -462.76974) (xy 35.496152 -462.76974)
			(xy 35.40947 -462.761694) (xy 35.323902 -462.74567) (xy 35.240182 -462.721805) (xy 35.159026 -462.690304)
			(xy 35.081129 -462.651437) (xy 35.007158 -462.605536) (xy 34.937747 -462.552995) (xy 34.873489 -462.494262)
			(xy 34.814934 -462.429842) (xy 34.762585 -462.360285) (xy 34.716889 -462.286187) (xy 34.678238 -462.208183)
			(xy 34.646961 -462.12694) (xy 34.623329 -462.043154) (xy 34.607541 -461.957543) (xy 34.599735 -461.870838)
			(xy 34.599976 -461.783784) (xy 34.608262 -461.697124) (xy 34.624523 -461.611601) (xy 34.648619 -461.527947)
			(xy 34.680344 -461.446878) (xy 34.699448 -461.407764) (xy 34.709593 -461.386538) (xy 34.72257 -461.341319)
			(xy 34.727005 -461.294484) (xy 34.722748 -461.247633) (xy 34.709944 -461.202365) (xy 34.68903 -461.160226)
			(xy 34.660719 -461.122653) (xy 34.62598 -461.090931) (xy 34.585997 -461.066141) (xy 34.542136 -461.049131)
			(xy 34.495894 -461.040481) (xy 34.472372 -461.039972) (xy 31.526988 -461.039972) (xy 31.503472 -461.040522)
			(xy 31.457243 -461.049176) (xy 31.413395 -461.066187) (xy 31.373425 -461.090974) (xy 31.338697 -461.12269)
			(xy 31.310396 -461.160255) (xy 31.289489 -461.202384) (xy 31.276689 -461.247641) (xy 31.272432 -461.294479)
			(xy 31.276865 -461.341302) (xy 31.289836 -461.38651) (xy 31.299912 -461.407764) (xy 31.319016 -461.446878)
			(xy 31.350741 -461.527947) (xy 31.374837 -461.611601) (xy 31.391098 -461.697124) (xy 31.399384 -461.783784)
			(xy 31.399625 -461.870838) (xy 31.391819 -461.957543) (xy 31.376031 -462.043154) (xy 31.352399 -462.12694)
			(xy 31.321122 -462.208183) (xy 31.282471 -462.286187) (xy 31.236775 -462.360285) (xy 31.184426 -462.429842)
			(xy 31.125871 -462.494262) (xy 31.061613 -462.552995) (xy 30.992202 -462.605536) (xy 30.918231 -462.651437)
			(xy 30.840334 -462.690304) (xy 30.759178 -462.721805) (xy 30.675458 -462.74567) (xy 30.58989 -462.761694)
			(xy 30.503208 -462.76974) (xy 30.416152 -462.76974) (xy 30.32947 -462.761694) (xy 30.243902 -462.74567)
			(xy 30.160182 -462.721805) (xy 30.079026 -462.690304) (xy 30.001129 -462.651437) (xy 29.927158 -462.605536)
			(xy 29.857747 -462.552995) (xy 29.793489 -462.494262) (xy 29.734934 -462.429842) (xy 29.682585 -462.360285)
			(xy 29.636889 -462.286187) (xy 29.598238 -462.208183) (xy 29.566961 -462.12694) (xy 29.543329 -462.043154)
			(xy 29.527541 -461.957543) (xy 29.519735 -461.870838) (xy 29.519976 -461.783784) (xy 29.528262 -461.697124)
			(xy 29.544523 -461.611601) (xy 29.568619 -461.527947) (xy 29.600344 -461.446878) (xy 29.619448 -461.407764)
			(xy 29.629593 -461.386538) (xy 29.64257 -461.341319) (xy 29.647005 -461.294484) (xy 29.642748 -461.247633)
			(xy 29.629944 -461.202365) (xy 29.60903 -461.160226) (xy 29.580719 -461.122653) (xy 29.54598 -461.090931)
			(xy 29.505997 -461.066141) (xy 29.462136 -461.049131) (xy 29.415894 -461.040481) (xy 29.392372 -461.039972)
			(xy 28.328366 -461.039972) (xy 28.049474 -460.76108) (xy 27.640026 -460.76108) (xy 27.608391 -460.760643)
			(xy 27.545662 -460.752387) (xy 27.484547 -460.736014) (xy 27.426092 -460.711804) (xy 27.371297 -460.680171)
			(xy 27.321101 -460.641657) (xy 27.276361 -460.596919) (xy 27.237843 -460.546724) (xy 27.206207 -460.491931)
			(xy 27.181994 -460.433478) (xy 27.165618 -460.372364) (xy 27.157359 -460.309635) (xy 19.90344 -460.309635)
			(xy 19.90344 -463.401428) (xy 27.258263 -463.401428) (xy 27.264363 -463.345991) (xy 27.278469 -463.292034)
			(xy 27.300281 -463.240705) (xy 27.329335 -463.193099) (xy 27.36501 -463.150231) (xy 27.406547 -463.113014)
			(xy 27.45306 -463.082241) (xy 27.503557 -463.058569) (xy 27.556964 -463.042501) (xy 27.61214 -463.034381)
			(xy 27.640026 -463.033872) (xy 27.667912 -463.034381) (xy 27.723088 -463.042501) (xy 27.776495 -463.058569)
			(xy 27.826992 -463.082241) (xy 27.873505 -463.113014) (xy 27.915042 -463.150231) (xy 27.950717 -463.193099)
			(xy 27.979771 -463.240705) (xy 28.001583 -463.292034) (xy 28.015689 -463.345991) (xy 28.021789 -463.401428)
			(xy 28.019752 -463.457162) (xy 28.009622 -463.512005) (xy 27.991615 -463.564789) (xy 27.966114 -463.614389)
			(xy 27.933663 -463.659747) (xy 27.894954 -463.699896) (xy 27.850811 -463.733982) (xy 27.802176 -463.761278)
			(xy 27.750085 -463.781201) (xy 27.695648 -463.793327) (xy 27.640026 -463.797398) (xy 27.584404 -463.793327)
			(xy 27.529967 -463.781201) (xy 27.477876 -463.761278) (xy 27.429241 -463.733982) (xy 27.385098 -463.699896)
			(xy 27.346389 -463.659747) (xy 27.313938 -463.614389) (xy 27.288437 -463.564789) (xy 27.27043 -463.512005)
			(xy 27.2603 -463.457162) (xy 27.258263 -463.401428) (xy 19.90344 -463.401428) (xy 19.90344 -464.413362)
			(xy 29.519874 -464.413362) (xy 29.519874 -464.326462) (xy 29.527892 -464.239933) (xy 29.54386 -464.154513)
			(xy 29.567641 -464.070931) (xy 29.599033 -463.989899) (xy 29.637767 -463.91211) (xy 29.683514 -463.838226)
			(xy 29.735883 -463.768879) (xy 29.794427 -463.704659) (xy 29.858647 -463.646115) (xy 29.927994 -463.593746)
			(xy 30.001878 -463.547999) (xy 30.079667 -463.509265) (xy 30.160699 -463.477873) (xy 30.244281 -463.454092)
			(xy 30.329701 -463.438124) (xy 30.41623 -463.430106) (xy 30.45968 -463.429604) (xy 30.50313 -463.430106)
			(xy 30.589659 -463.438124) (xy 30.675079 -463.454092) (xy 30.758661 -463.477873) (xy 30.839693 -463.509265)
			(xy 30.917482 -463.547999) (xy 30.991366 -463.593746) (xy 31.060713 -463.646115) (xy 31.124933 -463.704659)
			(xy 31.183477 -463.768879) (xy 31.235846 -463.838226) (xy 31.281593 -463.91211) (xy 31.320327 -463.989899)
			(xy 31.351719 -464.070931) (xy 31.3755 -464.154513) (xy 31.391468 -464.239933) (xy 31.399486 -464.326462)
			(xy 31.399486 -464.413362) (xy 34.599874 -464.413362) (xy 34.599874 -464.326462) (xy 34.607892 -464.239933)
			(xy 34.62386 -464.154513) (xy 34.647641 -464.070931) (xy 34.679033 -463.989899) (xy 34.717767 -463.91211)
			(xy 34.763514 -463.838226) (xy 34.815883 -463.768879) (xy 34.874427 -463.704659) (xy 34.938647 -463.646115)
			(xy 35.007994 -463.593746) (xy 35.081878 -463.547999) (xy 35.159667 -463.509265) (xy 35.240699 -463.477873)
			(xy 35.324281 -463.454092) (xy 35.409701 -463.438124) (xy 35.49623 -463.430106) (xy 35.53968 -463.429604)
			(xy 35.58313 -463.430106) (xy 35.669659 -463.438124) (xy 35.755079 -463.454092) (xy 35.838661 -463.477873)
			(xy 35.919693 -463.509265) (xy 35.997482 -463.547999) (xy 36.071366 -463.593746) (xy 36.140713 -463.646115)
			(xy 36.204933 -463.704659) (xy 36.263477 -463.768879) (xy 36.315846 -463.838226) (xy 36.361593 -463.91211)
			(xy 36.400327 -463.989899) (xy 36.431719 -464.070931) (xy 36.4555 -464.154513) (xy 36.471468 -464.239933)
			(xy 36.479486 -464.326462) (xy 36.479486 -464.413362) (xy 36.471468 -464.499891) (xy 36.4555 -464.585311)
			(xy 36.431719 -464.668893) (xy 36.400327 -464.749925) (xy 36.361593 -464.827714) (xy 36.315846 -464.901598)
			(xy 36.263477 -464.970945) (xy 36.204933 -465.035165) (xy 36.140713 -465.093709) (xy 36.071366 -465.146078)
			(xy 35.997482 -465.191825) (xy 35.919693 -465.230559) (xy 35.838661 -465.261951) (xy 35.755079 -465.285732)
			(xy 35.669659 -465.3017) (xy 35.58313 -465.309718) (xy 35.49623 -465.309718) (xy 35.409701 -465.3017)
			(xy 35.324281 -465.285732) (xy 35.240699 -465.261951) (xy 35.159667 -465.230559) (xy 35.081878 -465.191825)
			(xy 35.007994 -465.146078) (xy 34.938647 -465.093709) (xy 34.874427 -465.035165) (xy 34.815883 -464.970945)
			(xy 34.763514 -464.901598) (xy 34.717767 -464.827714) (xy 34.679033 -464.749925) (xy 34.647641 -464.668893)
			(xy 34.62386 -464.585311) (xy 34.607892 -464.499891) (xy 34.599874 -464.413362) (xy 31.399486 -464.413362)
			(xy 31.391468 -464.499891) (xy 31.3755 -464.585311) (xy 31.351719 -464.668893) (xy 31.320327 -464.749925)
			(xy 31.281593 -464.827714) (xy 31.235846 -464.901598) (xy 31.183477 -464.970945) (xy 31.124933 -465.035165)
			(xy 31.060713 -465.093709) (xy 30.991366 -465.146078) (xy 30.917482 -465.191825) (xy 30.839693 -465.230559)
			(xy 30.758661 -465.261951) (xy 30.675079 -465.285732) (xy 30.589659 -465.3017) (xy 30.50313 -465.309718)
			(xy 30.41623 -465.309718) (xy 30.329701 -465.3017) (xy 30.244281 -465.285732) (xy 30.160699 -465.261951)
			(xy 30.079667 -465.230559) (xy 30.001878 -465.191825) (xy 29.927994 -465.146078) (xy 29.858647 -465.093709)
			(xy 29.794427 -465.035165) (xy 29.735883 -464.970945) (xy 29.683514 -464.901598) (xy 29.637767 -464.827714)
			(xy 29.599033 -464.749925) (xy 29.567641 -464.668893) (xy 29.54386 -464.585311) (xy 29.527892 -464.499891)
			(xy 29.519874 -464.413362) (xy 19.90344 -464.413362) (xy 19.90344 -465.250276) (xy 19.903971 -465.266894)
			(xy 19.912572 -465.298997) (xy 19.92917 -465.327792) (xy 19.940524 -465.339938) (xy 25.02154 -470.4207)
			(xy 25.02154 -478.795334) (xy 74.887836 -478.795334) (xy 74.887836 -477.804734) (xy 74.888285 -477.726894)
			(xy 74.896067 -477.571409) (xy 74.911614 -477.416508) (xy 74.934886 -477.262578) (xy 74.965825 -477.110003)
			(xy 75.004354 -476.959167) (xy 75.050376 -476.810446) (xy 75.103777 -476.664211) (xy 75.164423 -476.52083)
			(xy 75.232161 -476.38066) (xy 75.306823 -476.244052) (xy 75.388222 -476.111348) (xy 75.476155 -475.98288)
			(xy 75.5704 -475.858969) (xy 75.670723 -475.739926) (xy 75.776873 -475.626047) (xy 75.888584 -475.517618)
			(xy 75.946762 -475.465902) (xy 76.007239 -475.41338) (xy 76.132813 -475.313911) (xy 76.263344 -475.221041)
			(xy 76.398485 -475.135018) (xy 76.537878 -475.056071) (xy 76.681152 -474.984408) (xy 76.827927 -474.920221)
			(xy 76.977814 -474.863679) (xy 77.130414 -474.814933) (xy 77.285323 -474.774111) (xy 77.442128 -474.741323)
			(xy 77.600415 -474.716656) (xy 77.759761 -474.700175) (xy 77.919746 -474.691923) (xy 78.079942 -474.691923)
			(xy 78.239927 -474.700175) (xy 78.399273 -474.716656) (xy 78.55756 -474.741323) (xy 78.714365 -474.774111)
			(xy 78.869274 -474.814933) (xy 79.021874 -474.863679) (xy 79.171761 -474.920221) (xy 79.318536 -474.984408)
			(xy 79.46181 -475.056071) (xy 79.601203 -475.135018) (xy 79.736344 -475.221041) (xy 79.866875 -475.313911)
			(xy 79.992449 -475.41338) (xy 80.052926 -475.465902) (xy 80.111074 -475.517651) (xy 80.22278 -475.62608)
			(xy 80.328926 -475.739959) (xy 80.429246 -475.859002) (xy 80.523489 -475.982912) (xy 80.611419 -476.111379)
			(xy 80.692816 -476.244081) (xy 80.767477 -476.380687) (xy 80.835215 -476.520854) (xy 80.89586 -476.664233)
			(xy 80.949261 -476.810464) (xy 80.995285 -476.959183) (xy 81.033815 -477.110016) (xy 81.064757 -477.262588)
			(xy 81.088032 -477.416515) (xy 81.103582 -477.571413) (xy 81.111368 -477.726895) (xy 81.111852 -477.804734)
			(xy 81.111852 -478.795334) (xy 81.111371 -478.874704) (xy 81.103273 -479.033238) (xy 81.087104 -479.191153)
			(xy 81.062907 -479.348038) (xy 81.030744 -479.503486) (xy 80.9907 -479.657093) (xy 80.942878 -479.808459)
			(xy 80.887402 -479.95719) (xy 80.824417 -480.1029) (xy 80.754087 -480.24521) (xy 80.676594 -480.383751)
			(xy 80.59214 -480.518161) (xy 80.500944 -480.648091) (xy 80.403245 -480.773204) (xy 80.299294 -480.893175)
			(xy 80.189364 -481.00769) (xy 80.073739 -481.116454) (xy 80.013556 -481.168202) (xy 79.953637 -481.218513)
			(xy 79.829479 -481.313747) (xy 79.700688 -481.402615) (xy 79.567588 -481.484891) (xy 79.430517 -481.560366)
			(xy 79.289823 -481.628849) (xy 79.145862 -481.690167) (xy 78.998998 -481.744164) (xy 78.849603 -481.790704)
			(xy 78.698055 -481.829669) (xy 78.54474 -481.86096) (xy 78.390044 -481.884498) (xy 78.23436 -481.900223)
			(xy 78.078082 -481.908096) (xy 77.921606 -481.908096) (xy 77.765328 -481.900223) (xy 77.609644 -481.884498)
			(xy 77.454948 -481.86096) (xy 77.301633 -481.829669) (xy 77.150085 -481.790704) (xy 77.00069 -481.744164)
			(xy 76.853826 -481.690167) (xy 76.709865 -481.628849) (xy 76.569171 -481.560366) (xy 76.4321 -481.484891)
			(xy 76.299 -481.402615) (xy 76.170209 -481.313747) (xy 76.046051 -481.218513) (xy 75.986132 -481.168202)
			(xy 75.925932 -481.116473) (xy 75.810304 -481.007712) (xy 75.700371 -480.893197) (xy 75.596418 -480.773228)
			(xy 75.498717 -480.648114) (xy 75.407521 -480.518183) (xy 75.323067 -480.383772) (xy 75.245575 -480.24523)
			(xy 75.175246 -480.102918) (xy 75.112264 -479.957206) (xy 75.056791 -479.808472) (xy 75.008974 -479.657104)
			(xy 74.968934 -479.503495) (xy 74.936778 -479.348044) (xy 74.912588 -479.191157) (xy 74.896428 -479.03324)
			(xy 74.888339 -478.874705) (xy 74.887836 -478.795334) (xy 25.02154 -478.795334) (xy 25.02154 -482.747235)
			(xy 51.008016 -482.747235) (xy 51.008016 -482.666125) (xy 51.015966 -482.585406) (xy 51.031789 -482.505855)
			(xy 51.055334 -482.428239) (xy 51.086373 -482.353303) (xy 51.124608 -482.281771) (xy 51.16967 -482.214331)
			(xy 51.221125 -482.151632) (xy 51.278478 -482.094279) (xy 51.341177 -482.042824) (xy 51.408617 -481.997762)
			(xy 51.480149 -481.959527) (xy 51.555085 -481.928488) (xy 51.632701 -481.904943) (xy 51.712252 -481.88912)
			(xy 51.792971 -481.88117) (xy 51.833526 -481.880672) (xy 51.874081 -481.88117) (xy 51.9548 -481.88912)
			(xy 52.034351 -481.904943) (xy 52.111967 -481.928488) (xy 52.186903 -481.959527) (xy 52.258435 -481.997762)
			(xy 52.325875 -482.042824) (xy 52.388574 -482.094279) (xy 52.445927 -482.151632) (xy 52.497382 -482.214331)
			(xy 52.542444 -482.281771) (xy 52.580679 -482.353303) (xy 52.611718 -482.428239) (xy 52.635263 -482.505855)
			(xy 52.651086 -482.585406) (xy 52.659036 -482.666125) (xy 52.659036 -482.747235) (xy 52.651086 -482.827954)
			(xy 52.635263 -482.907505) (xy 52.611718 -482.985121) (xy 52.580679 -483.060057) (xy 52.542444 -483.131589)
			(xy 52.497382 -483.199029) (xy 52.445927 -483.261728) (xy 52.388574 -483.319081) (xy 52.325875 -483.370536)
			(xy 52.258435 -483.415598) (xy 52.186903 -483.453833) (xy 52.111967 -483.484872) (xy 52.034351 -483.508417)
			(xy 51.9548 -483.52424) (xy 51.874081 -483.53219) (xy 51.792971 -483.53219) (xy 51.712252 -483.52424)
			(xy 51.632701 -483.508417) (xy 51.555085 -483.484872) (xy 51.480149 -483.453833) (xy 51.408617 -483.415598)
			(xy 51.341177 -483.370536) (xy 51.278478 -483.319081) (xy 51.221125 -483.261728) (xy 51.16967 -483.199029)
			(xy 51.124608 -483.131589) (xy 51.086373 -483.060057) (xy 51.055334 -482.985121) (xy 51.031789 -482.907505)
			(xy 51.015966 -482.827954) (xy 51.008016 -482.747235) (xy 25.02154 -482.747235) (xy 25.02154 -485.234589)
			(xy 73.724508 -485.234589) (xy 73.724508 -485.163267) (xy 73.732494 -485.092393) (xy 73.748364 -485.022858)
			(xy 73.771921 -484.955538) (xy 73.802866 -484.891279) (xy 73.840812 -484.830888) (xy 73.885281 -484.775126)
			(xy 73.935714 -484.724693) (xy 73.991476 -484.680224) (xy 74.051867 -484.642278) (xy 74.116126 -484.611333)
			(xy 74.183446 -484.587776) (xy 74.252981 -484.571906) (xy 74.323855 -484.56392) (xy 74.359516 -484.56342)
			(xy 74.395177 -484.56392) (xy 74.466051 -484.571906) (xy 74.535586 -484.587776) (xy 74.602906 -484.611333)
			(xy 74.667165 -484.642278) (xy 74.727556 -484.680224) (xy 74.783318 -484.724693) (xy 74.833751 -484.775126)
			(xy 74.87822 -484.830888) (xy 74.916166 -484.891279) (xy 74.947111 -484.955538) (xy 74.970668 -485.022858)
			(xy 74.986538 -485.092393) (xy 74.994524 -485.163267) (xy 74.994524 -485.234589) (xy 75.653638 -485.234589)
			(xy 75.653638 -485.163267) (xy 75.661624 -485.092393) (xy 75.677494 -485.022858) (xy 75.701051 -484.955538)
			(xy 75.731996 -484.891279) (xy 75.769942 -484.830888) (xy 75.814411 -484.775126) (xy 75.864844 -484.724693)
			(xy 75.920606 -484.680224) (xy 75.980997 -484.642278) (xy 76.045256 -484.611333) (xy 76.112576 -484.587776)
			(xy 76.182111 -484.571906) (xy 76.252985 -484.56392) (xy 76.288646 -484.56342) (xy 76.324307 -484.56392)
			(xy 76.395181 -484.571906) (xy 76.464716 -484.587776) (xy 76.532036 -484.611333) (xy 76.596295 -484.642278)
			(xy 76.656686 -484.680224) (xy 76.712448 -484.724693) (xy 76.762881 -484.775126) (xy 76.80735 -484.830888)
			(xy 76.845296 -484.891279) (xy 76.876241 -484.955538) (xy 76.899798 -485.022858) (xy 76.915668 -485.092393)
			(xy 76.923654 -485.163267) (xy 76.923654 -485.234589) (xy 76.918502 -485.280309) (xy 77.397602 -485.280309)
			(xy 77.397602 -485.208987) (xy 77.405588 -485.138113) (xy 77.421458 -485.068578) (xy 77.445015 -485.001258)
			(xy 77.47596 -484.936999) (xy 77.513906 -484.876608) (xy 77.558375 -484.820846) (xy 77.608808 -484.770413)
			(xy 77.66457 -484.725944) (xy 77.724961 -484.687998) (xy 77.78922 -484.657053) (xy 77.85654 -484.633496)
			(xy 77.926075 -484.617626) (xy 77.996949 -484.60964) (xy 78.03261 -484.60914) (xy 78.068271 -484.60964)
			(xy 78.139145 -484.617626) (xy 78.20868 -484.633496) (xy 78.276 -484.657053) (xy 78.340259 -484.687998)
			(xy 78.40065 -484.725944) (xy 78.456412 -484.770413) (xy 78.506845 -484.820846) (xy 78.551314 -484.876608)
			(xy 78.58926 -484.936999) (xy 78.620205 -485.001258) (xy 78.643762 -485.068578) (xy 78.659632 -485.138113)
			(xy 78.667618 -485.208987) (xy 78.667618 -485.280309) (xy 79.326732 -485.280309) (xy 79.326732 -485.208987)
			(xy 79.334718 -485.138113) (xy 79.350588 -485.068578) (xy 79.374145 -485.001258) (xy 79.40509 -484.936999)
			(xy 79.443036 -484.876608) (xy 79.487505 -484.820846) (xy 79.537938 -484.770413) (xy 79.5937 -484.725944)
			(xy 79.654091 -484.687998) (xy 79.71835 -484.657053) (xy 79.78567 -484.633496) (xy 79.855205 -484.617626)
			(xy 79.926079 -484.60964) (xy 79.96174 -484.60914) (xy 79.997401 -484.60964) (xy 80.068275 -484.617626)
			(xy 80.13781 -484.633496) (xy 80.20513 -484.657053) (xy 80.269389 -484.687998) (xy 80.32978 -484.725944)
			(xy 80.385542 -484.770413) (xy 80.435975 -484.820846) (xy 80.480444 -484.876608) (xy 80.51839 -484.936999)
			(xy 80.549335 -485.001258) (xy 80.572892 -485.068578) (xy 80.588762 -485.138113) (xy 80.596748 -485.208987)
			(xy 80.596748 -485.280309) (xy 80.588762 -485.351183) (xy 80.575044 -485.41129) (xy 87.096345 -485.41129)
			(xy 87.102445 -485.355853) (xy 87.116551 -485.301896) (xy 87.138363 -485.250567) (xy 87.167417 -485.202961)
			(xy 87.203092 -485.160093) (xy 87.244629 -485.122876) (xy 87.291142 -485.092103) (xy 87.341639 -485.068431)
			(xy 87.395046 -485.052363) (xy 87.450222 -485.044243) (xy 87.478108 -485.043734) (xy 87.505994 -485.044243)
			(xy 87.56117 -485.052363) (xy 87.614577 -485.068431) (xy 87.665074 -485.092103) (xy 87.711587 -485.122876)
			(xy 87.753124 -485.160093) (xy 87.788799 -485.202961) (xy 87.817853 -485.250567) (xy 87.839665 -485.301896)
			(xy 87.853771 -485.355853) (xy 87.859871 -485.41129) (xy 87.857834 -485.467024) (xy 87.847704 -485.521867)
			(xy 87.829697 -485.574651) (xy 87.804196 -485.624251) (xy 87.771745 -485.669609) (xy 87.733036 -485.709758)
			(xy 87.688893 -485.743844) (xy 87.640258 -485.77114) (xy 87.588167 -485.791063) (xy 87.53373 -485.803189)
			(xy 87.478108 -485.80726) (xy 87.422486 -485.803189) (xy 87.368049 -485.791063) (xy 87.315958 -485.77114)
			(xy 87.267323 -485.743844) (xy 87.22318 -485.709758) (xy 87.184471 -485.669609) (xy 87.15202 -485.624251)
			(xy 87.126519 -485.574651) (xy 87.108512 -485.521867) (xy 87.098382 -485.467024) (xy 87.096345 -485.41129)
			(xy 80.575044 -485.41129) (xy 80.572892 -485.420718) (xy 80.549335 -485.488038) (xy 80.51839 -485.552297)
			(xy 80.480444 -485.612688) (xy 80.435975 -485.66845) (xy 80.385542 -485.718883) (xy 80.32978 -485.763352)
			(xy 80.269389 -485.801298) (xy 80.20513 -485.832243) (xy 80.13781 -485.8558) (xy 80.068275 -485.87167)
			(xy 79.997401 -485.879656) (xy 79.926079 -485.879656) (xy 79.855205 -485.87167) (xy 79.78567 -485.8558)
			(xy 79.71835 -485.832243) (xy 79.654091 -485.801298) (xy 79.5937 -485.763352) (xy 79.537938 -485.718883)
			(xy 79.487505 -485.66845) (xy 79.443036 -485.612688) (xy 79.40509 -485.552297) (xy 79.374145 -485.488038)
			(xy 79.350588 -485.420718) (xy 79.334718 -485.351183) (xy 79.326732 -485.280309) (xy 78.667618 -485.280309)
			(xy 78.659632 -485.351183) (xy 78.643762 -485.420718) (xy 78.620205 -485.488038) (xy 78.58926 -485.552297)
			(xy 78.551314 -485.612688) (xy 78.506845 -485.66845) (xy 78.456412 -485.718883) (xy 78.40065 -485.763352)
			(xy 78.340259 -485.801298) (xy 78.276 -485.832243) (xy 78.20868 -485.8558) (xy 78.139145 -485.87167)
			(xy 78.068271 -485.879656) (xy 77.996949 -485.879656) (xy 77.926075 -485.87167) (xy 77.85654 -485.8558)
			(xy 77.78922 -485.832243) (xy 77.724961 -485.801298) (xy 77.66457 -485.763352) (xy 77.608808 -485.718883)
			(xy 77.558375 -485.66845) (xy 77.513906 -485.612688) (xy 77.47596 -485.552297) (xy 77.445015 -485.488038)
			(xy 77.421458 -485.420718) (xy 77.405588 -485.351183) (xy 77.397602 -485.280309) (xy 76.918502 -485.280309)
			(xy 76.915668 -485.305463) (xy 76.899798 -485.374998) (xy 76.876241 -485.442318) (xy 76.845296 -485.506577)
			(xy 76.80735 -485.566968) (xy 76.762881 -485.62273) (xy 76.712448 -485.673163) (xy 76.656686 -485.717632)
			(xy 76.596295 -485.755578) (xy 76.532036 -485.786523) (xy 76.464716 -485.81008) (xy 76.395181 -485.82595)
			(xy 76.324307 -485.833936) (xy 76.252985 -485.833936) (xy 76.182111 -485.82595) (xy 76.112576 -485.81008)
			(xy 76.045256 -485.786523) (xy 75.980997 -485.755578) (xy 75.920606 -485.717632) (xy 75.864844 -485.673163)
			(xy 75.814411 -485.62273) (xy 75.769942 -485.566968) (xy 75.731996 -485.506577) (xy 75.701051 -485.442318)
			(xy 75.677494 -485.374998) (xy 75.661624 -485.305463) (xy 75.653638 -485.234589) (xy 74.994524 -485.234589)
			(xy 74.986538 -485.305463) (xy 74.970668 -485.374998) (xy 74.947111 -485.442318) (xy 74.916166 -485.506577)
			(xy 74.87822 -485.566968) (xy 74.833751 -485.62273) (xy 74.783318 -485.673163) (xy 74.727556 -485.717632)
			(xy 74.667165 -485.755578) (xy 74.602906 -485.786523) (xy 74.535586 -485.81008) (xy 74.466051 -485.82595)
			(xy 74.395177 -485.833936) (xy 74.323855 -485.833936) (xy 74.252981 -485.82595) (xy 74.183446 -485.81008)
			(xy 74.116126 -485.786523) (xy 74.051867 -485.755578) (xy 73.991476 -485.717632) (xy 73.935714 -485.673163)
			(xy 73.885281 -485.62273) (xy 73.840812 -485.566968) (xy 73.802866 -485.506577) (xy 73.771921 -485.442318)
			(xy 73.748364 -485.374998) (xy 73.732494 -485.305463) (xy 73.724508 -485.234589) (xy 25.02154 -485.234589)
			(xy 25.02154 -486.991253) (xy 73.724508 -486.991253) (xy 73.724508 -486.919931) (xy 73.732494 -486.849057)
			(xy 73.748364 -486.779522) (xy 73.771921 -486.712202) (xy 73.802866 -486.647943) (xy 73.840812 -486.587552)
			(xy 73.885281 -486.53179) (xy 73.935714 -486.481357) (xy 73.991476 -486.436888) (xy 74.051867 -486.398942)
			(xy 74.116126 -486.367997) (xy 74.183446 -486.34444) (xy 74.252981 -486.32857) (xy 74.323855 -486.320584)
			(xy 74.359516 -486.320084) (xy 74.395177 -486.320584) (xy 74.466051 -486.32857) (xy 74.535586 -486.34444)
			(xy 74.602906 -486.367997) (xy 74.667165 -486.398942) (xy 74.727556 -486.436888) (xy 74.783318 -486.481357)
			(xy 74.833751 -486.53179) (xy 74.87822 -486.587552) (xy 74.916166 -486.647943) (xy 74.947111 -486.712202)
			(xy 74.970668 -486.779522) (xy 74.986538 -486.849057) (xy 74.994524 -486.919931) (xy 74.994524 -486.991253)
			(xy 75.653638 -486.991253) (xy 75.653638 -486.919931) (xy 75.661624 -486.849057) (xy 75.677494 -486.779522)
			(xy 75.701051 -486.712202) (xy 75.731996 -486.647943) (xy 75.769942 -486.587552) (xy 75.814411 -486.53179)
			(xy 75.864844 -486.481357) (xy 75.920606 -486.436888) (xy 75.980997 -486.398942) (xy 76.045256 -486.367997)
			(xy 76.112576 -486.34444) (xy 76.182111 -486.32857) (xy 76.252985 -486.320584) (xy 76.288646 -486.320084)
			(xy 76.324307 -486.320584) (xy 76.395181 -486.32857) (xy 76.464716 -486.34444) (xy 76.532036 -486.367997)
			(xy 76.596295 -486.398942) (xy 76.656686 -486.436888) (xy 76.712448 -486.481357) (xy 76.762881 -486.53179)
			(xy 76.80735 -486.587552) (xy 76.845296 -486.647943) (xy 76.876241 -486.712202) (xy 76.899798 -486.779522)
			(xy 76.915668 -486.849057) (xy 76.923654 -486.919931) (xy 76.923654 -486.991253) (xy 76.918502 -487.036973)
			(xy 77.397602 -487.036973) (xy 77.397602 -486.965651) (xy 77.405588 -486.894777) (xy 77.421458 -486.825242)
			(xy 77.445015 -486.757922) (xy 77.47596 -486.693663) (xy 77.513906 -486.633272) (xy 77.558375 -486.57751)
			(xy 77.608808 -486.527077) (xy 77.66457 -486.482608) (xy 77.724961 -486.444662) (xy 77.78922 -486.413717)
			(xy 77.85654 -486.39016) (xy 77.926075 -486.37429) (xy 77.996949 -486.366304) (xy 78.03261 -486.365804)
			(xy 78.068271 -486.366304) (xy 78.139145 -486.37429) (xy 78.20868 -486.39016) (xy 78.276 -486.413717)
			(xy 78.340259 -486.444662) (xy 78.40065 -486.482608) (xy 78.456412 -486.527077) (xy 78.506845 -486.57751)
			(xy 78.551314 -486.633272) (xy 78.58926 -486.693663) (xy 78.620205 -486.757922) (xy 78.643762 -486.825242)
			(xy 78.659632 -486.894777) (xy 78.667618 -486.965651) (xy 78.667618 -487.036973) (xy 79.326732 -487.036973)
			(xy 79.326732 -486.965651) (xy 79.334718 -486.894777) (xy 79.350588 -486.825242) (xy 79.374145 -486.757922)
			(xy 79.40509 -486.693663) (xy 79.443036 -486.633272) (xy 79.487505 -486.57751) (xy 79.537938 -486.527077)
			(xy 79.5937 -486.482608) (xy 79.654091 -486.444662) (xy 79.71835 -486.413717) (xy 79.78567 -486.39016)
			(xy 79.855205 -486.37429) (xy 79.926079 -486.366304) (xy 79.96174 -486.365804) (xy 79.997401 -486.366304)
			(xy 80.068275 -486.37429) (xy 80.13781 -486.39016) (xy 80.20513 -486.413717) (xy 80.269389 -486.444662)
			(xy 80.32978 -486.482608) (xy 80.385542 -486.527077) (xy 80.435975 -486.57751) (xy 80.480444 -486.633272)
			(xy 80.51839 -486.693663) (xy 80.549335 -486.757922) (xy 80.561183 -486.79178) (xy 87.384635 -486.79178)
			(xy 87.390735 -486.736343) (xy 87.404841 -486.682386) (xy 87.426653 -486.631057) (xy 87.455707 -486.583451)
			(xy 87.491382 -486.540583) (xy 87.532919 -486.503366) (xy 87.579432 -486.472593) (xy 87.629929 -486.448921)
			(xy 87.683336 -486.432853) (xy 87.738512 -486.424733) (xy 87.766398 -486.424224) (xy 87.794284 -486.424733)
			(xy 87.84946 -486.432853) (xy 87.902867 -486.448921) (xy 87.953364 -486.472593) (xy 87.999877 -486.503366)
			(xy 88.041414 -486.540583) (xy 88.077089 -486.583451) (xy 88.106143 -486.631057) (xy 88.127955 -486.682386)
			(xy 88.142061 -486.736343) (xy 88.148161 -486.79178) (xy 88.146124 -486.847514) (xy 88.135994 -486.902357)
			(xy 88.117987 -486.955141) (xy 88.092486 -487.004741) (xy 88.060035 -487.050099) (xy 88.021326 -487.090248)
			(xy 87.977183 -487.124334) (xy 87.928548 -487.15163) (xy 87.876457 -487.171553) (xy 87.82202 -487.183679)
			(xy 87.766398 -487.18775) (xy 87.710776 -487.183679) (xy 87.656339 -487.171553) (xy 87.604248 -487.15163)
			(xy 87.555613 -487.124334) (xy 87.51147 -487.090248) (xy 87.472761 -487.050099) (xy 87.44031 -487.004741)
			(xy 87.414809 -486.955141) (xy 87.396802 -486.902357) (xy 87.386672 -486.847514) (xy 87.384635 -486.79178)
			(xy 80.561183 -486.79178) (xy 80.572892 -486.825242) (xy 80.588762 -486.894777) (xy 80.596748 -486.965651)
			(xy 80.596748 -487.036973) (xy 80.588762 -487.107847) (xy 80.572892 -487.177382) (xy 80.549335 -487.244702)
			(xy 80.51839 -487.308961) (xy 80.480444 -487.369352) (xy 80.435975 -487.425114) (xy 80.385542 -487.475547)
			(xy 80.32978 -487.520016) (xy 80.269389 -487.557962) (xy 80.20513 -487.588907) (xy 80.13781 -487.612464)
			(xy 80.068275 -487.628334) (xy 79.997401 -487.63632) (xy 79.926079 -487.63632) (xy 79.855205 -487.628334)
			(xy 79.78567 -487.612464) (xy 79.71835 -487.588907) (xy 79.654091 -487.557962) (xy 79.5937 -487.520016)
			(xy 79.537938 -487.475547) (xy 79.487505 -487.425114) (xy 79.443036 -487.369352) (xy 79.40509 -487.308961)
			(xy 79.374145 -487.244702) (xy 79.350588 -487.177382) (xy 79.334718 -487.107847) (xy 79.326732 -487.036973)
			(xy 78.667618 -487.036973) (xy 78.659632 -487.107847) (xy 78.643762 -487.177382) (xy 78.620205 -487.244702)
			(xy 78.58926 -487.308961) (xy 78.551314 -487.369352) (xy 78.506845 -487.425114) (xy 78.456412 -487.475547)
			(xy 78.40065 -487.520016) (xy 78.340259 -487.557962) (xy 78.276 -487.588907) (xy 78.20868 -487.612464)
			(xy 78.139145 -487.628334) (xy 78.068271 -487.63632) (xy 77.996949 -487.63632) (xy 77.926075 -487.628334)
			(xy 77.85654 -487.612464) (xy 77.78922 -487.588907) (xy 77.724961 -487.557962) (xy 77.66457 -487.520016)
			(xy 77.608808 -487.475547) (xy 77.558375 -487.425114) (xy 77.513906 -487.369352) (xy 77.47596 -487.308961)
			(xy 77.445015 -487.244702) (xy 77.421458 -487.177382) (xy 77.405588 -487.107847) (xy 77.397602 -487.036973)
			(xy 76.918502 -487.036973) (xy 76.915668 -487.062127) (xy 76.899798 -487.131662) (xy 76.876241 -487.198982)
			(xy 76.845296 -487.263241) (xy 76.80735 -487.323632) (xy 76.762881 -487.379394) (xy 76.712448 -487.429827)
			(xy 76.656686 -487.474296) (xy 76.596295 -487.512242) (xy 76.532036 -487.543187) (xy 76.464716 -487.566744)
			(xy 76.395181 -487.582614) (xy 76.324307 -487.5906) (xy 76.252985 -487.5906) (xy 76.182111 -487.582614)
			(xy 76.112576 -487.566744) (xy 76.045256 -487.543187) (xy 75.980997 -487.512242) (xy 75.920606 -487.474296)
			(xy 75.864844 -487.429827) (xy 75.814411 -487.379394) (xy 75.769942 -487.323632) (xy 75.731996 -487.263241)
			(xy 75.701051 -487.198982) (xy 75.677494 -487.131662) (xy 75.661624 -487.062127) (xy 75.653638 -486.991253)
			(xy 74.994524 -486.991253) (xy 74.986538 -487.062127) (xy 74.970668 -487.131662) (xy 74.947111 -487.198982)
			(xy 74.916166 -487.263241) (xy 74.87822 -487.323632) (xy 74.833751 -487.379394) (xy 74.783318 -487.429827)
			(xy 74.727556 -487.474296) (xy 74.667165 -487.512242) (xy 74.602906 -487.543187) (xy 74.535586 -487.566744)
			(xy 74.466051 -487.582614) (xy 74.395177 -487.5906) (xy 74.323855 -487.5906) (xy 74.252981 -487.582614)
			(xy 74.183446 -487.566744) (xy 74.116126 -487.543187) (xy 74.051867 -487.512242) (xy 73.991476 -487.474296)
			(xy 73.935714 -487.429827) (xy 73.885281 -487.379394) (xy 73.840812 -487.323632) (xy 73.802866 -487.263241)
			(xy 73.771921 -487.198982) (xy 73.748364 -487.131662) (xy 73.732494 -487.062127) (xy 73.724508 -486.991253)
			(xy 25.02154 -486.991253) (xy 25.02154 -488.757823) (xy 73.724508 -488.757823) (xy 73.724508 -488.686501)
			(xy 73.732494 -488.615627) (xy 73.748364 -488.546092) (xy 73.771921 -488.478772) (xy 73.802866 -488.414513)
			(xy 73.840812 -488.354122) (xy 73.885281 -488.29836) (xy 73.935714 -488.247927) (xy 73.991476 -488.203458)
			(xy 74.051867 -488.165512) (xy 74.116126 -488.134567) (xy 74.183446 -488.11101) (xy 74.252981 -488.09514)
			(xy 74.323855 -488.087154) (xy 74.359516 -488.086654) (xy 74.395177 -488.087154) (xy 74.466051 -488.09514)
			(xy 74.535586 -488.11101) (xy 74.602906 -488.134567) (xy 74.667165 -488.165512) (xy 74.727556 -488.203458)
			(xy 74.783318 -488.247927) (xy 74.833751 -488.29836) (xy 74.87822 -488.354122) (xy 74.916166 -488.414513)
			(xy 74.947111 -488.478772) (xy 74.970668 -488.546092) (xy 74.986538 -488.615627) (xy 74.994524 -488.686501)
			(xy 74.994524 -488.757823) (xy 75.653638 -488.757823) (xy 75.653638 -488.686501) (xy 75.661624 -488.615627)
			(xy 75.677494 -488.546092) (xy 75.701051 -488.478772) (xy 75.731996 -488.414513) (xy 75.769942 -488.354122)
			(xy 75.814411 -488.29836) (xy 75.864844 -488.247927) (xy 75.920606 -488.203458) (xy 75.980997 -488.165512)
			(xy 76.045256 -488.134567) (xy 76.112576 -488.11101) (xy 76.182111 -488.09514) (xy 76.252985 -488.087154)
			(xy 76.288646 -488.086654) (xy 76.324307 -488.087154) (xy 76.395181 -488.09514) (xy 76.464716 -488.11101)
			(xy 76.532036 -488.134567) (xy 76.596295 -488.165512) (xy 76.656686 -488.203458) (xy 76.712448 -488.247927)
			(xy 76.762881 -488.29836) (xy 76.80735 -488.354122) (xy 76.845296 -488.414513) (xy 76.876241 -488.478772)
			(xy 76.899798 -488.546092) (xy 76.915668 -488.615627) (xy 76.923654 -488.686501) (xy 76.923654 -488.757823)
			(xy 76.918502 -488.803543) (xy 77.397602 -488.803543) (xy 77.397602 -488.732221) (xy 77.405588 -488.661347)
			(xy 77.421458 -488.591812) (xy 77.445015 -488.524492) (xy 77.47596 -488.460233) (xy 77.513906 -488.399842)
			(xy 77.558375 -488.34408) (xy 77.608808 -488.293647) (xy 77.66457 -488.249178) (xy 77.724961 -488.211232)
			(xy 77.78922 -488.180287) (xy 77.85654 -488.15673) (xy 77.926075 -488.14086) (xy 77.996949 -488.132874)
			(xy 78.03261 -488.132374) (xy 78.068271 -488.132874) (xy 78.139145 -488.14086) (xy 78.20868 -488.15673)
			(xy 78.276 -488.180287) (xy 78.340259 -488.211232) (xy 78.40065 -488.249178) (xy 78.456412 -488.293647)
			(xy 78.506845 -488.34408) (xy 78.551314 -488.399842) (xy 78.58926 -488.460233) (xy 78.620205 -488.524492)
			(xy 78.643762 -488.591812) (xy 78.659632 -488.661347) (xy 78.667618 -488.732221) (xy 78.667618 -488.803543)
			(xy 79.326732 -488.803543) (xy 79.326732 -488.732221) (xy 79.334718 -488.661347) (xy 79.350588 -488.591812)
			(xy 79.374145 -488.524492) (xy 79.40509 -488.460233) (xy 79.443036 -488.399842) (xy 79.487505 -488.34408)
			(xy 79.537938 -488.293647) (xy 79.5937 -488.249178) (xy 79.654091 -488.211232) (xy 79.71835 -488.180287)
			(xy 79.78567 -488.15673) (xy 79.855205 -488.14086) (xy 79.926079 -488.132874) (xy 79.96174 -488.132374)
			(xy 79.997401 -488.132874) (xy 80.068275 -488.14086) (xy 80.13781 -488.15673) (xy 80.20513 -488.180287)
			(xy 80.269389 -488.211232) (xy 80.32978 -488.249178) (xy 80.365839 -488.277934) (xy 86.063581 -488.277934)
			(xy 86.069681 -488.222497) (xy 86.083787 -488.16854) (xy 86.105599 -488.117211) (xy 86.134653 -488.069605)
			(xy 86.170328 -488.026737) (xy 86.211865 -487.98952) (xy 86.258378 -487.958747) (xy 86.308875 -487.935075)
			(xy 86.362282 -487.919007) (xy 86.417458 -487.910887) (xy 86.445344 -487.910378) (xy 86.47323 -487.910887)
			(xy 86.528406 -487.919007) (xy 86.581813 -487.935075) (xy 86.63231 -487.958747) (xy 86.678823 -487.98952)
			(xy 86.72036 -488.026737) (xy 86.756035 -488.069605) (xy 86.785089 -488.117211) (xy 86.806901 -488.16854)
			(xy 86.819298 -488.215958) (xy 87.927941 -488.215958) (xy 87.934041 -488.160521) (xy 87.948147 -488.106564)
			(xy 87.969959 -488.055235) (xy 87.999013 -488.007629) (xy 88.034688 -487.964761) (xy 88.076225 -487.927544)
			(xy 88.122738 -487.896771) (xy 88.173235 -487.873099) (xy 88.226642 -487.857031) (xy 88.281818 -487.848911)
			(xy 88.309704 -487.848402) (xy 88.33759 -487.848911) (xy 88.392766 -487.857031) (xy 88.446173 -487.873099)
			(xy 88.49667 -487.896771) (xy 88.543183 -487.927544) (xy 88.58472 -487.964761) (xy 88.620395 -488.007629)
			(xy 88.649449 -488.055235) (xy 88.671261 -488.106564) (xy 88.685367 -488.160521) (xy 88.691467 -488.215958)
			(xy 88.68943 -488.271692) (xy 88.6793 -488.326535) (xy 88.661293 -488.379319) (xy 88.635792 -488.428919)
			(xy 88.603341 -488.474277) (xy 88.564632 -488.514426) (xy 88.520489 -488.548512) (xy 88.471854 -488.575808)
			(xy 88.419763 -488.595731) (xy 88.365326 -488.607857) (xy 88.309704 -488.611928) (xy 88.254082 -488.607857)
			(xy 88.199645 -488.595731) (xy 88.147554 -488.575808) (xy 88.098919 -488.548512) (xy 88.054776 -488.514426)
			(xy 88.016067 -488.474277) (xy 87.983616 -488.428919) (xy 87.958115 -488.379319) (xy 87.940108 -488.326535)
			(xy 87.929978 -488.271692) (xy 87.927941 -488.215958) (xy 86.819298 -488.215958) (xy 86.821007 -488.222497)
			(xy 86.827107 -488.277934) (xy 86.82507 -488.333668) (xy 86.81494 -488.388511) (xy 86.796933 -488.441295)
			(xy 86.771432 -488.490895) (xy 86.738981 -488.536253) (xy 86.700272 -488.576402) (xy 86.656129 -488.610488)
			(xy 86.607494 -488.637784) (xy 86.555403 -488.657707) (xy 86.500966 -488.669833) (xy 86.445344 -488.673904)
			(xy 86.389722 -488.669833) (xy 86.335285 -488.657707) (xy 86.283194 -488.637784) (xy 86.234559 -488.610488)
			(xy 86.190416 -488.576402) (xy 86.151707 -488.536253) (xy 86.119256 -488.490895) (xy 86.093755 -488.441295)
			(xy 86.075748 -488.388511) (xy 86.065618 -488.333668) (xy 86.063581 -488.277934) (xy 80.365839 -488.277934)
			(xy 80.385542 -488.293647) (xy 80.435975 -488.34408) (xy 80.480444 -488.399842) (xy 80.51839 -488.460233)
			(xy 80.549335 -488.524492) (xy 80.572892 -488.591812) (xy 80.588762 -488.661347) (xy 80.596748 -488.732221)
			(xy 80.596748 -488.803543) (xy 80.588762 -488.874417) (xy 80.572892 -488.943952) (xy 80.549335 -489.011272)
			(xy 80.51839 -489.075531) (xy 80.480444 -489.135922) (xy 80.435975 -489.191684) (xy 80.385542 -489.242117)
			(xy 80.32978 -489.286586) (xy 80.269389 -489.324532) (xy 80.20513 -489.355477) (xy 80.13781 -489.379034)
			(xy 80.089999 -489.389946) (xy 84.047583 -489.389946) (xy 84.053683 -489.334509) (xy 84.067789 -489.280552)
			(xy 84.089601 -489.229223) (xy 84.118655 -489.181617) (xy 84.15433 -489.138749) (xy 84.195867 -489.101532)
			(xy 84.24238 -489.070759) (xy 84.292877 -489.047087) (xy 84.346284 -489.031019) (xy 84.40146 -489.022899)
			(xy 84.429346 -489.02239) (xy 84.457232 -489.022899) (xy 84.512408 -489.031019) (xy 84.565815 -489.047087)
			(xy 84.616312 -489.070759) (xy 84.662825 -489.101532) (xy 84.704362 -489.138749) (xy 84.740037 -489.181617)
			(xy 84.769091 -489.229223) (xy 84.790903 -489.280552) (xy 84.805009 -489.334509) (xy 84.811109 -489.389946)
			(xy 84.809072 -489.44568) (xy 84.798942 -489.500523) (xy 84.780935 -489.553307) (xy 84.755751 -489.60229)
			(xy 85.548723 -489.60229) (xy 85.554823 -489.546853) (xy 85.568929 -489.492896) (xy 85.590741 -489.441567)
			(xy 85.619795 -489.393961) (xy 85.65547 -489.351093) (xy 85.697007 -489.313876) (xy 85.74352 -489.283103)
			(xy 85.794017 -489.259431) (xy 85.847424 -489.243363) (xy 85.9026 -489.235243) (xy 85.930486 -489.234734)
			(xy 85.958372 -489.235243) (xy 86.013548 -489.243363) (xy 86.066955 -489.259431) (xy 86.117452 -489.283103)
			(xy 86.163965 -489.313876) (xy 86.205502 -489.351093) (xy 86.241177 -489.393961) (xy 86.270231 -489.441567)
			(xy 86.292043 -489.492896) (xy 86.306149 -489.546853) (xy 86.312249 -489.60229) (xy 86.310212 -489.658024)
			(xy 86.300082 -489.712867) (xy 86.282075 -489.765651) (xy 86.256574 -489.815251) (xy 86.224123 -489.860609)
			(xy 86.185414 -489.900758) (xy 86.141271 -489.934844) (xy 86.092636 -489.96214) (xy 86.040545 -489.982063)
			(xy 85.986108 -489.994189) (xy 85.930486 -489.99826) (xy 85.874864 -489.994189) (xy 85.820427 -489.982063)
			(xy 85.768336 -489.96214) (xy 85.719701 -489.934844) (xy 85.675558 -489.900758) (xy 85.636849 -489.860609)
			(xy 85.604398 -489.815251) (xy 85.578897 -489.765651) (xy 85.56089 -489.712867) (xy 85.55076 -489.658024)
			(xy 85.548723 -489.60229) (xy 84.755751 -489.60229) (xy 84.755434 -489.602907) (xy 84.722983 -489.648265)
			(xy 84.684274 -489.688414) (xy 84.640131 -489.7225) (xy 84.591496 -489.749796) (xy 84.539405 -489.769719)
			(xy 84.484968 -489.781845) (xy 84.429346 -489.785916) (xy 84.373724 -489.781845) (xy 84.319287 -489.769719)
			(xy 84.267196 -489.749796) (xy 84.218561 -489.7225) (xy 84.174418 -489.688414) (xy 84.135709 -489.648265)
			(xy 84.103258 -489.602907) (xy 84.077757 -489.553307) (xy 84.05975 -489.500523) (xy 84.04962 -489.44568)
			(xy 84.047583 -489.389946) (xy 80.089999 -489.389946) (xy 80.068275 -489.394904) (xy 79.997401 -489.40289)
			(xy 79.926079 -489.40289) (xy 79.855205 -489.394904) (xy 79.78567 -489.379034) (xy 79.71835 -489.355477)
			(xy 79.654091 -489.324532) (xy 79.5937 -489.286586) (xy 79.537938 -489.242117) (xy 79.487505 -489.191684)
			(xy 79.443036 -489.135922) (xy 79.40509 -489.075531) (xy 79.374145 -489.011272) (xy 79.350588 -488.943952)
			(xy 79.334718 -488.874417) (xy 79.326732 -488.803543) (xy 78.667618 -488.803543) (xy 78.659632 -488.874417)
			(xy 78.643762 -488.943952) (xy 78.620205 -489.011272) (xy 78.58926 -489.075531) (xy 78.551314 -489.135922)
			(xy 78.506845 -489.191684) (xy 78.456412 -489.242117) (xy 78.40065 -489.286586) (xy 78.340259 -489.324532)
			(xy 78.276 -489.355477) (xy 78.20868 -489.379034) (xy 78.139145 -489.394904) (xy 78.068271 -489.40289)
			(xy 77.996949 -489.40289) (xy 77.926075 -489.394904) (xy 77.85654 -489.379034) (xy 77.78922 -489.355477)
			(xy 77.724961 -489.324532) (xy 77.66457 -489.286586) (xy 77.608808 -489.242117) (xy 77.558375 -489.191684)
			(xy 77.513906 -489.135922) (xy 77.47596 -489.075531) (xy 77.445015 -489.011272) (xy 77.421458 -488.943952)
			(xy 77.405588 -488.874417) (xy 77.397602 -488.803543) (xy 76.918502 -488.803543) (xy 76.915668 -488.828697)
			(xy 76.899798 -488.898232) (xy 76.876241 -488.965552) (xy 76.845296 -489.029811) (xy 76.80735 -489.090202)
			(xy 76.762881 -489.145964) (xy 76.712448 -489.196397) (xy 76.656686 -489.240866) (xy 76.596295 -489.278812)
			(xy 76.532036 -489.309757) (xy 76.464716 -489.333314) (xy 76.395181 -489.349184) (xy 76.324307 -489.35717)
			(xy 76.252985 -489.35717) (xy 76.182111 -489.349184) (xy 76.112576 -489.333314) (xy 76.045256 -489.309757)
			(xy 75.980997 -489.278812) (xy 75.920606 -489.240866) (xy 75.864844 -489.196397) (xy 75.814411 -489.145964)
			(xy 75.769942 -489.090202) (xy 75.731996 -489.029811) (xy 75.701051 -488.965552) (xy 75.677494 -488.898232)
			(xy 75.661624 -488.828697) (xy 75.653638 -488.757823) (xy 74.994524 -488.757823) (xy 74.986538 -488.828697)
			(xy 74.970668 -488.898232) (xy 74.947111 -488.965552) (xy 74.916166 -489.029811) (xy 74.87822 -489.090202)
			(xy 74.833751 -489.145964) (xy 74.783318 -489.196397) (xy 74.727556 -489.240866) (xy 74.667165 -489.278812)
			(xy 74.602906 -489.309757) (xy 74.535586 -489.333314) (xy 74.466051 -489.349184) (xy 74.395177 -489.35717)
			(xy 74.323855 -489.35717) (xy 74.252981 -489.349184) (xy 74.183446 -489.333314) (xy 74.116126 -489.309757)
			(xy 74.051867 -489.278812) (xy 73.991476 -489.240866) (xy 73.935714 -489.196397) (xy 73.885281 -489.145964)
			(xy 73.840812 -489.090202) (xy 73.802866 -489.029811) (xy 73.771921 -488.965552) (xy 73.748364 -488.898232)
			(xy 73.732494 -488.828697) (xy 73.724508 -488.757823) (xy 25.02154 -488.757823) (xy 25.02154 -495.831042)
			(xy 39.818314 -495.831042) (xy 39.824323 -495.715104) (xy 39.838316 -495.599857) (xy 39.860227 -495.485851)
			(xy 39.889952 -495.373627) (xy 39.927348 -495.263721) (xy 39.972237 -495.156658) (xy 40.024406 -495.052946)
			(xy 40.083606 -494.953081) (xy 40.149555 -494.857538) (xy 40.221938 -494.766772) (xy 40.300411 -494.681217)
			(xy 40.384599 -494.601279) (xy 40.474101 -494.52734) (xy 40.568492 -494.459752) (xy 40.66732 -494.398838)
			(xy 40.770116 -494.344886) (xy 40.876389 -494.298156) (xy 40.985633 -494.258868) (xy 41.097326 -494.227211)
			(xy 41.210938 -494.203335) (xy 41.325926 -494.187354) (xy 41.441743 -494.179345) (xy 41.49979 -494.178844)
			(xy 41.557837 -494.179345) (xy 41.673654 -494.187354) (xy 41.788642 -494.203335) (xy 41.902254 -494.227211)
			(xy 42.013947 -494.258868) (xy 42.123191 -494.298156) (xy 42.229464 -494.344886) (xy 42.33226 -494.398838)
			(xy 42.431088 -494.459752) (xy 42.474869 -494.491101) (xy 63.647829 -494.491101) (xy 63.653878 -494.415531)
			(xy 63.667925 -494.341033) (xy 63.689811 -494.26845) (xy 63.719288 -494.198604) (xy 63.756023 -494.132287)
			(xy 63.799598 -494.070251) (xy 63.84952 -494.013198) (xy 63.905224 -493.961774) (xy 63.966079 -493.916563)
			(xy 64.031394 -493.878076) (xy 64.10043 -493.84675) (xy 64.172405 -493.82294) (xy 64.246503 -493.806915)
			(xy 64.321884 -493.798856) (xy 64.35979 -493.798352) (xy 64.397696 -493.798856) (xy 64.473077 -493.806915)
			(xy 64.547175 -493.82294) (xy 64.61915 -493.84675) (xy 64.688186 -493.878076) (xy 64.753501 -493.916563)
			(xy 64.814356 -493.961774) (xy 64.87006 -494.013198) (xy 64.919982 -494.070251) (xy 64.963557 -494.132287)
			(xy 65.000292 -494.198604) (xy 65.029769 -494.26845) (xy 65.051655 -494.341033) (xy 65.065702 -494.415531)
			(xy 65.071751 -494.491101) (xy 66.187829 -494.491101) (xy 66.193878 -494.415531) (xy 66.207925 -494.341033)
			(xy 66.229811 -494.26845) (xy 66.259288 -494.198604) (xy 66.296023 -494.132287) (xy 66.339598 -494.070251)
			(xy 66.38952 -494.013198) (xy 66.445224 -493.961774) (xy 66.506079 -493.916563) (xy 66.571394 -493.878076)
			(xy 66.64043 -493.84675) (xy 66.712405 -493.82294) (xy 66.786503 -493.806915) (xy 66.861884 -493.798856)
			(xy 66.89979 -493.798352) (xy 66.937696 -493.798856) (xy 67.013077 -493.806915) (xy 67.087175 -493.82294)
			(xy 67.15915 -493.84675) (xy 67.228186 -493.878076) (xy 67.293501 -493.916563) (xy 67.354356 -493.961774)
			(xy 67.41006 -494.013198) (xy 67.459982 -494.070251) (xy 67.503557 -494.132287) (xy 67.540292 -494.198604)
			(xy 67.569769 -494.26845) (xy 67.591655 -494.341033) (xy 67.605702 -494.415531) (xy 67.611751 -494.491101)
			(xy 68.727829 -494.491101) (xy 68.733878 -494.415531) (xy 68.747925 -494.341033) (xy 68.769811 -494.26845)
			(xy 68.799288 -494.198604) (xy 68.836023 -494.132287) (xy 68.879598 -494.070251) (xy 68.92952 -494.013198)
			(xy 68.985224 -493.961774) (xy 69.046079 -493.916563) (xy 69.111394 -493.878076) (xy 69.18043 -493.84675)
			(xy 69.252405 -493.82294) (xy 69.326503 -493.806915) (xy 69.401884 -493.798856) (xy 69.43979 -493.798352)
			(xy 69.477696 -493.798856) (xy 69.553077 -493.806915) (xy 69.627175 -493.82294) (xy 69.69915 -493.84675)
			(xy 69.768186 -493.878076) (xy 69.833501 -493.916563) (xy 69.894356 -493.961774) (xy 69.95006 -494.013198)
			(xy 69.999982 -494.070251) (xy 70.043557 -494.132287) (xy 70.080292 -494.198604) (xy 70.109769 -494.26845)
			(xy 70.131655 -494.341033) (xy 70.145702 -494.415531) (xy 70.151751 -494.491101) (xy 71.267829 -494.491101)
			(xy 71.273878 -494.415531) (xy 71.287925 -494.341033) (xy 71.309811 -494.26845) (xy 71.339288 -494.198604)
			(xy 71.376023 -494.132287) (xy 71.419598 -494.070251) (xy 71.46952 -494.013198) (xy 71.525224 -493.961774)
			(xy 71.586079 -493.916563) (xy 71.651394 -493.878076) (xy 71.72043 -493.84675) (xy 71.792405 -493.82294)
			(xy 71.866503 -493.806915) (xy 71.941884 -493.798856) (xy 71.97979 -493.798352) (xy 72.017696 -493.798856)
			(xy 72.093077 -493.806915) (xy 72.167175 -493.82294) (xy 72.23915 -493.84675) (xy 72.308186 -493.878076)
			(xy 72.373501 -493.916563) (xy 72.434356 -493.961774) (xy 72.49006 -494.013198) (xy 72.539982 -494.070251)
			(xy 72.583557 -494.132287) (xy 72.620292 -494.198604) (xy 72.649769 -494.26845) (xy 72.671655 -494.341033)
			(xy 72.685702 -494.415531) (xy 72.691751 -494.491101) (xy 73.807829 -494.491101) (xy 73.813878 -494.415531)
			(xy 73.827925 -494.341033) (xy 73.849811 -494.26845) (xy 73.879288 -494.198604) (xy 73.916023 -494.132287)
			(xy 73.959598 -494.070251) (xy 74.00952 -494.013198) (xy 74.065224 -493.961774) (xy 74.126079 -493.916563)
			(xy 74.191394 -493.878076) (xy 74.26043 -493.84675) (xy 74.332405 -493.82294) (xy 74.406503 -493.806915)
			(xy 74.481884 -493.798856) (xy 74.51979 -493.798352) (xy 74.557696 -493.798856) (xy 74.633077 -493.806915)
			(xy 74.707175 -493.82294) (xy 74.77915 -493.84675) (xy 74.848186 -493.878076) (xy 74.913501 -493.916563)
			(xy 74.974356 -493.961774) (xy 75.03006 -494.013198) (xy 75.079982 -494.070251) (xy 75.123557 -494.132287)
			(xy 75.160292 -494.198604) (xy 75.189769 -494.26845) (xy 75.211655 -494.341033) (xy 75.225702 -494.415531)
			(xy 75.231751 -494.491101) (xy 76.347829 -494.491101) (xy 76.353878 -494.415531) (xy 76.367925 -494.341033)
			(xy 76.389811 -494.26845) (xy 76.419288 -494.198604) (xy 76.456023 -494.132287) (xy 76.499598 -494.070251)
			(xy 76.54952 -494.013198) (xy 76.605224 -493.961774) (xy 76.666079 -493.916563) (xy 76.731394 -493.878076)
			(xy 76.80043 -493.84675) (xy 76.872405 -493.82294) (xy 76.946503 -493.806915) (xy 77.021884 -493.798856)
			(xy 77.05979 -493.798352) (xy 77.097696 -493.798856) (xy 77.173077 -493.806915) (xy 77.247175 -493.82294)
			(xy 77.31915 -493.84675) (xy 77.388186 -493.878076) (xy 77.453501 -493.916563) (xy 77.514356 -493.961774)
			(xy 77.57006 -494.013198) (xy 77.619982 -494.070251) (xy 77.663557 -494.132287) (xy 77.700292 -494.198604)
			(xy 77.729769 -494.26845) (xy 77.751655 -494.341033) (xy 77.765702 -494.415531) (xy 77.771751 -494.491101)
			(xy 78.887829 -494.491101) (xy 78.893878 -494.415531) (xy 78.907925 -494.341033) (xy 78.929811 -494.26845)
			(xy 78.959288 -494.198604) (xy 78.996023 -494.132287) (xy 79.039598 -494.070251) (xy 79.08952 -494.013198)
			(xy 79.145224 -493.961774) (xy 79.206079 -493.916563) (xy 79.271394 -493.878076) (xy 79.34043 -493.84675)
			(xy 79.412405 -493.82294) (xy 79.486503 -493.806915) (xy 79.561884 -493.798856) (xy 79.59979 -493.798352)
			(xy 79.637696 -493.798856) (xy 79.713077 -493.806915) (xy 79.787175 -493.82294) (xy 79.85915 -493.84675)
			(xy 79.928186 -493.878076) (xy 79.993501 -493.916563) (xy 80.054356 -493.961774) (xy 80.11006 -494.013198)
			(xy 80.159982 -494.070251) (xy 80.203557 -494.132287) (xy 80.240292 -494.198604) (xy 80.269769 -494.26845)
			(xy 80.291655 -494.341033) (xy 80.305702 -494.415531) (xy 80.311751 -494.491101) (xy 81.427829 -494.491101)
			(xy 81.433878 -494.415531) (xy 81.447925 -494.341033) (xy 81.469811 -494.26845) (xy 81.499288 -494.198604)
			(xy 81.536023 -494.132287) (xy 81.579598 -494.070251) (xy 81.62952 -494.013198) (xy 81.685224 -493.961774)
			(xy 81.746079 -493.916563) (xy 81.811394 -493.878076) (xy 81.88043 -493.84675) (xy 81.952405 -493.82294)
			(xy 82.026503 -493.806915) (xy 82.101884 -493.798856) (xy 82.13979 -493.798352) (xy 82.177696 -493.798856)
			(xy 82.253077 -493.806915) (xy 82.327175 -493.82294) (xy 82.39915 -493.84675) (xy 82.468186 -493.878076)
			(xy 82.533501 -493.916563) (xy 82.594356 -493.961774) (xy 82.65006 -494.013198) (xy 82.699982 -494.070251)
			(xy 82.743557 -494.132287) (xy 82.780292 -494.198604) (xy 82.809769 -494.26845) (xy 82.831655 -494.341033)
			(xy 82.845702 -494.415531) (xy 82.851751 -494.491101) (xy 82.849732 -494.566885) (xy 82.83967 -494.642025)
			(xy 82.821678 -494.71567) (xy 82.79596 -494.786986) (xy 82.762808 -494.855163) (xy 82.722596 -494.919431)
			(xy 82.675781 -494.97906) (xy 82.622893 -495.033376) (xy 82.564531 -495.081762) (xy 82.501356 -495.12367)
			(xy 82.434085 -495.158626) (xy 82.36348 -495.186233) (xy 82.290339 -495.206179) (xy 82.215494 -495.218238)
			(xy 82.13979 -495.222273) (xy 82.064086 -495.218238) (xy 81.989241 -495.206179) (xy 81.9161 -495.186233)
			(xy 81.845495 -495.158626) (xy 81.778224 -495.12367) (xy 81.715049 -495.081762) (xy 81.656687 -495.033376)
			(xy 81.603799 -494.97906) (xy 81.556984 -494.919431) (xy 81.516772 -494.855163) (xy 81.48362 -494.786986)
			(xy 81.457902 -494.71567) (xy 81.43991 -494.642025) (xy 81.429848 -494.566885) (xy 81.427829 -494.491101)
			(xy 80.311751 -494.491101) (xy 80.309732 -494.566885) (xy 80.29967 -494.642025) (xy 80.281678 -494.71567)
			(xy 80.25596 -494.786986) (xy 80.222808 -494.855163) (xy 80.182596 -494.919431) (xy 80.135781 -494.97906)
			(xy 80.082893 -495.033376) (xy 80.024531 -495.081762) (xy 79.961356 -495.12367) (xy 79.894085 -495.158626)
			(xy 79.82348 -495.186233) (xy 79.750339 -495.206179) (xy 79.675494 -495.218238) (xy 79.59979 -495.222273)
			(xy 79.524086 -495.218238) (xy 79.449241 -495.206179) (xy 79.3761 -495.186233) (xy 79.305495 -495.158626)
			(xy 79.238224 -495.12367) (xy 79.175049 -495.081762) (xy 79.116687 -495.033376) (xy 79.063799 -494.97906)
			(xy 79.016984 -494.919431) (xy 78.976772 -494.855163) (xy 78.94362 -494.786986) (xy 78.917902 -494.71567)
			(xy 78.89991 -494.642025) (xy 78.889848 -494.566885) (xy 78.887829 -494.491101) (xy 77.771751 -494.491101)
			(xy 77.769732 -494.566885) (xy 77.75967 -494.642025) (xy 77.741678 -494.71567) (xy 77.71596 -494.786986)
			(xy 77.682808 -494.855163) (xy 77.642596 -494.919431) (xy 77.595781 -494.97906) (xy 77.542893 -495.033376)
			(xy 77.484531 -495.081762) (xy 77.421356 -495.12367) (xy 77.354085 -495.158626) (xy 77.28348 -495.186233)
			(xy 77.210339 -495.206179) (xy 77.135494 -495.218238) (xy 77.05979 -495.222273) (xy 76.984086 -495.218238)
			(xy 76.909241 -495.206179) (xy 76.8361 -495.186233) (xy 76.765495 -495.158626) (xy 76.698224 -495.12367)
			(xy 76.635049 -495.081762) (xy 76.576687 -495.033376) (xy 76.523799 -494.97906) (xy 76.476984 -494.919431)
			(xy 76.436772 -494.855163) (xy 76.40362 -494.786986) (xy 76.377902 -494.71567) (xy 76.35991 -494.642025)
			(xy 76.349848 -494.566885) (xy 76.347829 -494.491101) (xy 75.231751 -494.491101) (xy 75.229732 -494.566885)
			(xy 75.21967 -494.642025) (xy 75.201678 -494.71567) (xy 75.17596 -494.786986) (xy 75.142808 -494.855163)
			(xy 75.102596 -494.919431) (xy 75.055781 -494.97906) (xy 75.002893 -495.033376) (xy 74.944531 -495.081762)
			(xy 74.881356 -495.12367) (xy 74.814085 -495.158626) (xy 74.74348 -495.186233) (xy 74.670339 -495.206179)
			(xy 74.595494 -495.218238) (xy 74.51979 -495.222273) (xy 74.444086 -495.218238) (xy 74.369241 -495.206179)
			(xy 74.2961 -495.186233) (xy 74.225495 -495.158626) (xy 74.158224 -495.12367) (xy 74.095049 -495.081762)
			(xy 74.036687 -495.033376) (xy 73.983799 -494.97906) (xy 73.936984 -494.919431) (xy 73.896772 -494.855163)
			(xy 73.86362 -494.786986) (xy 73.837902 -494.71567) (xy 73.81991 -494.642025) (xy 73.809848 -494.566885)
			(xy 73.807829 -494.491101) (xy 72.691751 -494.491101) (xy 72.689732 -494.566885) (xy 72.67967 -494.642025)
			(xy 72.661678 -494.71567) (xy 72.63596 -494.786986) (xy 72.602808 -494.855163) (xy 72.562596 -494.919431)
			(xy 72.515781 -494.97906) (xy 72.462893 -495.033376) (xy 72.404531 -495.081762) (xy 72.341356 -495.12367)
			(xy 72.274085 -495.158626) (xy 72.20348 -495.186233) (xy 72.130339 -495.206179) (xy 72.055494 -495.218238)
			(xy 71.97979 -495.222273) (xy 71.904086 -495.218238) (xy 71.829241 -495.206179) (xy 71.7561 -495.186233)
			(xy 71.685495 -495.158626) (xy 71.618224 -495.12367) (xy 71.555049 -495.081762) (xy 71.496687 -495.033376)
			(xy 71.443799 -494.97906) (xy 71.396984 -494.919431) (xy 71.356772 -494.855163) (xy 71.32362 -494.786986)
			(xy 71.297902 -494.71567) (xy 71.27991 -494.642025) (xy 71.269848 -494.566885) (xy 71.267829 -494.491101)
			(xy 70.151751 -494.491101) (xy 70.149732 -494.566885) (xy 70.13967 -494.642025) (xy 70.121678 -494.71567)
			(xy 70.09596 -494.786986) (xy 70.062808 -494.855163) (xy 70.022596 -494.919431) (xy 69.975781 -494.97906)
			(xy 69.922893 -495.033376) (xy 69.864531 -495.081762) (xy 69.801356 -495.12367) (xy 69.734085 -495.158626)
			(xy 69.66348 -495.186233) (xy 69.590339 -495.206179) (xy 69.515494 -495.218238) (xy 69.43979 -495.222273)
			(xy 69.364086 -495.218238) (xy 69.289241 -495.206179) (xy 69.2161 -495.186233) (xy 69.145495 -495.158626)
			(xy 69.078224 -495.12367) (xy 69.015049 -495.081762) (xy 68.956687 -495.033376) (xy 68.903799 -494.97906)
			(xy 68.856984 -494.919431) (xy 68.816772 -494.855163) (xy 68.78362 -494.786986) (xy 68.757902 -494.71567)
			(xy 68.73991 -494.642025) (xy 68.729848 -494.566885) (xy 68.727829 -494.491101) (xy 67.611751 -494.491101)
			(xy 67.609732 -494.566885) (xy 67.59967 -494.642025) (xy 67.581678 -494.71567) (xy 67.55596 -494.786986)
			(xy 67.522808 -494.855163) (xy 67.482596 -494.919431) (xy 67.435781 -494.97906) (xy 67.382893 -495.033376)
			(xy 67.324531 -495.081762) (xy 67.261356 -495.12367) (xy 67.194085 -495.158626) (xy 67.12348 -495.186233)
			(xy 67.050339 -495.206179) (xy 66.975494 -495.218238) (xy 66.89979 -495.222273) (xy 66.824086 -495.218238)
			(xy 66.749241 -495.206179) (xy 66.6761 -495.186233) (xy 66.605495 -495.158626) (xy 66.538224 -495.12367)
			(xy 66.475049 -495.081762) (xy 66.416687 -495.033376) (xy 66.363799 -494.97906) (xy 66.316984 -494.919431)
			(xy 66.276772 -494.855163) (xy 66.24362 -494.786986) (xy 66.217902 -494.71567) (xy 66.19991 -494.642025)
			(xy 66.189848 -494.566885) (xy 66.187829 -494.491101) (xy 65.071751 -494.491101) (xy 65.069732 -494.566885)
			(xy 65.05967 -494.642025) (xy 65.041678 -494.71567) (xy 65.01596 -494.786986) (xy 64.982808 -494.855163)
			(xy 64.942596 -494.919431) (xy 64.895781 -494.97906) (xy 64.842893 -495.033376) (xy 64.784531 -495.081762)
			(xy 64.721356 -495.12367) (xy 64.654085 -495.158626) (xy 64.58348 -495.186233) (xy 64.510339 -495.206179)
			(xy 64.435494 -495.218238) (xy 64.35979 -495.222273) (xy 64.284086 -495.218238) (xy 64.209241 -495.206179)
			(xy 64.1361 -495.186233) (xy 64.065495 -495.158626) (xy 63.998224 -495.12367) (xy 63.935049 -495.081762)
			(xy 63.876687 -495.033376) (xy 63.823799 -494.97906) (xy 63.776984 -494.919431) (xy 63.736772 -494.855163)
			(xy 63.70362 -494.786986) (xy 63.677902 -494.71567) (xy 63.65991 -494.642025) (xy 63.649848 -494.566885)
			(xy 63.647829 -494.491101) (xy 42.474869 -494.491101) (xy 42.525479 -494.52734) (xy 42.614981 -494.601279)
			(xy 42.699169 -494.681217) (xy 42.777642 -494.766772) (xy 42.850025 -494.857538) (xy 42.915974 -494.953081)
			(xy 42.975174 -495.052946) (xy 43.027343 -495.156658) (xy 43.072232 -495.263721) (xy 43.109628 -495.373627)
			(xy 43.139353 -495.485851) (xy 43.161264 -495.599857) (xy 43.175257 -495.715104) (xy 43.181266 -495.831042)
			(xy 43.179263 -495.947118) (xy 43.169255 -496.06278) (xy 43.151292 -496.177475) (xy 43.125459 -496.290658)
			(xy 43.091879 -496.401789) (xy 43.050711 -496.510338) (xy 43.002153 -496.615788) (xy 42.946436 -496.717637)
			(xy 42.883824 -496.8154) (xy 42.814617 -496.90861) (xy 42.739144 -496.996823) (xy 42.657765 -497.079619)
			(xy 42.570868 -497.156603) (xy 42.526017 -497.191121) (xy 63.647829 -497.191121) (xy 63.653878 -497.115551)
			(xy 63.667925 -497.041053) (xy 63.689811 -496.96847) (xy 63.719288 -496.898624) (xy 63.756023 -496.832307)
			(xy 63.799598 -496.770271) (xy 63.84952 -496.713218) (xy 63.905224 -496.661794) (xy 63.966079 -496.616583)
			(xy 64.031394 -496.578096) (xy 64.10043 -496.54677) (xy 64.172405 -496.52296) (xy 64.246503 -496.506935)
			(xy 64.321884 -496.498876) (xy 64.35979 -496.498372) (xy 64.397696 -496.498876) (xy 64.473077 -496.506935)
			(xy 64.547175 -496.52296) (xy 64.61915 -496.54677) (xy 64.688186 -496.578096) (xy 64.753501 -496.616583)
			(xy 64.814356 -496.661794) (xy 64.87006 -496.713218) (xy 64.919982 -496.770271) (xy 64.963557 -496.832307)
			(xy 65.000292 -496.898624) (xy 65.029769 -496.96847) (xy 65.051655 -497.041053) (xy 65.065702 -497.115551)
			(xy 65.071751 -497.191121) (xy 66.187829 -497.191121) (xy 66.193878 -497.115551) (xy 66.207925 -497.041053)
			(xy 66.229811 -496.96847) (xy 66.259288 -496.898624) (xy 66.296023 -496.832307) (xy 66.339598 -496.770271)
			(xy 66.38952 -496.713218) (xy 66.445224 -496.661794) (xy 66.506079 -496.616583) (xy 66.571394 -496.578096)
			(xy 66.64043 -496.54677) (xy 66.712405 -496.52296) (xy 66.786503 -496.506935) (xy 66.861884 -496.498876)
			(xy 66.89979 -496.498372) (xy 66.937696 -496.498876) (xy 67.013077 -496.506935) (xy 67.087175 -496.52296)
			(xy 67.15915 -496.54677) (xy 67.228186 -496.578096) (xy 67.293501 -496.616583) (xy 67.354356 -496.661794)
			(xy 67.41006 -496.713218) (xy 67.459982 -496.770271) (xy 67.503557 -496.832307) (xy 67.540292 -496.898624)
			(xy 67.569769 -496.96847) (xy 67.591655 -497.041053) (xy 67.605702 -497.115551) (xy 67.611751 -497.191121)
			(xy 68.727829 -497.191121) (xy 68.733878 -497.115551) (xy 68.747925 -497.041053) (xy 68.769811 -496.96847)
			(xy 68.799288 -496.898624) (xy 68.836023 -496.832307) (xy 68.879598 -496.770271) (xy 68.92952 -496.713218)
			(xy 68.985224 -496.661794) (xy 69.046079 -496.616583) (xy 69.111394 -496.578096) (xy 69.18043 -496.54677)
			(xy 69.252405 -496.52296) (xy 69.326503 -496.506935) (xy 69.401884 -496.498876) (xy 69.43979 -496.498372)
			(xy 69.477696 -496.498876) (xy 69.553077 -496.506935) (xy 69.627175 -496.52296) (xy 69.69915 -496.54677)
			(xy 69.768186 -496.578096) (xy 69.833501 -496.616583) (xy 69.894356 -496.661794) (xy 69.95006 -496.713218)
			(xy 69.999982 -496.770271) (xy 70.043557 -496.832307) (xy 70.080292 -496.898624) (xy 70.109769 -496.96847)
			(xy 70.131655 -497.041053) (xy 70.145702 -497.115551) (xy 70.151751 -497.191121) (xy 71.267829 -497.191121)
			(xy 71.273878 -497.115551) (xy 71.287925 -497.041053) (xy 71.309811 -496.96847) (xy 71.339288 -496.898624)
			(xy 71.376023 -496.832307) (xy 71.419598 -496.770271) (xy 71.46952 -496.713218) (xy 71.525224 -496.661794)
			(xy 71.586079 -496.616583) (xy 71.651394 -496.578096) (xy 71.72043 -496.54677) (xy 71.792405 -496.52296)
			(xy 71.866503 -496.506935) (xy 71.941884 -496.498876) (xy 71.97979 -496.498372) (xy 72.017696 -496.498876)
			(xy 72.093077 -496.506935) (xy 72.167175 -496.52296) (xy 72.23915 -496.54677) (xy 72.308186 -496.578096)
			(xy 72.373501 -496.616583) (xy 72.434356 -496.661794) (xy 72.49006 -496.713218) (xy 72.539982 -496.770271)
			(xy 72.583557 -496.832307) (xy 72.620292 -496.898624) (xy 72.649769 -496.96847) (xy 72.671655 -497.041053)
			(xy 72.685702 -497.115551) (xy 72.691751 -497.191121) (xy 73.807829 -497.191121) (xy 73.813878 -497.115551)
			(xy 73.827925 -497.041053) (xy 73.849811 -496.96847) (xy 73.879288 -496.898624) (xy 73.916023 -496.832307)
			(xy 73.959598 -496.770271) (xy 74.00952 -496.713218) (xy 74.065224 -496.661794) (xy 74.126079 -496.616583)
			(xy 74.191394 -496.578096) (xy 74.26043 -496.54677) (xy 74.332405 -496.52296) (xy 74.406503 -496.506935)
			(xy 74.481884 -496.498876) (xy 74.51979 -496.498372) (xy 74.557696 -496.498876) (xy 74.633077 -496.506935)
			(xy 74.707175 -496.52296) (xy 74.77915 -496.54677) (xy 74.848186 -496.578096) (xy 74.913501 -496.616583)
			(xy 74.974356 -496.661794) (xy 75.03006 -496.713218) (xy 75.079982 -496.770271) (xy 75.123557 -496.832307)
			(xy 75.160292 -496.898624) (xy 75.189769 -496.96847) (xy 75.211655 -497.041053) (xy 75.225702 -497.115551)
			(xy 75.231751 -497.191121) (xy 76.347829 -497.191121) (xy 76.353878 -497.115551) (xy 76.367925 -497.041053)
			(xy 76.389811 -496.96847) (xy 76.419288 -496.898624) (xy 76.456023 -496.832307) (xy 76.499598 -496.770271)
			(xy 76.54952 -496.713218) (xy 76.605224 -496.661794) (xy 76.666079 -496.616583) (xy 76.731394 -496.578096)
			(xy 76.80043 -496.54677) (xy 76.872405 -496.52296) (xy 76.946503 -496.506935) (xy 77.021884 -496.498876)
			(xy 77.05979 -496.498372) (xy 77.097696 -496.498876) (xy 77.173077 -496.506935) (xy 77.247175 -496.52296)
			(xy 77.31915 -496.54677) (xy 77.388186 -496.578096) (xy 77.453501 -496.616583) (xy 77.514356 -496.661794)
			(xy 77.57006 -496.713218) (xy 77.619982 -496.770271) (xy 77.663557 -496.832307) (xy 77.700292 -496.898624)
			(xy 77.729769 -496.96847) (xy 77.751655 -497.041053) (xy 77.765702 -497.115551) (xy 77.771751 -497.191121)
			(xy 78.887829 -497.191121) (xy 78.893878 -497.115551) (xy 78.907925 -497.041053) (xy 78.929811 -496.96847)
			(xy 78.959288 -496.898624) (xy 78.996023 -496.832307) (xy 79.039598 -496.770271) (xy 79.08952 -496.713218)
			(xy 79.145224 -496.661794) (xy 79.206079 -496.616583) (xy 79.271394 -496.578096) (xy 79.34043 -496.54677)
			(xy 79.412405 -496.52296) (xy 79.486503 -496.506935) (xy 79.561884 -496.498876) (xy 79.59979 -496.498372)
			(xy 79.637696 -496.498876) (xy 79.713077 -496.506935) (xy 79.787175 -496.52296) (xy 79.85915 -496.54677)
			(xy 79.928186 -496.578096) (xy 79.993501 -496.616583) (xy 80.054356 -496.661794) (xy 80.11006 -496.713218)
			(xy 80.159982 -496.770271) (xy 80.203557 -496.832307) (xy 80.240292 -496.898624) (xy 80.269769 -496.96847)
			(xy 80.291655 -497.041053) (xy 80.305702 -497.115551) (xy 80.311751 -497.191121) (xy 81.427829 -497.191121)
			(xy 81.433878 -497.115551) (xy 81.447925 -497.041053) (xy 81.469811 -496.96847) (xy 81.499288 -496.898624)
			(xy 81.536023 -496.832307) (xy 81.579598 -496.770271) (xy 81.62952 -496.713218) (xy 81.685224 -496.661794)
			(xy 81.746079 -496.616583) (xy 81.811394 -496.578096) (xy 81.88043 -496.54677) (xy 81.952405 -496.52296)
			(xy 82.026503 -496.506935) (xy 82.101884 -496.498876) (xy 82.13979 -496.498372) (xy 82.177696 -496.498876)
			(xy 82.253077 -496.506935) (xy 82.327175 -496.52296) (xy 82.39915 -496.54677) (xy 82.468186 -496.578096)
			(xy 82.533501 -496.616583) (xy 82.594356 -496.661794) (xy 82.65006 -496.713218) (xy 82.699982 -496.770271)
			(xy 82.743557 -496.832307) (xy 82.780292 -496.898624) (xy 82.809769 -496.96847) (xy 82.831655 -497.041053)
			(xy 82.845702 -497.115551) (xy 82.851751 -497.191121) (xy 82.849732 -497.266905) (xy 82.83967 -497.342045)
			(xy 82.821678 -497.41569) (xy 82.79596 -497.487006) (xy 82.762808 -497.555183) (xy 82.722596 -497.619451)
			(xy 82.675781 -497.67908) (xy 82.622893 -497.733396) (xy 82.564531 -497.781782) (xy 82.501356 -497.82369)
			(xy 82.434085 -497.858646) (xy 82.36348 -497.886253) (xy 82.290339 -497.906199) (xy 82.215494 -497.918258)
			(xy 82.13979 -497.922293) (xy 82.064086 -497.918258) (xy 81.989241 -497.906199) (xy 81.9161 -497.886253)
			(xy 81.845495 -497.858646) (xy 81.778224 -497.82369) (xy 81.715049 -497.781782) (xy 81.656687 -497.733396)
			(xy 81.603799 -497.67908) (xy 81.556984 -497.619451) (xy 81.516772 -497.555183) (xy 81.48362 -497.487006)
			(xy 81.457902 -497.41569) (xy 81.43991 -497.342045) (xy 81.429848 -497.266905) (xy 81.427829 -497.191121)
			(xy 80.311751 -497.191121) (xy 80.309732 -497.266905) (xy 80.29967 -497.342045) (xy 80.281678 -497.41569)
			(xy 80.25596 -497.487006) (xy 80.222808 -497.555183) (xy 80.182596 -497.619451) (xy 80.135781 -497.67908)
			(xy 80.082893 -497.733396) (xy 80.024531 -497.781782) (xy 79.961356 -497.82369) (xy 79.894085 -497.858646)
			(xy 79.82348 -497.886253) (xy 79.750339 -497.906199) (xy 79.675494 -497.918258) (xy 79.59979 -497.922293)
			(xy 79.524086 -497.918258) (xy 79.449241 -497.906199) (xy 79.3761 -497.886253) (xy 79.305495 -497.858646)
			(xy 79.238224 -497.82369) (xy 79.175049 -497.781782) (xy 79.116687 -497.733396) (xy 79.063799 -497.67908)
			(xy 79.016984 -497.619451) (xy 78.976772 -497.555183) (xy 78.94362 -497.487006) (xy 78.917902 -497.41569)
			(xy 78.89991 -497.342045) (xy 78.889848 -497.266905) (xy 78.887829 -497.191121) (xy 77.771751 -497.191121)
			(xy 77.769732 -497.266905) (xy 77.75967 -497.342045) (xy 77.741678 -497.41569) (xy 77.71596 -497.487006)
			(xy 77.682808 -497.555183) (xy 77.642596 -497.619451) (xy 77.595781 -497.67908) (xy 77.542893 -497.733396)
			(xy 77.484531 -497.781782) (xy 77.421356 -497.82369) (xy 77.354085 -497.858646) (xy 77.28348 -497.886253)
			(xy 77.210339 -497.906199) (xy 77.135494 -497.918258) (xy 77.05979 -497.922293) (xy 76.984086 -497.918258)
			(xy 76.909241 -497.906199) (xy 76.8361 -497.886253) (xy 76.765495 -497.858646) (xy 76.698224 -497.82369)
			(xy 76.635049 -497.781782) (xy 76.576687 -497.733396) (xy 76.523799 -497.67908) (xy 76.476984 -497.619451)
			(xy 76.436772 -497.555183) (xy 76.40362 -497.487006) (xy 76.377902 -497.41569) (xy 76.35991 -497.342045)
			(xy 76.349848 -497.266905) (xy 76.347829 -497.191121) (xy 75.231751 -497.191121) (xy 75.229732 -497.266905)
			(xy 75.21967 -497.342045) (xy 75.201678 -497.41569) (xy 75.17596 -497.487006) (xy 75.142808 -497.555183)
			(xy 75.102596 -497.619451) (xy 75.055781 -497.67908) (xy 75.002893 -497.733396) (xy 74.944531 -497.781782)
			(xy 74.881356 -497.82369) (xy 74.814085 -497.858646) (xy 74.74348 -497.886253) (xy 74.670339 -497.906199)
			(xy 74.595494 -497.918258) (xy 74.51979 -497.922293) (xy 74.444086 -497.918258) (xy 74.369241 -497.906199)
			(xy 74.2961 -497.886253) (xy 74.225495 -497.858646) (xy 74.158224 -497.82369) (xy 74.095049 -497.781782)
			(xy 74.036687 -497.733396) (xy 73.983799 -497.67908) (xy 73.936984 -497.619451) (xy 73.896772 -497.555183)
			(xy 73.86362 -497.487006) (xy 73.837902 -497.41569) (xy 73.81991 -497.342045) (xy 73.809848 -497.266905)
			(xy 73.807829 -497.191121) (xy 72.691751 -497.191121) (xy 72.689732 -497.266905) (xy 72.67967 -497.342045)
			(xy 72.661678 -497.41569) (xy 72.63596 -497.487006) (xy 72.602808 -497.555183) (xy 72.562596 -497.619451)
			(xy 72.515781 -497.67908) (xy 72.462893 -497.733396) (xy 72.404531 -497.781782) (xy 72.341356 -497.82369)
			(xy 72.274085 -497.858646) (xy 72.20348 -497.886253) (xy 72.130339 -497.906199) (xy 72.055494 -497.918258)
			(xy 71.97979 -497.922293) (xy 71.904086 -497.918258) (xy 71.829241 -497.906199) (xy 71.7561 -497.886253)
			(xy 71.685495 -497.858646) (xy 71.618224 -497.82369) (xy 71.555049 -497.781782) (xy 71.496687 -497.733396)
			(xy 71.443799 -497.67908) (xy 71.396984 -497.619451) (xy 71.356772 -497.555183) (xy 71.32362 -497.487006)
			(xy 71.297902 -497.41569) (xy 71.27991 -497.342045) (xy 71.269848 -497.266905) (xy 71.267829 -497.191121)
			(xy 70.151751 -497.191121) (xy 70.149732 -497.266905) (xy 70.13967 -497.342045) (xy 70.121678 -497.41569)
			(xy 70.09596 -497.487006) (xy 70.062808 -497.555183) (xy 70.022596 -497.619451) (xy 69.975781 -497.67908)
			(xy 69.922893 -497.733396) (xy 69.864531 -497.781782) (xy 69.801356 -497.82369) (xy 69.734085 -497.858646)
			(xy 69.66348 -497.886253) (xy 69.590339 -497.906199) (xy 69.515494 -497.918258) (xy 69.43979 -497.922293)
			(xy 69.364086 -497.918258) (xy 69.289241 -497.906199) (xy 69.2161 -497.886253) (xy 69.145495 -497.858646)
			(xy 69.078224 -497.82369) (xy 69.015049 -497.781782) (xy 68.956687 -497.733396) (xy 68.903799 -497.67908)
			(xy 68.856984 -497.619451) (xy 68.816772 -497.555183) (xy 68.78362 -497.487006) (xy 68.757902 -497.41569)
			(xy 68.73991 -497.342045) (xy 68.729848 -497.266905) (xy 68.727829 -497.191121) (xy 67.611751 -497.191121)
			(xy 67.609732 -497.266905) (xy 67.59967 -497.342045) (xy 67.581678 -497.41569) (xy 67.55596 -497.487006)
			(xy 67.522808 -497.555183) (xy 67.482596 -497.619451) (xy 67.435781 -497.67908) (xy 67.382893 -497.733396)
			(xy 67.324531 -497.781782) (xy 67.261356 -497.82369) (xy 67.194085 -497.858646) (xy 67.12348 -497.886253)
			(xy 67.050339 -497.906199) (xy 66.975494 -497.918258) (xy 66.89979 -497.922293) (xy 66.824086 -497.918258)
			(xy 66.749241 -497.906199) (xy 66.6761 -497.886253) (xy 66.605495 -497.858646) (xy 66.538224 -497.82369)
			(xy 66.475049 -497.781782) (xy 66.416687 -497.733396) (xy 66.363799 -497.67908) (xy 66.316984 -497.619451)
			(xy 66.276772 -497.555183) (xy 66.24362 -497.487006) (xy 66.217902 -497.41569) (xy 66.19991 -497.342045)
			(xy 66.189848 -497.266905) (xy 66.187829 -497.191121) (xy 65.071751 -497.191121) (xy 65.069732 -497.266905)
			(xy 65.05967 -497.342045) (xy 65.041678 -497.41569) (xy 65.01596 -497.487006) (xy 64.982808 -497.555183)
			(xy 64.942596 -497.619451) (xy 64.895781 -497.67908) (xy 64.842893 -497.733396) (xy 64.784531 -497.781782)
			(xy 64.721356 -497.82369) (xy 64.654085 -497.858646) (xy 64.58348 -497.886253) (xy 64.510339 -497.906199)
			(xy 64.435494 -497.918258) (xy 64.35979 -497.922293) (xy 64.284086 -497.918258) (xy 64.209241 -497.906199)
			(xy 64.1361 -497.886253) (xy 64.065495 -497.858646) (xy 63.998224 -497.82369) (xy 63.935049 -497.781782)
			(xy 63.876687 -497.733396) (xy 63.823799 -497.67908) (xy 63.776984 -497.619451) (xy 63.736772 -497.555183)
			(xy 63.70362 -497.487006) (xy 63.677902 -497.41569) (xy 63.65991 -497.342045) (xy 63.649848 -497.266905)
			(xy 63.647829 -497.191121) (xy 42.526017 -497.191121) (xy 42.478867 -497.227408) (xy 42.3822 -497.291698)
			(xy 42.281328 -497.349165) (xy 42.176731 -497.399536) (xy 42.068908 -497.442571) (xy 41.958374 -497.478065)
			(xy 41.845654 -497.505848) (xy 41.731286 -497.525788) (xy 41.615814 -497.53779) (xy 41.49979 -497.541797)
			(xy 41.383766 -497.53779) (xy 41.268294 -497.525788) (xy 41.153926 -497.505848) (xy 41.041206 -497.478065)
			(xy 40.930672 -497.442571) (xy 40.822849 -497.399536) (xy 40.718252 -497.349165) (xy 40.61738 -497.291698)
			(xy 40.520713 -497.227408) (xy 40.428712 -497.156603) (xy 40.341815 -497.079619) (xy 40.260436 -496.996823)
			(xy 40.184963 -496.90861) (xy 40.115756 -496.8154) (xy 40.053144 -496.717637) (xy 39.997427 -496.615788)
			(xy 39.948869 -496.510338) (xy 39.907701 -496.401789) (xy 39.874121 -496.290658) (xy 39.848288 -496.177475)
			(xy 39.830325 -496.06278) (xy 39.820317 -495.947118) (xy 39.818314 -495.831042) (xy 25.02154 -495.831042)
			(xy 25.02154 -497.433362) (xy 29.519874 -497.433362) (xy 29.519874 -497.346462) (xy 29.527892 -497.259933)
			(xy 29.54386 -497.174513) (xy 29.567641 -497.090931) (xy 29.599033 -497.009899) (xy 29.637767 -496.93211)
			(xy 29.683514 -496.858226) (xy 29.735883 -496.788879) (xy 29.794427 -496.724659) (xy 29.858647 -496.666115)
			(xy 29.927994 -496.613746) (xy 30.001878 -496.567999) (xy 30.079667 -496.529265) (xy 30.160699 -496.497873)
			(xy 30.244281 -496.474092) (xy 30.329701 -496.458124) (xy 30.41623 -496.450106) (xy 30.45968 -496.449604)
			(xy 30.50313 -496.450106) (xy 30.589659 -496.458124) (xy 30.675079 -496.474092) (xy 30.758661 -496.497873)
			(xy 30.839693 -496.529265) (xy 30.917482 -496.567999) (xy 30.991366 -496.613746) (xy 31.060713 -496.666115)
			(xy 31.124933 -496.724659) (xy 31.183477 -496.788879) (xy 31.235846 -496.858226) (xy 31.281593 -496.93211)
			(xy 31.320327 -497.009899) (xy 31.351719 -497.090931) (xy 31.3755 -497.174513) (xy 31.391468 -497.259933)
			(xy 31.399486 -497.346462) (xy 31.399486 -497.433362) (xy 34.599874 -497.433362) (xy 34.599874 -497.346462)
			(xy 34.607892 -497.259933) (xy 34.62386 -497.174513) (xy 34.647641 -497.090931) (xy 34.679033 -497.009899)
			(xy 34.717767 -496.93211) (xy 34.763514 -496.858226) (xy 34.815883 -496.788879) (xy 34.874427 -496.724659)
			(xy 34.938647 -496.666115) (xy 35.007994 -496.613746) (xy 35.081878 -496.567999) (xy 35.159667 -496.529265)
			(xy 35.240699 -496.497873) (xy 35.324281 -496.474092) (xy 35.409701 -496.458124) (xy 35.49623 -496.450106)
			(xy 35.53968 -496.449604) (xy 35.58313 -496.450106) (xy 35.669659 -496.458124) (xy 35.755079 -496.474092)
			(xy 35.838661 -496.497873) (xy 35.919693 -496.529265) (xy 35.997482 -496.567999) (xy 36.071366 -496.613746)
			(xy 36.140713 -496.666115) (xy 36.204933 -496.724659) (xy 36.263477 -496.788879) (xy 36.315846 -496.858226)
			(xy 36.361593 -496.93211) (xy 36.400327 -497.009899) (xy 36.431719 -497.090931) (xy 36.4555 -497.174513)
			(xy 36.471468 -497.259933) (xy 36.479486 -497.346462) (xy 36.479486 -497.433362) (xy 36.471468 -497.519891)
			(xy 36.4555 -497.605311) (xy 36.431719 -497.688893) (xy 36.400327 -497.769925) (xy 36.361593 -497.847714)
			(xy 36.315846 -497.921598) (xy 36.263477 -497.990945) (xy 36.204933 -498.055165) (xy 36.140713 -498.113709)
			(xy 36.071366 -498.166078) (xy 35.997482 -498.211825) (xy 35.919693 -498.250559) (xy 35.838661 -498.281951)
			(xy 35.755079 -498.305732) (xy 35.669659 -498.3217) (xy 35.58313 -498.329718) (xy 35.49623 -498.329718)
			(xy 35.409701 -498.3217) (xy 35.324281 -498.305732) (xy 35.240699 -498.281951) (xy 35.159667 -498.250559)
			(xy 35.081878 -498.211825) (xy 35.007994 -498.166078) (xy 34.938647 -498.113709) (xy 34.874427 -498.055165)
			(xy 34.815883 -497.990945) (xy 34.763514 -497.921598) (xy 34.717767 -497.847714) (xy 34.679033 -497.769925)
			(xy 34.647641 -497.688893) (xy 34.62386 -497.605311) (xy 34.607892 -497.519891) (xy 34.599874 -497.433362)
			(xy 31.399486 -497.433362) (xy 31.391468 -497.519891) (xy 31.3755 -497.605311) (xy 31.351719 -497.688893)
			(xy 31.320327 -497.769925) (xy 31.281593 -497.847714) (xy 31.235846 -497.921598) (xy 31.183477 -497.990945)
			(xy 31.124933 -498.055165) (xy 31.060713 -498.113709) (xy 30.991366 -498.166078) (xy 30.917482 -498.211825)
			(xy 30.839693 -498.250559) (xy 30.758661 -498.281951) (xy 30.675079 -498.305732) (xy 30.589659 -498.3217)
			(xy 30.50313 -498.329718) (xy 30.41623 -498.329718) (xy 30.329701 -498.3217) (xy 30.244281 -498.305732)
			(xy 30.160699 -498.281951) (xy 30.079667 -498.250559) (xy 30.001878 -498.211825) (xy 29.927994 -498.166078)
			(xy 29.858647 -498.113709) (xy 29.794427 -498.055165) (xy 29.735883 -497.990945) (xy 29.683514 -497.921598)
			(xy 29.637767 -497.847714) (xy 29.599033 -497.769925) (xy 29.567641 -497.688893) (xy 29.54386 -497.605311)
			(xy 29.527892 -497.519891) (xy 29.519874 -497.433362) (xy 25.02154 -497.433362) (xy 25.02154 -497.961412)
			(xy 23.00959 -499.973362) (xy 29.519874 -499.973362) (xy 29.519874 -499.886462) (xy 29.527892 -499.799933)
			(xy 29.54386 -499.714513) (xy 29.567641 -499.630931) (xy 29.599033 -499.549899) (xy 29.637767 -499.47211)
			(xy 29.683514 -499.398226) (xy 29.735883 -499.328879) (xy 29.794427 -499.264659) (xy 29.858647 -499.206115)
			(xy 29.927994 -499.153746) (xy 30.001878 -499.107999) (xy 30.079667 -499.069265) (xy 30.160699 -499.037873)
			(xy 30.244281 -499.014092) (xy 30.329701 -498.998124) (xy 30.41623 -498.990106) (xy 30.45968 -498.989604)
			(xy 30.50313 -498.990106) (xy 30.589659 -498.998124) (xy 30.675079 -499.014092) (xy 30.758661 -499.037873)
			(xy 30.839693 -499.069265) (xy 30.917482 -499.107999) (xy 30.991366 -499.153746) (xy 31.060713 -499.206115)
			(xy 31.124933 -499.264659) (xy 31.183477 -499.328879) (xy 31.235846 -499.398226) (xy 31.281593 -499.47211)
			(xy 31.320327 -499.549899) (xy 31.351719 -499.630931) (xy 31.3755 -499.714513) (xy 31.391468 -499.799933)
			(xy 31.399486 -499.886462) (xy 31.399486 -499.973362) (xy 34.599874 -499.973362) (xy 34.599874 -499.886462)
			(xy 34.607892 -499.799933) (xy 34.62386 -499.714513) (xy 34.647641 -499.630931) (xy 34.679033 -499.549899)
			(xy 34.717767 -499.47211) (xy 34.763514 -499.398226) (xy 34.815883 -499.328879) (xy 34.874427 -499.264659)
			(xy 34.938647 -499.206115) (xy 35.007994 -499.153746) (xy 35.081878 -499.107999) (xy 35.159667 -499.069265)
			(xy 35.240699 -499.037873) (xy 35.324281 -499.014092) (xy 35.409701 -498.998124) (xy 35.49623 -498.990106)
			(xy 35.53968 -498.989604) (xy 35.58313 -498.990106) (xy 35.669659 -498.998124) (xy 35.755079 -499.014092)
			(xy 35.838661 -499.037873) (xy 35.919693 -499.069265) (xy 35.997482 -499.107999) (xy 36.071366 -499.153746)
			(xy 36.140713 -499.206115) (xy 36.204933 -499.264659) (xy 36.263477 -499.328879) (xy 36.315846 -499.398226)
			(xy 36.361593 -499.47211) (xy 36.400327 -499.549899) (xy 36.431719 -499.630931) (xy 36.4555 -499.714513)
			(xy 36.471468 -499.799933) (xy 36.479486 -499.886462) (xy 36.479486 -499.973362) (xy 36.471468 -500.059891)
			(xy 36.4555 -500.145311) (xy 36.431719 -500.228893) (xy 36.400327 -500.309925) (xy 36.361593 -500.387714)
			(xy 36.315846 -500.461598) (xy 36.263477 -500.530945) (xy 36.204933 -500.595165) (xy 36.140713 -500.653709)
			(xy 36.071366 -500.706078) (xy 35.997482 -500.751825) (xy 35.919693 -500.790559) (xy 35.838661 -500.821951)
			(xy 35.755079 -500.845732) (xy 35.669659 -500.8617) (xy 35.58313 -500.869718) (xy 35.49623 -500.869718)
			(xy 35.409701 -500.8617) (xy 35.324281 -500.845732) (xy 35.240699 -500.821951) (xy 35.159667 -500.790559)
			(xy 35.081878 -500.751825) (xy 35.007994 -500.706078) (xy 34.938647 -500.653709) (xy 34.874427 -500.595165)
			(xy 34.815883 -500.530945) (xy 34.763514 -500.461598) (xy 34.717767 -500.387714) (xy 34.679033 -500.309925)
			(xy 34.647641 -500.228893) (xy 34.62386 -500.145311) (xy 34.607892 -500.059891) (xy 34.599874 -499.973362)
			(xy 31.399486 -499.973362) (xy 31.391468 -500.059891) (xy 31.3755 -500.145311) (xy 31.351719 -500.228893)
			(xy 31.320327 -500.309925) (xy 31.281593 -500.387714) (xy 31.235846 -500.461598) (xy 31.183477 -500.530945)
			(xy 31.124933 -500.595165) (xy 31.060713 -500.653709) (xy 30.991366 -500.706078) (xy 30.917482 -500.751825)
			(xy 30.839693 -500.790559) (xy 30.758661 -500.821951) (xy 30.675079 -500.845732) (xy 30.589659 -500.8617)
			(xy 30.50313 -500.869718) (xy 30.41623 -500.869718) (xy 30.329701 -500.8617) (xy 30.244281 -500.845732)
			(xy 30.160699 -500.821951) (xy 30.079667 -500.790559) (xy 30.001878 -500.751825) (xy 29.927994 -500.706078)
			(xy 29.858647 -500.653709) (xy 29.794427 -500.595165) (xy 29.735883 -500.530945) (xy 29.683514 -500.461598)
			(xy 29.637767 -500.387714) (xy 29.599033 -500.309925) (xy 29.567641 -500.228893) (xy 29.54386 -500.145311)
			(xy 29.527892 -500.059891) (xy 29.519874 -499.973362) (xy 23.00959 -499.973362) (xy 20.46959 -502.513362)
			(xy 29.519874 -502.513362) (xy 29.519874 -502.426462) (xy 29.527892 -502.339933) (xy 29.54386 -502.254513)
			(xy 29.567641 -502.170931) (xy 29.599033 -502.089899) (xy 29.637767 -502.01211) (xy 29.683514 -501.938226)
			(xy 29.735883 -501.868879) (xy 29.794427 -501.804659) (xy 29.858647 -501.746115) (xy 29.927994 -501.693746)
			(xy 30.001878 -501.647999) (xy 30.079667 -501.609265) (xy 30.160699 -501.577873) (xy 30.244281 -501.554092)
			(xy 30.329701 -501.538124) (xy 30.41623 -501.530106) (xy 30.45968 -501.529604) (xy 30.50313 -501.530106)
			(xy 30.589659 -501.538124) (xy 30.675079 -501.554092) (xy 30.758661 -501.577873) (xy 30.839693 -501.609265)
			(xy 30.917482 -501.647999) (xy 30.991366 -501.693746) (xy 31.060713 -501.746115) (xy 31.124933 -501.804659)
			(xy 31.183477 -501.868879) (xy 31.235846 -501.938226) (xy 31.281593 -502.01211) (xy 31.320327 -502.089899)
			(xy 31.351719 -502.170931) (xy 31.3755 -502.254513) (xy 31.391468 -502.339933) (xy 31.399486 -502.426462)
			(xy 31.399486 -502.513362) (xy 34.599874 -502.513362) (xy 34.599874 -502.426462) (xy 34.607892 -502.339933)
			(xy 34.62386 -502.254513) (xy 34.647641 -502.170931) (xy 34.679033 -502.089899) (xy 34.717767 -502.01211)
			(xy 34.763514 -501.938226) (xy 34.815883 -501.868879) (xy 34.874427 -501.804659) (xy 34.938647 -501.746115)
			(xy 35.007994 -501.693746) (xy 35.081878 -501.647999) (xy 35.159667 -501.609265) (xy 35.240699 -501.577873)
			(xy 35.324281 -501.554092) (xy 35.409701 -501.538124) (xy 35.49623 -501.530106) (xy 35.53968 -501.529604)
			(xy 35.58313 -501.530106) (xy 35.669659 -501.538124) (xy 35.755079 -501.554092) (xy 35.838661 -501.577873)
			(xy 35.919693 -501.609265) (xy 35.997482 -501.647999) (xy 36.071366 -501.693746) (xy 36.140713 -501.746115)
			(xy 36.204933 -501.804659) (xy 36.263477 -501.868879) (xy 36.315846 -501.938226) (xy 36.361593 -502.01211)
			(xy 36.400327 -502.089899) (xy 36.431719 -502.170931) (xy 36.4555 -502.254513) (xy 36.471468 -502.339933)
			(xy 36.479486 -502.426462) (xy 36.479486 -502.513362) (xy 36.471468 -502.599891) (xy 36.4555 -502.685311)
			(xy 36.431719 -502.768893) (xy 36.400327 -502.849925) (xy 36.361593 -502.927714) (xy 36.315846 -503.001598)
			(xy 36.263477 -503.070945) (xy 36.204933 -503.135165) (xy 36.140713 -503.193709) (xy 36.071366 -503.246078)
			(xy 35.997482 -503.291825) (xy 35.919693 -503.330559) (xy 35.838661 -503.361951) (xy 35.755079 -503.385732)
			(xy 35.669659 -503.4017) (xy 35.58313 -503.409718) (xy 35.49623 -503.409718) (xy 35.409701 -503.4017)
			(xy 35.324281 -503.385732) (xy 35.240699 -503.361951) (xy 35.159667 -503.330559) (xy 35.081878 -503.291825)
			(xy 35.007994 -503.246078) (xy 34.938647 -503.193709) (xy 34.874427 -503.135165) (xy 34.815883 -503.070945)
			(xy 34.763514 -503.001598) (xy 34.717767 -502.927714) (xy 34.679033 -502.849925) (xy 34.647641 -502.768893)
			(xy 34.62386 -502.685311) (xy 34.607892 -502.599891) (xy 34.599874 -502.513362) (xy 31.399486 -502.513362)
			(xy 31.391468 -502.599891) (xy 31.3755 -502.685311) (xy 31.351719 -502.768893) (xy 31.320327 -502.849925)
			(xy 31.281593 -502.927714) (xy 31.235846 -503.001598) (xy 31.183477 -503.070945) (xy 31.124933 -503.135165)
			(xy 31.060713 -503.193709) (xy 30.991366 -503.246078) (xy 30.917482 -503.291825) (xy 30.839693 -503.330559)
			(xy 30.758661 -503.361951) (xy 30.675079 -503.385732) (xy 30.589659 -503.4017) (xy 30.50313 -503.409718)
			(xy 30.41623 -503.409718) (xy 30.329701 -503.4017) (xy 30.244281 -503.385732) (xy 30.160699 -503.361951)
			(xy 30.079667 -503.330559) (xy 30.001878 -503.291825) (xy 29.927994 -503.246078) (xy 29.858647 -503.193709)
			(xy 29.794427 -503.135165) (xy 29.735883 -503.070945) (xy 29.683514 -503.001598) (xy 29.637767 -502.927714)
			(xy 29.599033 -502.849925) (xy 29.567641 -502.768893) (xy 29.54386 -502.685311) (xy 29.527892 -502.599891)
			(xy 29.519874 -502.513362) (xy 20.46959 -502.513362) (xy 17.92959 -505.053362) (xy 29.519874 -505.053362)
			(xy 29.519874 -504.966462) (xy 29.527892 -504.879933) (xy 29.54386 -504.794513) (xy 29.567641 -504.710931)
			(xy 29.599033 -504.629899) (xy 29.637767 -504.55211) (xy 29.683514 -504.478226) (xy 29.735883 -504.408879)
			(xy 29.794427 -504.344659) (xy 29.858647 -504.286115) (xy 29.927994 -504.233746) (xy 30.001878 -504.187999)
			(xy 30.079667 -504.149265) (xy 30.160699 -504.117873) (xy 30.244281 -504.094092) (xy 30.329701 -504.078124)
			(xy 30.41623 -504.070106) (xy 30.45968 -504.069604) (xy 30.50313 -504.070106) (xy 30.589659 -504.078124)
			(xy 30.675079 -504.094092) (xy 30.758661 -504.117873) (xy 30.839693 -504.149265) (xy 30.917482 -504.187999)
			(xy 30.991366 -504.233746) (xy 31.060713 -504.286115) (xy 31.124933 -504.344659) (xy 31.183477 -504.408879)
			(xy 31.235846 -504.478226) (xy 31.281593 -504.55211) (xy 31.320327 -504.629899) (xy 31.351719 -504.710931)
			(xy 31.3755 -504.794513) (xy 31.391468 -504.879933) (xy 31.399486 -504.966462) (xy 31.399486 -505.053362)
			(xy 34.599874 -505.053362) (xy 34.599874 -504.966462) (xy 34.607892 -504.879933) (xy 34.62386 -504.794513)
			(xy 34.647641 -504.710931) (xy 34.679033 -504.629899) (xy 34.717767 -504.55211) (xy 34.763514 -504.478226)
			(xy 34.815883 -504.408879) (xy 34.874427 -504.344659) (xy 34.938647 -504.286115) (xy 35.007994 -504.233746)
			(xy 35.081878 -504.187999) (xy 35.159667 -504.149265) (xy 35.240699 -504.117873) (xy 35.324281 -504.094092)
			(xy 35.409701 -504.078124) (xy 35.49623 -504.070106) (xy 35.53968 -504.069604) (xy 35.58313 -504.070106)
			(xy 35.669659 -504.078124) (xy 35.755079 -504.094092) (xy 35.838661 -504.117873) (xy 35.919693 -504.149265)
			(xy 35.997482 -504.187999) (xy 36.071366 -504.233746) (xy 36.140713 -504.286115) (xy 36.204933 -504.344659)
			(xy 36.263477 -504.408879) (xy 36.315846 -504.478226) (xy 36.361593 -504.55211) (xy 36.400327 -504.629899)
			(xy 36.431719 -504.710931) (xy 36.4555 -504.794513) (xy 36.471468 -504.879933) (xy 36.479486 -504.966462)
			(xy 36.479486 -505.053362) (xy 36.471468 -505.139891) (xy 36.4555 -505.225311) (xy 36.431719 -505.308893)
			(xy 36.400327 -505.389925) (xy 36.361593 -505.467714) (xy 36.315846 -505.541598) (xy 36.263477 -505.610945)
			(xy 36.204933 -505.675165) (xy 36.140713 -505.733709) (xy 36.071366 -505.786078) (xy 35.997482 -505.831825)
			(xy 35.919693 -505.870559) (xy 35.838661 -505.901951) (xy 35.755079 -505.925732) (xy 35.669659 -505.9417)
			(xy 35.58313 -505.949718) (xy 35.49623 -505.949718) (xy 35.409701 -505.9417) (xy 35.324281 -505.925732)
			(xy 35.240699 -505.901951) (xy 35.159667 -505.870559) (xy 35.081878 -505.831825) (xy 35.007994 -505.786078)
			(xy 34.938647 -505.733709) (xy 34.874427 -505.675165) (xy 34.815883 -505.610945) (xy 34.763514 -505.541598)
			(xy 34.717767 -505.467714) (xy 34.679033 -505.389925) (xy 34.647641 -505.308893) (xy 34.62386 -505.225311)
			(xy 34.607892 -505.139891) (xy 34.599874 -505.053362) (xy 31.399486 -505.053362) (xy 31.391468 -505.139891)
			(xy 31.3755 -505.225311) (xy 31.351719 -505.308893) (xy 31.320327 -505.389925) (xy 31.281593 -505.467714)
			(xy 31.235846 -505.541598) (xy 31.183477 -505.610945) (xy 31.124933 -505.675165) (xy 31.060713 -505.733709)
			(xy 30.991366 -505.786078) (xy 30.917482 -505.831825) (xy 30.839693 -505.870559) (xy 30.758661 -505.901951)
			(xy 30.675079 -505.925732) (xy 30.589659 -505.9417) (xy 30.50313 -505.949718) (xy 30.41623 -505.949718)
			(xy 30.329701 -505.9417) (xy 30.244281 -505.925732) (xy 30.160699 -505.901951) (xy 30.079667 -505.870559)
			(xy 30.001878 -505.831825) (xy 29.927994 -505.786078) (xy 29.858647 -505.733709) (xy 29.794427 -505.675165)
			(xy 29.735883 -505.610945) (xy 29.683514 -505.541598) (xy 29.637767 -505.467714) (xy 29.599033 -505.389925)
			(xy 29.567641 -505.308893) (xy 29.54386 -505.225311) (xy 29.527892 -505.139891) (xy 29.519874 -505.053362)
			(xy 17.92959 -505.053362) (xy 15.38959 -507.593362) (xy 29.519874 -507.593362) (xy 29.519874 -507.506462)
			(xy 29.527892 -507.419933) (xy 29.54386 -507.334513) (xy 29.567641 -507.250931) (xy 29.599033 -507.169899)
			(xy 29.637767 -507.09211) (xy 29.683514 -507.018226) (xy 29.735883 -506.948879) (xy 29.794427 -506.884659)
			(xy 29.858647 -506.826115) (xy 29.927994 -506.773746) (xy 30.001878 -506.727999) (xy 30.079667 -506.689265)
			(xy 30.160699 -506.657873) (xy 30.244281 -506.634092) (xy 30.329701 -506.618124) (xy 30.41623 -506.610106)
			(xy 30.45968 -506.609604) (xy 30.50313 -506.610106) (xy 30.589659 -506.618124) (xy 30.675079 -506.634092)
			(xy 30.758661 -506.657873) (xy 30.839693 -506.689265) (xy 30.917482 -506.727999) (xy 30.991366 -506.773746)
			(xy 31.060713 -506.826115) (xy 31.124933 -506.884659) (xy 31.183477 -506.948879) (xy 31.235846 -507.018226)
			(xy 31.281593 -507.09211) (xy 31.320327 -507.169899) (xy 31.351719 -507.250931) (xy 31.3755 -507.334513)
			(xy 31.391468 -507.419933) (xy 31.399486 -507.506462) (xy 31.399486 -507.593362) (xy 34.599874 -507.593362)
			(xy 34.599874 -507.506462) (xy 34.607892 -507.419933) (xy 34.62386 -507.334513) (xy 34.647641 -507.250931)
			(xy 34.679033 -507.169899) (xy 34.717767 -507.09211) (xy 34.763514 -507.018226) (xy 34.815883 -506.948879)
			(xy 34.874427 -506.884659) (xy 34.938647 -506.826115) (xy 35.007994 -506.773746) (xy 35.081878 -506.727999)
			(xy 35.159667 -506.689265) (xy 35.240699 -506.657873) (xy 35.324281 -506.634092) (xy 35.409701 -506.618124)
			(xy 35.49623 -506.610106) (xy 35.53968 -506.609604) (xy 35.58313 -506.610106) (xy 35.669659 -506.618124)
			(xy 35.755079 -506.634092) (xy 35.838661 -506.657873) (xy 35.919693 -506.689265) (xy 35.997482 -506.727999)
			(xy 36.071366 -506.773746) (xy 36.140713 -506.826115) (xy 36.204933 -506.884659) (xy 36.263477 -506.948879)
			(xy 36.315846 -507.018226) (xy 36.361593 -507.09211) (xy 36.400327 -507.169899) (xy 36.431719 -507.250931)
			(xy 36.4555 -507.334513) (xy 36.471468 -507.419933) (xy 36.479486 -507.506462) (xy 36.479486 -507.593362)
			(xy 36.471468 -507.679891) (xy 36.464349 -507.717975) (xy 51.47436 -507.717975) (xy 51.47436 -507.636865)
			(xy 51.48231 -507.556146) (xy 51.498133 -507.476595) (xy 51.521678 -507.398979) (xy 51.552717 -507.324043)
			(xy 51.590952 -507.252511) (xy 51.636014 -507.185071) (xy 51.687469 -507.122372) (xy 51.744822 -507.065019)
			(xy 51.807521 -507.013564) (xy 51.874961 -506.968502) (xy 51.946493 -506.930267) (xy 52.021429 -506.899228)
			(xy 52.099045 -506.875683) (xy 52.178596 -506.85986) (xy 52.259315 -506.85191) (xy 52.29987 -506.851412)
			(xy 52.340425 -506.85191) (xy 52.421144 -506.85986) (xy 52.500695 -506.875683) (xy 52.578311 -506.899228)
			(xy 52.653247 -506.930267) (xy 52.724779 -506.968502) (xy 52.792219 -507.013564) (xy 52.854918 -507.065019)
			(xy 52.912271 -507.122372) (xy 52.963726 -507.185071) (xy 53.008788 -507.252511) (xy 53.047023 -507.324043)
			(xy 53.078062 -507.398979) (xy 53.101607 -507.476595) (xy 53.11743 -507.556146) (xy 53.12538 -507.636865)
			(xy 53.12538 -507.717975) (xy 53.11743 -507.798694) (xy 53.101607 -507.878245) (xy 53.078062 -507.955861)
			(xy 53.047023 -508.030797) (xy 53.008788 -508.102329) (xy 52.963726 -508.169769) (xy 52.912271 -508.232468)
			(xy 52.854918 -508.289821) (xy 52.792219 -508.341276) (xy 52.724779 -508.386338) (xy 52.653247 -508.424573)
			(xy 52.578311 -508.455612) (xy 52.500695 -508.479157) (xy 52.421144 -508.49498) (xy 52.340425 -508.50293)
			(xy 52.259315 -508.50293) (xy 52.178596 -508.49498) (xy 52.099045 -508.479157) (xy 52.021429 -508.455612)
			(xy 51.946493 -508.424573) (xy 51.874961 -508.386338) (xy 51.807521 -508.341276) (xy 51.744822 -508.289821)
			(xy 51.687469 -508.232468) (xy 51.636014 -508.169769) (xy 51.590952 -508.102329) (xy 51.552717 -508.030797)
			(xy 51.521678 -507.955861) (xy 51.498133 -507.878245) (xy 51.48231 -507.798694) (xy 51.47436 -507.717975)
			(xy 36.464349 -507.717975) (xy 36.4555 -507.765311) (xy 36.431719 -507.848893) (xy 36.400327 -507.929925)
			(xy 36.361593 -508.007714) (xy 36.315846 -508.081598) (xy 36.263477 -508.150945) (xy 36.204933 -508.215165)
			(xy 36.140713 -508.273709) (xy 36.071366 -508.326078) (xy 35.997482 -508.371825) (xy 35.919693 -508.410559)
			(xy 35.838661 -508.441951) (xy 35.755079 -508.465732) (xy 35.669659 -508.4817) (xy 35.58313 -508.489718)
			(xy 35.49623 -508.489718) (xy 35.409701 -508.4817) (xy 35.324281 -508.465732) (xy 35.240699 -508.441951)
			(xy 35.159667 -508.410559) (xy 35.081878 -508.371825) (xy 35.007994 -508.326078) (xy 34.938647 -508.273709)
			(xy 34.874427 -508.215165) (xy 34.815883 -508.150945) (xy 34.763514 -508.081598) (xy 34.717767 -508.007714)
			(xy 34.679033 -507.929925) (xy 34.647641 -507.848893) (xy 34.62386 -507.765311) (xy 34.607892 -507.679891)
			(xy 34.599874 -507.593362) (xy 31.399486 -507.593362) (xy 31.391468 -507.679891) (xy 31.3755 -507.765311)
			(xy 31.351719 -507.848893) (xy 31.320327 -507.929925) (xy 31.281593 -508.007714) (xy 31.235846 -508.081598)
			(xy 31.183477 -508.150945) (xy 31.124933 -508.215165) (xy 31.060713 -508.273709) (xy 30.991366 -508.326078)
			(xy 30.917482 -508.371825) (xy 30.839693 -508.410559) (xy 30.758661 -508.441951) (xy 30.675079 -508.465732)
			(xy 30.589659 -508.4817) (xy 30.50313 -508.489718) (xy 30.41623 -508.489718) (xy 30.329701 -508.4817)
			(xy 30.244281 -508.465732) (xy 30.160699 -508.441951) (xy 30.079667 -508.410559) (xy 30.001878 -508.371825)
			(xy 29.927994 -508.326078) (xy 29.858647 -508.273709) (xy 29.794427 -508.215165) (xy 29.735883 -508.150945)
			(xy 29.683514 -508.081598) (xy 29.637767 -508.007714) (xy 29.599033 -507.929925) (xy 29.567641 -507.848893)
			(xy 29.54386 -507.765311) (xy 29.527892 -507.679891) (xy 29.519874 -507.593362) (xy 15.38959 -507.593362)
			(xy 13.975156 -509.007796) (xy 86.877655 -509.007796) (xy 86.879665 -508.817113) (xy 86.889712 -508.626684)
			(xy 86.907778 -508.436848) (xy 86.933831 -508.247942) (xy 86.967824 -508.060303) (xy 87.009697 -507.874263)
			(xy 87.059376 -507.690154) (xy 87.116772 -507.508303) (xy 87.181783 -507.329033) (xy 87.254294 -507.152663)
			(xy 87.334175 -506.979507) (xy 87.421285 -506.809872) (xy 87.515469 -506.64406) (xy 87.61656 -506.482366)
			(xy 87.724376 -506.325078) (xy 87.838728 -506.172475) (xy 87.959411 -506.024827) (xy 88.086212 -505.882399)
			(xy 88.218903 -505.745443) (xy 88.357251 -505.614202) (xy 88.501008 -505.48891) (xy 88.649919 -505.36979)
			(xy 88.80372 -505.257054) (xy 88.962136 -505.150901) (xy 89.124887 -505.051521) (xy 89.291682 -504.959091)
			(xy 89.462226 -504.873774) (xy 89.636214 -504.795722) (xy 89.813339 -504.725075) (xy 89.993284 -504.661957)
			(xy 90.17573 -504.606481) (xy 90.360353 -504.558746) (xy 90.546823 -504.518836) (xy 90.734811 -504.486823)
			(xy 90.923981 -504.462763) (xy 91.113997 -504.4467) (xy 91.304521 -504.438661) (xy 91.399868 -504.438158)
			(xy 91.495215 -504.438661) (xy 91.685739 -504.4467) (xy 91.875755 -504.462763) (xy 92.064925 -504.486823)
			(xy 92.252913 -504.518836) (xy 92.439383 -504.558746) (xy 92.624006 -504.606481) (xy 92.806452 -504.661957)
			(xy 92.986397 -504.725075) (xy 93.163522 -504.795722) (xy 93.33751 -504.873774) (xy 93.508054 -504.959091)
			(xy 93.674849 -505.051521) (xy 93.8376 -505.150901) (xy 93.996016 -505.257054) (xy 94.149817 -505.36979)
			(xy 94.298728 -505.48891) (xy 94.442485 -505.614202) (xy 94.580833 -505.745443) (xy 94.713524 -505.882399)
			(xy 94.840325 -506.024827) (xy 94.961008 -506.172475) (xy 95.07536 -506.325078) (xy 95.183176 -506.482366)
			(xy 95.284267 -506.64406) (xy 95.378451 -506.809872) (xy 95.465561 -506.979507) (xy 95.545442 -507.152663)
			(xy 95.617953 -507.329033) (xy 95.682964 -507.508303) (xy 95.74036 -507.690154) (xy 95.790039 -507.874263)
			(xy 95.831912 -508.060303) (xy 95.865905 -508.247942) (xy 95.891958 -508.436848) (xy 95.910024 -508.626684)
			(xy 95.920071 -508.817113) (xy 95.922081 -509.007796) (xy 95.916051 -509.198395) (xy 95.901992 -509.388569)
			(xy 95.879927 -509.577982) (xy 95.849898 -509.766297) (xy 95.811956 -509.953178) (xy 95.76617 -510.138294)
			(xy 95.712621 -510.321314) (xy 95.651403 -510.501915) (xy 95.582627 -510.679774) (xy 95.506414 -510.854576)
			(xy 95.4229 -511.02601) (xy 95.332233 -511.19377) (xy 95.234574 -511.357559) (xy 95.130097 -511.517086)
			(xy 95.018988 -511.672067) (xy 94.901445 -511.822225) (xy 94.777675 -511.967295) (xy 94.6479 -512.107019)
			(xy 94.512351 -512.241147) (xy 94.371267 -512.369441) (xy 94.2249 -512.491675) (xy 94.073511 -512.607629)
			(xy 93.917368 -512.717098) (xy 93.756749 -512.819887) (xy 93.591939 -512.915813) (xy 93.423232 -513.004707)
			(xy 93.250927 -513.086409) (xy 93.075332 -513.160775) (xy 92.896757 -513.227673) (xy 92.715521 -513.286983)
			(xy 92.531946 -513.3386) (xy 92.346358 -513.382432) (xy 92.159088 -513.418401) (xy 91.970467 -513.446444)
			(xy 91.780832 -513.46651) (xy 91.590519 -513.478564) (xy 91.399868 -513.482585) (xy 91.209217 -513.478564)
			(xy 91.018904 -513.46651) (xy 90.829269 -513.446444) (xy 90.640648 -513.418401) (xy 90.453378 -513.382432)
			(xy 90.26779 -513.3386) (xy 90.084215 -513.286983) (xy 89.902979 -513.227673) (xy 89.724404 -513.160775)
			(xy 89.548809 -513.086409) (xy 89.376504 -513.004707) (xy 89.207797 -512.915813) (xy 89.042987 -512.819887)
			(xy 88.882368 -512.717098) (xy 88.726225 -512.607629) (xy 88.574836 -512.491675) (xy 88.428469 -512.369441)
			(xy 88.287385 -512.241147) (xy 88.151836 -512.107019) (xy 88.022061 -511.967295) (xy 87.898291 -511.822225)
			(xy 87.780748 -511.672067) (xy 87.669639 -511.517086) (xy 87.565162 -511.357559) (xy 87.467503 -511.19377)
			(xy 87.376836 -511.02601) (xy 87.293322 -510.854576) (xy 87.217109 -510.679774) (xy 87.148333 -510.501915)
			(xy 87.087115 -510.321314) (xy 87.033566 -510.138294) (xy 86.98778 -509.953178) (xy 86.949838 -509.766297)
			(xy 86.919809 -509.577982) (xy 86.897744 -509.388569) (xy 86.883685 -509.198395) (xy 86.877655 -509.007796)
			(xy 13.975156 -509.007796) (xy 12.84959 -510.133362) (xy 29.519874 -510.133362) (xy 29.519874 -510.046462)
			(xy 29.527892 -509.959933) (xy 29.54386 -509.874513) (xy 29.567641 -509.790931) (xy 29.599033 -509.709899)
			(xy 29.637767 -509.63211) (xy 29.683514 -509.558226) (xy 29.735883 -509.488879) (xy 29.794427 -509.424659)
			(xy 29.858647 -509.366115) (xy 29.927994 -509.313746) (xy 30.001878 -509.267999) (xy 30.079667 -509.229265)
			(xy 30.160699 -509.197873) (xy 30.244281 -509.174092) (xy 30.329701 -509.158124) (xy 30.41623 -509.150106)
			(xy 30.45968 -509.149604) (xy 30.50313 -509.150106) (xy 30.589659 -509.158124) (xy 30.675079 -509.174092)
			(xy 30.758661 -509.197873) (xy 30.839693 -509.229265) (xy 30.917482 -509.267999) (xy 30.991366 -509.313746)
			(xy 31.060713 -509.366115) (xy 31.124933 -509.424659) (xy 31.183477 -509.488879) (xy 31.235846 -509.558226)
			(xy 31.281593 -509.63211) (xy 31.320327 -509.709899) (xy 31.351719 -509.790931) (xy 31.3755 -509.874513)
			(xy 31.391468 -509.959933) (xy 31.399486 -510.046462) (xy 31.399486 -510.133362) (xy 34.599874 -510.133362)
			(xy 34.599874 -510.046462) (xy 34.607892 -509.959933) (xy 34.62386 -509.874513) (xy 34.647641 -509.790931)
			(xy 34.679033 -509.709899) (xy 34.717767 -509.63211) (xy 34.763514 -509.558226) (xy 34.815883 -509.488879)
			(xy 34.874427 -509.424659) (xy 34.938647 -509.366115) (xy 35.007994 -509.313746) (xy 35.081878 -509.267999)
			(xy 35.159667 -509.229265) (xy 35.240699 -509.197873) (xy 35.324281 -509.174092) (xy 35.409701 -509.158124)
			(xy 35.49623 -509.150106) (xy 35.53968 -509.149604) (xy 35.58313 -509.150106) (xy 35.669659 -509.158124)
			(xy 35.755079 -509.174092) (xy 35.838661 -509.197873) (xy 35.919693 -509.229265) (xy 35.997482 -509.267999)
			(xy 36.071366 -509.313746) (xy 36.140713 -509.366115) (xy 36.204933 -509.424659) (xy 36.263477 -509.488879)
			(xy 36.315846 -509.558226) (xy 36.361593 -509.63211) (xy 36.400327 -509.709899) (xy 36.431719 -509.790931)
			(xy 36.4555 -509.874513) (xy 36.471468 -509.959933) (xy 36.479486 -510.046462) (xy 36.479486 -510.133362)
			(xy 36.471468 -510.219891) (xy 36.4555 -510.305311) (xy 36.431719 -510.388893) (xy 36.400327 -510.469925)
			(xy 36.361593 -510.547714) (xy 36.315846 -510.621598) (xy 36.263477 -510.690945) (xy 36.204933 -510.755165)
			(xy 36.140713 -510.813709) (xy 36.071366 -510.866078) (xy 35.997482 -510.911825) (xy 35.919693 -510.950559)
			(xy 35.838661 -510.981951) (xy 35.755079 -511.005732) (xy 35.669659 -511.0217) (xy 35.58313 -511.029718)
			(xy 35.49623 -511.029718) (xy 35.409701 -511.0217) (xy 35.324281 -511.005732) (xy 35.240699 -510.981951)
			(xy 35.159667 -510.950559) (xy 35.081878 -510.911825) (xy 35.007994 -510.866078) (xy 34.938647 -510.813709)
			(xy 34.874427 -510.755165) (xy 34.815883 -510.690945) (xy 34.763514 -510.621598) (xy 34.717767 -510.547714)
			(xy 34.679033 -510.469925) (xy 34.647641 -510.388893) (xy 34.62386 -510.305311) (xy 34.607892 -510.219891)
			(xy 34.599874 -510.133362) (xy 31.399486 -510.133362) (xy 31.391468 -510.219891) (xy 31.3755 -510.305311)
			(xy 31.351719 -510.388893) (xy 31.320327 -510.469925) (xy 31.281593 -510.547714) (xy 31.235846 -510.621598)
			(xy 31.183477 -510.690945) (xy 31.124933 -510.755165) (xy 31.060713 -510.813709) (xy 30.991366 -510.866078)
			(xy 30.917482 -510.911825) (xy 30.839693 -510.950559) (xy 30.758661 -510.981951) (xy 30.675079 -511.005732)
			(xy 30.589659 -511.0217) (xy 30.50313 -511.029718) (xy 30.41623 -511.029718) (xy 30.329701 -511.0217)
			(xy 30.244281 -511.005732) (xy 30.160699 -510.981951) (xy 30.079667 -510.950559) (xy 30.001878 -510.911825)
			(xy 29.927994 -510.866078) (xy 29.858647 -510.813709) (xy 29.794427 -510.755165) (xy 29.735883 -510.690945)
			(xy 29.683514 -510.621598) (xy 29.637767 -510.547714) (xy 29.599033 -510.469925) (xy 29.567641 -510.388893)
			(xy 29.54386 -510.305311) (xy 29.527892 -510.219891) (xy 29.519874 -510.133362) (xy 12.84959 -510.133362)
			(xy 10.30959 -512.673362) (xy 29.519874 -512.673362) (xy 29.519874 -512.586462) (xy 29.527892 -512.499933)
			(xy 29.54386 -512.414513) (xy 29.567641 -512.330931) (xy 29.599033 -512.249899) (xy 29.637767 -512.17211)
			(xy 29.683514 -512.098226) (xy 29.735883 -512.028879) (xy 29.794427 -511.964659) (xy 29.858647 -511.906115)
			(xy 29.927994 -511.853746) (xy 30.001878 -511.807999) (xy 30.079667 -511.769265) (xy 30.160699 -511.737873)
			(xy 30.244281 -511.714092) (xy 30.329701 -511.698124) (xy 30.41623 -511.690106) (xy 30.45968 -511.689604)
			(xy 30.50313 -511.690106) (xy 30.589659 -511.698124) (xy 30.675079 -511.714092) (xy 30.758661 -511.737873)
			(xy 30.839693 -511.769265) (xy 30.917482 -511.807999) (xy 30.991366 -511.853746) (xy 31.060713 -511.906115)
			(xy 31.124933 -511.964659) (xy 31.183477 -512.028879) (xy 31.235846 -512.098226) (xy 31.281593 -512.17211)
			(xy 31.320327 -512.249899) (xy 31.351719 -512.330931) (xy 31.3755 -512.414513) (xy 31.391468 -512.499933)
			(xy 31.399486 -512.586462) (xy 31.399486 -512.673362) (xy 34.599874 -512.673362) (xy 34.599874 -512.586462)
			(xy 34.607892 -512.499933) (xy 34.62386 -512.414513) (xy 34.647641 -512.330931) (xy 34.679033 -512.249899)
			(xy 34.717767 -512.17211) (xy 34.763514 -512.098226) (xy 34.815883 -512.028879) (xy 34.874427 -511.964659)
			(xy 34.938647 -511.906115) (xy 35.007994 -511.853746) (xy 35.081878 -511.807999) (xy 35.159667 -511.769265)
			(xy 35.240699 -511.737873) (xy 35.324281 -511.714092) (xy 35.409701 -511.698124) (xy 35.49623 -511.690106)
			(xy 35.53968 -511.689604) (xy 35.58313 -511.690106) (xy 35.669659 -511.698124) (xy 35.755079 -511.714092)
			(xy 35.838661 -511.737873) (xy 35.919693 -511.769265) (xy 35.997482 -511.807999) (xy 36.071366 -511.853746)
			(xy 36.140713 -511.906115) (xy 36.204933 -511.964659) (xy 36.263477 -512.028879) (xy 36.315846 -512.098226)
			(xy 36.361593 -512.17211) (xy 36.400327 -512.249899) (xy 36.431719 -512.330931) (xy 36.4555 -512.414513)
			(xy 36.471468 -512.499933) (xy 36.479486 -512.586462) (xy 36.479486 -512.673362) (xy 36.471468 -512.759891)
			(xy 36.4555 -512.845311) (xy 36.431719 -512.928893) (xy 36.400327 -513.009925) (xy 36.361593 -513.087714)
			(xy 36.315846 -513.161598) (xy 36.263477 -513.230945) (xy 36.204933 -513.295165) (xy 36.140713 -513.353709)
			(xy 36.131362 -513.360771) (xy 56.406534 -513.360771) (xy 56.406534 -513.289449) (xy 56.41452 -513.218575)
			(xy 56.43039 -513.14904) (xy 56.453947 -513.08172) (xy 56.484892 -513.017461) (xy 56.522838 -512.95707)
			(xy 56.567307 -512.901308) (xy 56.61774 -512.850875) (xy 56.673502 -512.806406) (xy 56.733893 -512.76846)
			(xy 56.798152 -512.737515) (xy 56.865472 -512.713958) (xy 56.935007 -512.698088) (xy 57.005881 -512.690102)
			(xy 57.041542 -512.689602) (xy 57.077203 -512.690102) (xy 57.148077 -512.698088) (xy 57.217612 -512.713958)
			(xy 57.284932 -512.737515) (xy 57.349191 -512.76846) (xy 57.409582 -512.806406) (xy 57.465344 -512.850875)
			(xy 57.515777 -512.901308) (xy 57.560246 -512.95707) (xy 57.598192 -513.017461) (xy 57.629137 -513.08172)
			(xy 57.652694 -513.14904) (xy 57.668564 -513.218575) (xy 57.67655 -513.289449) (xy 57.67655 -513.360771)
			(xy 58.938406 -513.360771) (xy 58.938406 -513.289449) (xy 58.946392 -513.218575) (xy 58.962262 -513.14904)
			(xy 58.985819 -513.08172) (xy 59.016764 -513.017461) (xy 59.05471 -512.95707) (xy 59.099179 -512.901308)
			(xy 59.149612 -512.850875) (xy 59.205374 -512.806406) (xy 59.265765 -512.76846) (xy 59.330024 -512.737515)
			(xy 59.397344 -512.713958) (xy 59.466879 -512.698088) (xy 59.537753 -512.690102) (xy 59.573414 -512.689602)
			(xy 59.609075 -512.690102) (xy 59.679949 -512.698088) (xy 59.749484 -512.713958) (xy 59.816804 -512.737515)
			(xy 59.881063 -512.76846) (xy 59.941454 -512.806406) (xy 59.997216 -512.850875) (xy 60.047649 -512.901308)
			(xy 60.092118 -512.95707) (xy 60.130064 -513.017461) (xy 60.161009 -513.08172) (xy 60.184566 -513.14904)
			(xy 60.200436 -513.218575) (xy 60.208422 -513.289449) (xy 60.208422 -513.360771) (xy 61.74282 -513.360771)
			(xy 61.74282 -513.289449) (xy 61.750806 -513.218575) (xy 61.766676 -513.14904) (xy 61.790233 -513.08172)
			(xy 61.821178 -513.017461) (xy 61.859124 -512.95707) (xy 61.903593 -512.901308) (xy 61.954026 -512.850875)
			(xy 62.009788 -512.806406) (xy 62.070179 -512.76846) (xy 62.134438 -512.737515) (xy 62.201758 -512.713958)
			(xy 62.271293 -512.698088) (xy 62.342167 -512.690102) (xy 62.377828 -512.689602) (xy 62.413489 -512.690102)
			(xy 62.484363 -512.698088) (xy 62.553898 -512.713958) (xy 62.621218 -512.737515) (xy 62.685477 -512.76846)
			(xy 62.745868 -512.806406) (xy 62.80163 -512.850875) (xy 62.852063 -512.901308) (xy 62.896532 -512.95707)
			(xy 62.934478 -513.017461) (xy 62.965423 -513.08172) (xy 62.98898 -513.14904) (xy 63.00485 -513.218575)
			(xy 63.012836 -513.289449) (xy 63.012836 -513.360771) (xy 64.98259 -513.360771) (xy 64.98259 -513.289449)
			(xy 64.990576 -513.218575) (xy 65.006446 -513.14904) (xy 65.030003 -513.08172) (xy 65.060948 -513.017461)
			(xy 65.098894 -512.95707) (xy 65.143363 -512.901308) (xy 65.193796 -512.850875) (xy 65.249558 -512.806406)
			(xy 65.309949 -512.76846) (xy 65.374208 -512.737515) (xy 65.441528 -512.713958) (xy 65.511063 -512.698088)
			(xy 65.581937 -512.690102) (xy 65.617598 -512.689602) (xy 65.653259 -512.690102) (xy 65.724133 -512.698088)
			(xy 65.793668 -512.713958) (xy 65.860988 -512.737515) (xy 65.925247 -512.76846) (xy 65.985638 -512.806406)
			(xy 66.0414 -512.850875) (xy 66.091833 -512.901308) (xy 66.136302 -512.95707) (xy 66.174248 -513.017461)
			(xy 66.205193 -513.08172) (xy 66.22875 -513.14904) (xy 66.24462 -513.218575) (xy 66.252606 -513.289449)
			(xy 66.252606 -513.360771) (xy 67.974202 -513.360771) (xy 67.974202 -513.289449) (xy 67.982188 -513.218575)
			(xy 67.998058 -513.14904) (xy 68.021615 -513.08172) (xy 68.05256 -513.017461) (xy 68.090506 -512.95707)
			(xy 68.134975 -512.901308) (xy 68.185408 -512.850875) (xy 68.24117 -512.806406) (xy 68.301561 -512.76846)
			(xy 68.36582 -512.737515) (xy 68.43314 -512.713958) (xy 68.502675 -512.698088) (xy 68.573549 -512.690102)
			(xy 68.60921 -512.689602) (xy 68.644871 -512.690102) (xy 68.715745 -512.698088) (xy 68.78528 -512.713958)
			(xy 68.8526 -512.737515) (xy 68.916859 -512.76846) (xy 68.97725 -512.806406) (xy 69.033012 -512.850875)
			(xy 69.083445 -512.901308) (xy 69.127914 -512.95707) (xy 69.16586 -513.017461) (xy 69.196805 -513.08172)
			(xy 69.220362 -513.14904) (xy 69.236232 -513.218575) (xy 69.244218 -513.289449) (xy 69.244218 -513.360771)
			(xy 69.236232 -513.431645) (xy 69.220362 -513.50118) (xy 69.196805 -513.5685) (xy 69.16586 -513.632759)
			(xy 69.127914 -513.69315) (xy 69.083445 -513.748912) (xy 69.033012 -513.799345) (xy 68.97725 -513.843814)
			(xy 68.916859 -513.88176) (xy 68.8526 -513.912705) (xy 68.78528 -513.936262) (xy 68.715745 -513.952132)
			(xy 68.644871 -513.960118) (xy 68.573549 -513.960118) (xy 68.502675 -513.952132) (xy 68.43314 -513.936262)
			(xy 68.36582 -513.912705) (xy 68.301561 -513.88176) (xy 68.24117 -513.843814) (xy 68.185408 -513.799345)
			(xy 68.134975 -513.748912) (xy 68.090506 -513.69315) (xy 68.05256 -513.632759) (xy 68.021615 -513.5685)
			(xy 67.998058 -513.50118) (xy 67.982188 -513.431645) (xy 67.974202 -513.360771) (xy 66.252606 -513.360771)
			(xy 66.24462 -513.431645) (xy 66.22875 -513.50118) (xy 66.205193 -513.5685) (xy 66.174248 -513.632759)
			(xy 66.136302 -513.69315) (xy 66.091833 -513.748912) (xy 66.0414 -513.799345) (xy 65.985638 -513.843814)
			(xy 65.925247 -513.88176) (xy 65.860988 -513.912705) (xy 65.793668 -513.936262) (xy 65.724133 -513.952132)
			(xy 65.653259 -513.960118) (xy 65.581937 -513.960118) (xy 65.511063 -513.952132) (xy 65.441528 -513.936262)
			(xy 65.374208 -513.912705) (xy 65.309949 -513.88176) (xy 65.249558 -513.843814) (xy 65.193796 -513.799345)
			(xy 65.143363 -513.748912) (xy 65.098894 -513.69315) (xy 65.060948 -513.632759) (xy 65.030003 -513.5685)
			(xy 65.006446 -513.50118) (xy 64.990576 -513.431645) (xy 64.98259 -513.360771) (xy 63.012836 -513.360771)
			(xy 63.00485 -513.431645) (xy 62.98898 -513.50118) (xy 62.965423 -513.5685) (xy 62.934478 -513.632759)
			(xy 62.896532 -513.69315) (xy 62.852063 -513.748912) (xy 62.80163 -513.799345) (xy 62.745868 -513.843814)
			(xy 62.685477 -513.88176) (xy 62.621218 -513.912705) (xy 62.553898 -513.936262) (xy 62.484363 -513.952132)
			(xy 62.413489 -513.960118) (xy 62.342167 -513.960118) (xy 62.271293 -513.952132) (xy 62.201758 -513.936262)
			(xy 62.134438 -513.912705) (xy 62.070179 -513.88176) (xy 62.009788 -513.843814) (xy 61.954026 -513.799345)
			(xy 61.903593 -513.748912) (xy 61.859124 -513.69315) (xy 61.821178 -513.632759) (xy 61.790233 -513.5685)
			(xy 61.766676 -513.50118) (xy 61.750806 -513.431645) (xy 61.74282 -513.360771) (xy 60.208422 -513.360771)
			(xy 60.200436 -513.431645) (xy 60.184566 -513.50118) (xy 60.161009 -513.5685) (xy 60.130064 -513.632759)
			(xy 60.092118 -513.69315) (xy 60.047649 -513.748912) (xy 59.997216 -513.799345) (xy 59.941454 -513.843814)
			(xy 59.881063 -513.88176) (xy 59.816804 -513.912705) (xy 59.749484 -513.936262) (xy 59.679949 -513.952132)
			(xy 59.609075 -513.960118) (xy 59.537753 -513.960118) (xy 59.466879 -513.952132) (xy 59.397344 -513.936262)
			(xy 59.330024 -513.912705) (xy 59.265765 -513.88176) (xy 59.205374 -513.843814) (xy 59.149612 -513.799345)
			(xy 59.099179 -513.748912) (xy 59.05471 -513.69315) (xy 59.016764 -513.632759) (xy 58.985819 -513.5685)
			(xy 58.962262 -513.50118) (xy 58.946392 -513.431645) (xy 58.938406 -513.360771) (xy 57.67655 -513.360771)
			(xy 57.668564 -513.431645) (xy 57.652694 -513.50118) (xy 57.629137 -513.5685) (xy 57.598192 -513.632759)
			(xy 57.560246 -513.69315) (xy 57.515777 -513.748912) (xy 57.465344 -513.799345) (xy 57.409582 -513.843814)
			(xy 57.349191 -513.88176) (xy 57.284932 -513.912705) (xy 57.217612 -513.936262) (xy 57.148077 -513.952132)
			(xy 57.077203 -513.960118) (xy 57.005881 -513.960118) (xy 56.935007 -513.952132) (xy 56.865472 -513.936262)
			(xy 56.798152 -513.912705) (xy 56.733893 -513.88176) (xy 56.673502 -513.843814) (xy 56.61774 -513.799345)
			(xy 56.567307 -513.748912) (xy 56.522838 -513.69315) (xy 56.484892 -513.632759) (xy 56.453947 -513.5685)
			(xy 56.43039 -513.50118) (xy 56.41452 -513.431645) (xy 56.406534 -513.360771) (xy 36.131362 -513.360771)
			(xy 36.071366 -513.406078) (xy 35.997482 -513.451825) (xy 35.919693 -513.490559) (xy 35.838661 -513.521951)
			(xy 35.755079 -513.545732) (xy 35.669659 -513.5617) (xy 35.58313 -513.569718) (xy 35.49623 -513.569718)
			(xy 35.409701 -513.5617) (xy 35.324281 -513.545732) (xy 35.240699 -513.521951) (xy 35.159667 -513.490559)
			(xy 35.081878 -513.451825) (xy 35.007994 -513.406078) (xy 34.938647 -513.353709) (xy 34.874427 -513.295165)
			(xy 34.815883 -513.230945) (xy 34.763514 -513.161598) (xy 34.717767 -513.087714) (xy 34.679033 -513.009925)
			(xy 34.647641 -512.928893) (xy 34.62386 -512.845311) (xy 34.607892 -512.759891) (xy 34.599874 -512.673362)
			(xy 31.399486 -512.673362) (xy 31.391468 -512.759891) (xy 31.3755 -512.845311) (xy 31.351719 -512.928893)
			(xy 31.320327 -513.009925) (xy 31.281593 -513.087714) (xy 31.235846 -513.161598) (xy 31.183477 -513.230945)
			(xy 31.124933 -513.295165) (xy 31.060713 -513.353709) (xy 30.991366 -513.406078) (xy 30.917482 -513.451825)
			(xy 30.839693 -513.490559) (xy 30.758661 -513.521951) (xy 30.675079 -513.545732) (xy 30.589659 -513.5617)
			(xy 30.50313 -513.569718) (xy 30.41623 -513.569718) (xy 30.329701 -513.5617) (xy 30.244281 -513.545732)
			(xy 30.160699 -513.521951) (xy 30.079667 -513.490559) (xy 30.001878 -513.451825) (xy 29.927994 -513.406078)
			(xy 29.858647 -513.353709) (xy 29.794427 -513.295165) (xy 29.735883 -513.230945) (xy 29.683514 -513.161598)
			(xy 29.637767 -513.087714) (xy 29.599033 -513.009925) (xy 29.567641 -512.928893) (xy 29.54386 -512.845311)
			(xy 29.527892 -512.759891) (xy 29.519874 -512.673362) (xy 10.30959 -512.673362) (xy 9.530588 -513.452364)
			(xy 9.530588 -514.804305) (xy 12.580876 -514.804305) (xy 12.582892 -514.674692) (xy 12.592962 -514.545456)
			(xy 12.611047 -514.417095) (xy 12.637077 -514.290107) (xy 12.670952 -514.164983) (xy 12.71254 -514.042207)
			(xy 12.761681 -513.922254) (xy 12.818184 -513.805589) (xy 12.881831 -513.692661) (xy 12.952375 -513.583909)
			(xy 13.029544 -513.479753) (xy 13.113039 -513.380596) (xy 13.202537 -513.286822) (xy 13.297692 -513.198793)
			(xy 13.398135 -513.11685) (xy 13.503478 -513.041311) (xy 13.613314 -512.972466) (xy 13.727218 -512.910583)
			(xy 13.844748 -512.855902) (xy 13.965451 -512.808632) (xy 14.088859 -512.768959) (xy 14.214495 -512.737034)
			(xy 14.341872 -512.712982) (xy 14.470498 -512.696895) (xy 14.599876 -512.688836) (xy 14.66469 -512.688332)
			(xy 14.729504 -512.688836) (xy 14.858882 -512.696895) (xy 14.987508 -512.712982) (xy 15.114885 -512.737034)
			(xy 15.240521 -512.768959) (xy 15.363929 -512.808632) (xy 15.484632 -512.855902) (xy 15.602162 -512.910583)
			(xy 15.716066 -512.972466) (xy 15.825902 -513.041311) (xy 15.931245 -513.11685) (xy 16.031688 -513.198793)
			(xy 16.126843 -513.286822) (xy 16.216341 -513.380596) (xy 16.299836 -513.479753) (xy 16.377005 -513.583909)
			(xy 16.447549 -513.692661) (xy 16.511196 -513.805589) (xy 16.567699 -513.922254) (xy 16.61684 -514.042207)
			(xy 16.658428 -514.164983) (xy 16.692303 -514.290107) (xy 16.718333 -514.417095) (xy 16.736418 -514.545456)
			(xy 16.746488 -514.674692) (xy 16.748504 -514.804305) (xy 16.742458 -514.933792) (xy 16.728374 -515.062653)
			(xy 16.706305 -515.190389) (xy 16.700846 -515.213362) (xy 29.519874 -515.213362) (xy 29.519874 -515.126462)
			(xy 29.527892 -515.039933) (xy 29.54386 -514.954513) (xy 29.567641 -514.870931) (xy 29.599033 -514.789899)
			(xy 29.637767 -514.71211) (xy 29.683514 -514.638226) (xy 29.735883 -514.568879) (xy 29.794427 -514.504659)
			(xy 29.858647 -514.446115) (xy 29.927994 -514.393746) (xy 30.001878 -514.347999) (xy 30.079667 -514.309265)
			(xy 30.160699 -514.277873) (xy 30.244281 -514.254092) (xy 30.329701 -514.238124) (xy 30.41623 -514.230106)
			(xy 30.45968 -514.229604) (xy 30.50313 -514.230106) (xy 30.589659 -514.238124) (xy 30.675079 -514.254092)
			(xy 30.758661 -514.277873) (xy 30.839693 -514.309265) (xy 30.917482 -514.347999) (xy 30.991366 -514.393746)
			(xy 31.060713 -514.446115) (xy 31.124933 -514.504659) (xy 31.183477 -514.568879) (xy 31.235846 -514.638226)
			(xy 31.281593 -514.71211) (xy 31.320327 -514.789899) (xy 31.351719 -514.870931) (xy 31.3755 -514.954513)
			(xy 31.391468 -515.039933) (xy 31.399486 -515.126462) (xy 31.399486 -515.213362) (xy 34.599874 -515.213362)
			(xy 34.599874 -515.126462) (xy 34.607892 -515.039933) (xy 34.62386 -514.954513) (xy 34.647641 -514.870931)
			(xy 34.679033 -514.789899) (xy 34.717767 -514.71211) (xy 34.763514 -514.638226) (xy 34.815883 -514.568879)
			(xy 34.874427 -514.504659) (xy 34.938647 -514.446115) (xy 35.007994 -514.393746) (xy 35.081878 -514.347999)
			(xy 35.159667 -514.309265) (xy 35.240699 -514.277873) (xy 35.324281 -514.254092) (xy 35.409701 -514.238124)
			(xy 35.49623 -514.230106) (xy 35.53968 -514.229604) (xy 35.58313 -514.230106) (xy 35.669659 -514.238124)
			(xy 35.755079 -514.254092) (xy 35.838661 -514.277873) (xy 35.919693 -514.309265) (xy 35.997482 -514.347999)
			(xy 36.071366 -514.393746) (xy 36.140713 -514.446115) (xy 36.204933 -514.504659) (xy 36.263477 -514.568879)
			(xy 36.315846 -514.638226) (xy 36.361593 -514.71211) (xy 36.400327 -514.789899) (xy 36.431719 -514.870931)
			(xy 36.4555 -514.954513) (xy 36.471468 -515.039933) (xy 36.479486 -515.126462) (xy 36.479486 -515.213362)
			(xy 36.471468 -515.299891) (xy 36.4555 -515.385311) (xy 36.431719 -515.468893) (xy 36.400327 -515.549925)
			(xy 36.361593 -515.627714) (xy 36.315846 -515.701598) (xy 36.263477 -515.770945) (xy 36.204933 -515.835165)
			(xy 36.140713 -515.893709) (xy 36.071366 -515.946078) (xy 35.997482 -515.991825) (xy 35.919693 -516.030559)
			(xy 35.917055 -516.031581) (xy 56.406534 -516.031581) (xy 56.406534 -515.960259) (xy 56.41452 -515.889385)
			(xy 56.43039 -515.81985) (xy 56.453947 -515.75253) (xy 56.484892 -515.688271) (xy 56.522838 -515.62788)
			(xy 56.567307 -515.572118) (xy 56.61774 -515.521685) (xy 56.673502 -515.477216) (xy 56.733893 -515.43927)
			(xy 56.798152 -515.408325) (xy 56.865472 -515.384768) (xy 56.935007 -515.368898) (xy 57.005881 -515.360912)
			(xy 57.041542 -515.360412) (xy 57.077203 -515.360912) (xy 57.148077 -515.368898) (xy 57.217612 -515.384768)
			(xy 57.284932 -515.408325) (xy 57.349191 -515.43927) (xy 57.409582 -515.477216) (xy 57.465344 -515.521685)
			(xy 57.515777 -515.572118) (xy 57.560246 -515.62788) (xy 57.598192 -515.688271) (xy 57.629137 -515.75253)
			(xy 57.652694 -515.81985) (xy 57.668564 -515.889385) (xy 57.67655 -515.960259) (xy 57.67655 -516.031581)
			(xy 58.938406 -516.031581) (xy 58.938406 -515.960259) (xy 58.946392 -515.889385) (xy 58.962262 -515.81985)
			(xy 58.985819 -515.75253) (xy 59.016764 -515.688271) (xy 59.05471 -515.62788) (xy 59.099179 -515.572118)
			(xy 59.149612 -515.521685) (xy 59.205374 -515.477216) (xy 59.265765 -515.43927) (xy 59.330024 -515.408325)
			(xy 59.397344 -515.384768) (xy 59.466879 -515.368898) (xy 59.537753 -515.360912) (xy 59.573414 -515.360412)
			(xy 59.609075 -515.360912) (xy 59.679949 -515.368898) (xy 59.749484 -515.384768) (xy 59.816804 -515.408325)
			(xy 59.881063 -515.43927) (xy 59.941454 -515.477216) (xy 59.997216 -515.521685) (xy 60.047649 -515.572118)
			(xy 60.092118 -515.62788) (xy 60.130064 -515.688271) (xy 60.161009 -515.75253) (xy 60.184566 -515.81985)
			(xy 60.200436 -515.889385) (xy 60.208422 -515.960259) (xy 60.208422 -516.031581) (xy 61.74282 -516.031581)
			(xy 61.74282 -515.960259) (xy 61.750806 -515.889385) (xy 61.766676 -515.81985) (xy 61.790233 -515.75253)
			(xy 61.821178 -515.688271) (xy 61.859124 -515.62788) (xy 61.903593 -515.572118) (xy 61.954026 -515.521685)
			(xy 62.009788 -515.477216) (xy 62.070179 -515.43927) (xy 62.134438 -515.408325) (xy 62.201758 -515.384768)
			(xy 62.271293 -515.368898) (xy 62.342167 -515.360912) (xy 62.377828 -515.360412) (xy 62.413489 -515.360912)
			(xy 62.484363 -515.368898) (xy 62.553898 -515.384768) (xy 62.621218 -515.408325) (xy 62.685477 -515.43927)
			(xy 62.745868 -515.477216) (xy 62.80163 -515.521685) (xy 62.852063 -515.572118) (xy 62.896532 -515.62788)
			(xy 62.934478 -515.688271) (xy 62.965423 -515.75253) (xy 62.98898 -515.81985) (xy 63.00485 -515.889385)
			(xy 63.012836 -515.960259) (xy 63.012836 -516.031581) (xy 64.98259 -516.031581) (xy 64.98259 -515.960259)
			(xy 64.990576 -515.889385) (xy 65.006446 -515.81985) (xy 65.030003 -515.75253) (xy 65.060948 -515.688271)
			(xy 65.098894 -515.62788) (xy 65.143363 -515.572118) (xy 65.193796 -515.521685) (xy 65.249558 -515.477216)
			(xy 65.309949 -515.43927) (xy 65.374208 -515.408325) (xy 65.441528 -515.384768) (xy 65.511063 -515.368898)
			(xy 65.581937 -515.360912) (xy 65.617598 -515.360412) (xy 65.653259 -515.360912) (xy 65.724133 -515.368898)
			(xy 65.793668 -515.384768) (xy 65.860988 -515.408325) (xy 65.925247 -515.43927) (xy 65.985638 -515.477216)
			(xy 66.0414 -515.521685) (xy 66.091833 -515.572118) (xy 66.136302 -515.62788) (xy 66.174248 -515.688271)
			(xy 66.205193 -515.75253) (xy 66.22875 -515.81985) (xy 66.24462 -515.889385) (xy 66.252606 -515.960259)
			(xy 66.252606 -516.031581) (xy 67.974202 -516.031581) (xy 67.974202 -515.960259) (xy 67.982188 -515.889385)
			(xy 67.998058 -515.81985) (xy 68.021615 -515.75253) (xy 68.05256 -515.688271) (xy 68.090506 -515.62788)
			(xy 68.134975 -515.572118) (xy 68.185408 -515.521685) (xy 68.24117 -515.477216) (xy 68.301561 -515.43927)
			(xy 68.36582 -515.408325) (xy 68.43314 -515.384768) (xy 68.502675 -515.368898) (xy 68.573549 -515.360912)
			(xy 68.60921 -515.360412) (xy 68.644871 -515.360912) (xy 68.715745 -515.368898) (xy 68.78528 -515.384768)
			(xy 68.8526 -515.408325) (xy 68.916859 -515.43927) (xy 68.97725 -515.477216) (xy 69.033012 -515.521685)
			(xy 69.083445 -515.572118) (xy 69.127914 -515.62788) (xy 69.16586 -515.688271) (xy 69.196805 -515.75253)
			(xy 69.220362 -515.81985) (xy 69.236232 -515.889385) (xy 69.244218 -515.960259) (xy 69.244218 -516.031581)
			(xy 69.236232 -516.102455) (xy 69.220362 -516.17199) (xy 69.196805 -516.23931) (xy 69.16586 -516.303569)
			(xy 69.127914 -516.36396) (xy 69.083445 -516.419722) (xy 69.033012 -516.470155) (xy 68.97725 -516.514624)
			(xy 68.916859 -516.55257) (xy 68.8526 -516.583515) (xy 68.78528 -516.607072) (xy 68.715745 -516.622942)
			(xy 68.644871 -516.630928) (xy 68.573549 -516.630928) (xy 68.502675 -516.622942) (xy 68.43314 -516.607072)
			(xy 68.36582 -516.583515) (xy 68.301561 -516.55257) (xy 68.24117 -516.514624) (xy 68.185408 -516.470155)
			(xy 68.134975 -516.419722) (xy 68.090506 -516.36396) (xy 68.05256 -516.303569) (xy 68.021615 -516.23931)
			(xy 67.998058 -516.17199) (xy 67.982188 -516.102455) (xy 67.974202 -516.031581) (xy 66.252606 -516.031581)
			(xy 66.24462 -516.102455) (xy 66.22875 -516.17199) (xy 66.205193 -516.23931) (xy 66.174248 -516.303569)
			(xy 66.136302 -516.36396) (xy 66.091833 -516.419722) (xy 66.0414 -516.470155) (xy 65.985638 -516.514624)
			(xy 65.925247 -516.55257) (xy 65.860988 -516.583515) (xy 65.793668 -516.607072) (xy 65.724133 -516.622942)
			(xy 65.653259 -516.630928) (xy 65.581937 -516.630928) (xy 65.511063 -516.622942) (xy 65.441528 -516.607072)
			(xy 65.374208 -516.583515) (xy 65.309949 -516.55257) (xy 65.249558 -516.514624) (xy 65.193796 -516.470155)
			(xy 65.143363 -516.419722) (xy 65.098894 -516.36396) (xy 65.060948 -516.303569) (xy 65.030003 -516.23931)
			(xy 65.006446 -516.17199) (xy 64.990576 -516.102455) (xy 64.98259 -516.031581) (xy 63.012836 -516.031581)
			(xy 63.00485 -516.102455) (xy 62.98898 -516.17199) (xy 62.965423 -516.23931) (xy 62.934478 -516.303569)
			(xy 62.896532 -516.36396) (xy 62.852063 -516.419722) (xy 62.80163 -516.470155) (xy 62.745868 -516.514624)
			(xy 62.685477 -516.55257) (xy 62.621218 -516.583515) (xy 62.553898 -516.607072) (xy 62.484363 -516.622942)
			(xy 62.413489 -516.630928) (xy 62.342167 -516.630928) (xy 62.271293 -516.622942) (xy 62.201758 -516.607072)
			(xy 62.134438 -516.583515) (xy 62.070179 -516.55257) (xy 62.009788 -516.514624) (xy 61.954026 -516.470155)
			(xy 61.903593 -516.419722) (xy 61.859124 -516.36396) (xy 61.821178 -516.303569) (xy 61.790233 -516.23931)
			(xy 61.766676 -516.17199) (xy 61.750806 -516.102455) (xy 61.74282 -516.031581) (xy 60.208422 -516.031581)
			(xy 60.200436 -516.102455) (xy 60.184566 -516.17199) (xy 60.161009 -516.23931) (xy 60.130064 -516.303569)
			(xy 60.092118 -516.36396) (xy 60.047649 -516.419722) (xy 59.997216 -516.470155) (xy 59.941454 -516.514624)
			(xy 59.881063 -516.55257) (xy 59.816804 -516.583515) (xy 59.749484 -516.607072) (xy 59.679949 -516.622942)
			(xy 59.609075 -516.630928) (xy 59.537753 -516.630928) (xy 59.466879 -516.622942) (xy 59.397344 -516.607072)
			(xy 59.330024 -516.583515) (xy 59.265765 -516.55257) (xy 59.205374 -516.514624) (xy 59.149612 -516.470155)
			(xy 59.099179 -516.419722) (xy 59.05471 -516.36396) (xy 59.016764 -516.303569) (xy 58.985819 -516.23931)
			(xy 58.962262 -516.17199) (xy 58.946392 -516.102455) (xy 58.938406 -516.031581) (xy 57.67655 -516.031581)
			(xy 57.668564 -516.102455) (xy 57.652694 -516.17199) (xy 57.629137 -516.23931) (xy 57.598192 -516.303569)
			(xy 57.560246 -516.36396) (xy 57.515777 -516.419722) (xy 57.465344 -516.470155) (xy 57.409582 -516.514624)
			(xy 57.349191 -516.55257) (xy 57.284932 -516.583515) (xy 57.217612 -516.607072) (xy 57.148077 -516.622942)
			(xy 57.077203 -516.630928) (xy 57.005881 -516.630928) (xy 56.935007 -516.622942) (xy 56.865472 -516.607072)
			(xy 56.798152 -516.583515) (xy 56.733893 -516.55257) (xy 56.673502 -516.514624) (xy 56.61774 -516.470155)
			(xy 56.567307 -516.419722) (xy 56.522838 -516.36396) (xy 56.484892 -516.303569) (xy 56.453947 -516.23931)
			(xy 56.43039 -516.17199) (xy 56.41452 -516.102455) (xy 56.406534 -516.031581) (xy 35.917055 -516.031581)
			(xy 35.838661 -516.061951) (xy 35.755079 -516.085732) (xy 35.669659 -516.1017) (xy 35.58313 -516.109718)
			(xy 35.49623 -516.109718) (xy 35.409701 -516.1017) (xy 35.324281 -516.085732) (xy 35.240699 -516.061951)
			(xy 35.159667 -516.030559) (xy 35.081878 -515.991825) (xy 35.007994 -515.946078) (xy 34.938647 -515.893709)
			(xy 34.874427 -515.835165) (xy 34.815883 -515.770945) (xy 34.763514 -515.701598) (xy 34.717767 -515.627714)
			(xy 34.679033 -515.549925) (xy 34.647641 -515.468893) (xy 34.62386 -515.385311) (xy 34.607892 -515.299891)
			(xy 34.599874 -515.213362) (xy 31.399486 -515.213362) (xy 31.391468 -515.299891) (xy 31.3755 -515.385311)
			(xy 31.351719 -515.468893) (xy 31.320327 -515.549925) (xy 31.281593 -515.627714) (xy 31.235846 -515.701598)
			(xy 31.183477 -515.770945) (xy 31.124933 -515.835165) (xy 31.060713 -515.893709) (xy 30.991366 -515.946078)
			(xy 30.917482 -515.991825) (xy 30.839693 -516.030559) (xy 30.758661 -516.061951) (xy 30.675079 -516.085732)
			(xy 30.589659 -516.1017) (xy 30.50313 -516.109718) (xy 30.41623 -516.109718) (xy 30.329701 -516.1017)
			(xy 30.244281 -516.085732) (xy 30.160699 -516.061951) (xy 30.079667 -516.030559) (xy 30.001878 -515.991825)
			(xy 29.927994 -515.946078) (xy 29.858647 -515.893709) (xy 29.794427 -515.835165) (xy 29.735883 -515.770945)
			(xy 29.683514 -515.701598) (xy 29.637767 -515.627714) (xy 29.599033 -515.549925) (xy 29.567641 -515.468893)
			(xy 29.54386 -515.385311) (xy 29.527892 -515.299891) (xy 29.519874 -515.213362) (xy 16.700846 -515.213362)
			(xy 16.676338 -515.316506) (xy 16.638589 -515.440516) (xy 16.593202 -515.561939) (xy 16.540355 -515.680306)
			(xy 16.480251 -515.795158) (xy 16.413123 -515.906051) (xy 16.339231 -516.012557) (xy 16.25886 -516.114263)
			(xy 16.172322 -516.210775) (xy 16.07995 -516.30172) (xy 15.982104 -516.386747) (xy 15.879161 -516.465527)
			(xy 15.771519 -516.537754) (xy 15.659595 -516.603149) (xy 15.543822 -516.66146) (xy 15.424648 -516.71246)
			(xy 15.302534 -516.755952) (xy 15.177951 -516.791769) (xy 15.051384 -516.819771) (xy 14.92332 -516.83985)
			(xy 14.794256 -516.851929) (xy 14.66469 -516.85596) (xy 14.535124 -516.851929) (xy 14.40606 -516.83985)
			(xy 14.277996 -516.819771) (xy 14.151429 -516.791769) (xy 14.026846 -516.755952) (xy 13.904732 -516.71246)
			(xy 13.785558 -516.66146) (xy 13.669785 -516.603149) (xy 13.557861 -516.537754) (xy 13.450219 -516.465527)
			(xy 13.347276 -516.386747) (xy 13.24943 -516.30172) (xy 13.157058 -516.210775) (xy 13.07052 -516.114263)
			(xy 12.990149 -516.012557) (xy 12.916257 -515.906051) (xy 12.849129 -515.795158) (xy 12.789025 -515.680306)
			(xy 12.736178 -515.561939) (xy 12.690791 -515.440516) (xy 12.653042 -515.316506) (xy 12.623075 -515.190389)
			(xy 12.601006 -515.062653) (xy 12.586922 -514.933792) (xy 12.580876 -514.804305) (xy 9.530588 -514.804305)
			(xy 9.530588 -516.52805) (xy 10.755825 -517.753362) (xy 29.519874 -517.753362) (xy 29.519874 -517.666462)
			(xy 29.527892 -517.579933) (xy 29.54386 -517.494513) (xy 29.567641 -517.410931) (xy 29.599033 -517.329899)
			(xy 29.637767 -517.25211) (xy 29.683514 -517.178226) (xy 29.735883 -517.108879) (xy 29.794427 -517.044659)
			(xy 29.858647 -516.986115) (xy 29.927994 -516.933746) (xy 30.001878 -516.887999) (xy 30.079667 -516.849265)
			(xy 30.160699 -516.817873) (xy 30.244281 -516.794092) (xy 30.329701 -516.778124) (xy 30.41623 -516.770106)
			(xy 30.45968 -516.769604) (xy 30.50313 -516.770106) (xy 30.589659 -516.778124) (xy 30.675079 -516.794092)
			(xy 30.758661 -516.817873) (xy 30.839693 -516.849265) (xy 30.917482 -516.887999) (xy 30.991366 -516.933746)
			(xy 31.060713 -516.986115) (xy 31.124933 -517.044659) (xy 31.183477 -517.108879) (xy 31.235846 -517.178226)
			(xy 31.281593 -517.25211) (xy 31.320327 -517.329899) (xy 31.351719 -517.410931) (xy 31.3755 -517.494513)
			(xy 31.391468 -517.579933) (xy 31.399486 -517.666462) (xy 31.399486 -517.753362) (xy 34.599874 -517.753362)
			(xy 34.599874 -517.666462) (xy 34.607892 -517.579933) (xy 34.62386 -517.494513) (xy 34.647641 -517.410931)
			(xy 34.679033 -517.329899) (xy 34.717767 -517.25211) (xy 34.763514 -517.178226) (xy 34.815883 -517.108879)
			(xy 34.874427 -517.044659) (xy 34.938647 -516.986115) (xy 35.007994 -516.933746) (xy 35.081878 -516.887999)
			(xy 35.159667 -516.849265) (xy 35.240699 -516.817873) (xy 35.324281 -516.794092) (xy 35.409701 -516.778124)
			(xy 35.49623 -516.770106) (xy 35.53968 -516.769604) (xy 35.58313 -516.770106) (xy 35.669659 -516.778124)
			(xy 35.755079 -516.794092) (xy 35.838661 -516.817873) (xy 35.919693 -516.849265) (xy 35.997482 -516.887999)
			(xy 36.071366 -516.933746) (xy 36.140713 -516.986115) (xy 36.204933 -517.044659) (xy 36.263477 -517.108879)
			(xy 36.315846 -517.178226) (xy 36.361593 -517.25211) (xy 36.400327 -517.329899) (xy 36.431719 -517.410931)
			(xy 36.4555 -517.494513) (xy 36.471468 -517.579933) (xy 36.479486 -517.666462) (xy 36.479486 -517.753362)
			(xy 36.471468 -517.839891) (xy 36.4555 -517.925311) (xy 36.431719 -518.008893) (xy 36.400327 -518.089925)
			(xy 36.361593 -518.167714) (xy 36.315846 -518.241598) (xy 36.263477 -518.310945) (xy 36.204933 -518.375165)
			(xy 36.140713 -518.433709) (xy 36.071366 -518.486078) (xy 35.997482 -518.531825) (xy 35.919693 -518.570559)
			(xy 35.838661 -518.601951) (xy 35.755079 -518.625732) (xy 35.669659 -518.6417) (xy 35.58313 -518.649718)
			(xy 35.49623 -518.649718) (xy 35.409701 -518.6417) (xy 35.324281 -518.625732) (xy 35.240699 -518.601951)
			(xy 35.159667 -518.570559) (xy 35.081878 -518.531825) (xy 35.007994 -518.486078) (xy 34.938647 -518.433709)
			(xy 34.874427 -518.375165) (xy 34.815883 -518.310945) (xy 34.763514 -518.241598) (xy 34.717767 -518.167714)
			(xy 34.679033 -518.089925) (xy 34.647641 -518.008893) (xy 34.62386 -517.925311) (xy 34.607892 -517.839891)
			(xy 34.599874 -517.753362) (xy 31.399486 -517.753362) (xy 31.391468 -517.839891) (xy 31.3755 -517.925311)
			(xy 31.351719 -518.008893) (xy 31.320327 -518.089925) (xy 31.281593 -518.167714) (xy 31.235846 -518.241598)
			(xy 31.183477 -518.310945) (xy 31.124933 -518.375165) (xy 31.060713 -518.433709) (xy 30.991366 -518.486078)
			(xy 30.917482 -518.531825) (xy 30.839693 -518.570559) (xy 30.758661 -518.601951) (xy 30.675079 -518.625732)
			(xy 30.589659 -518.6417) (xy 30.50313 -518.649718) (xy 30.41623 -518.649718) (xy 30.329701 -518.6417)
			(xy 30.244281 -518.625732) (xy 30.160699 -518.601951) (xy 30.079667 -518.570559) (xy 30.001878 -518.531825)
			(xy 29.927994 -518.486078) (xy 29.858647 -518.433709) (xy 29.794427 -518.375165) (xy 29.735883 -518.310945)
			(xy 29.683514 -518.241598) (xy 29.637767 -518.167714) (xy 29.599033 -518.089925) (xy 29.567641 -518.008893)
			(xy 29.54386 -517.925311) (xy 29.527892 -517.839891) (xy 29.519874 -517.753362) (xy 10.755825 -517.753362)
			(xy 12.063491 -519.061107) (xy 51.32323 -519.061107) (xy 51.32323 -518.979997) (xy 51.33118 -518.899278)
			(xy 51.347003 -518.819727) (xy 51.370548 -518.742111) (xy 51.401587 -518.667175) (xy 51.439822 -518.595643)
			(xy 51.484884 -518.528203) (xy 51.536339 -518.465504) (xy 51.593692 -518.408151) (xy 51.656391 -518.356696)
			(xy 51.723831 -518.311634) (xy 51.795363 -518.273399) (xy 51.870299 -518.24236) (xy 51.947915 -518.218815)
			(xy 52.027466 -518.202992) (xy 52.108185 -518.195042) (xy 52.14874 -518.194544) (xy 52.189295 -518.195042)
			(xy 52.270014 -518.202992) (xy 52.349565 -518.218815) (xy 52.427181 -518.24236) (xy 52.502117 -518.273399)
			(xy 52.573649 -518.311634) (xy 52.641089 -518.356696) (xy 52.703788 -518.408151) (xy 52.761141 -518.465504)
			(xy 52.812596 -518.528203) (xy 52.857658 -518.595643) (xy 52.895893 -518.667175) (xy 52.909428 -518.699851)
			(xy 56.406534 -518.699851) (xy 56.406534 -518.628529) (xy 56.41452 -518.557655) (xy 56.43039 -518.48812)
			(xy 56.453947 -518.4208) (xy 56.484892 -518.356541) (xy 56.522838 -518.29615) (xy 56.567307 -518.240388)
			(xy 56.61774 -518.189955) (xy 56.673502 -518.145486) (xy 56.733893 -518.10754) (xy 56.798152 -518.076595)
			(xy 56.865472 -518.053038) (xy 56.935007 -518.037168) (xy 57.005881 -518.029182) (xy 57.041542 -518.028682)
			(xy 57.077203 -518.029182) (xy 57.148077 -518.037168) (xy 57.217612 -518.053038) (xy 57.284932 -518.076595)
			(xy 57.349191 -518.10754) (xy 57.409582 -518.145486) (xy 57.465344 -518.189955) (xy 57.515777 -518.240388)
			(xy 57.560246 -518.29615) (xy 57.598192 -518.356541) (xy 57.629137 -518.4208) (xy 57.652694 -518.48812)
			(xy 57.668564 -518.557655) (xy 57.67655 -518.628529) (xy 57.67655 -518.699851) (xy 58.938406 -518.699851)
			(xy 58.938406 -518.628529) (xy 58.946392 -518.557655) (xy 58.962262 -518.48812) (xy 58.985819 -518.4208)
			(xy 59.016764 -518.356541) (xy 59.05471 -518.29615) (xy 59.099179 -518.240388) (xy 59.149612 -518.189955)
			(xy 59.205374 -518.145486) (xy 59.265765 -518.10754) (xy 59.330024 -518.076595) (xy 59.397344 -518.053038)
			(xy 59.466879 -518.037168) (xy 59.537753 -518.029182) (xy 59.573414 -518.028682) (xy 59.609075 -518.029182)
			(xy 59.679949 -518.037168) (xy 59.749484 -518.053038) (xy 59.816804 -518.076595) (xy 59.881063 -518.10754)
			(xy 59.941454 -518.145486) (xy 59.997216 -518.189955) (xy 60.047649 -518.240388) (xy 60.092118 -518.29615)
			(xy 60.130064 -518.356541) (xy 60.161009 -518.4208) (xy 60.184566 -518.48812) (xy 60.200436 -518.557655)
			(xy 60.208422 -518.628529) (xy 60.208422 -518.699851) (xy 61.74282 -518.699851) (xy 61.74282 -518.628529)
			(xy 61.750806 -518.557655) (xy 61.766676 -518.48812) (xy 61.790233 -518.4208) (xy 61.821178 -518.356541)
			(xy 61.859124 -518.29615) (xy 61.903593 -518.240388) (xy 61.954026 -518.189955) (xy 62.009788 -518.145486)
			(xy 62.070179 -518.10754) (xy 62.134438 -518.076595) (xy 62.201758 -518.053038) (xy 62.271293 -518.037168)
			(xy 62.342167 -518.029182) (xy 62.377828 -518.028682) (xy 62.413489 -518.029182) (xy 62.484363 -518.037168)
			(xy 62.553898 -518.053038) (xy 62.621218 -518.076595) (xy 62.685477 -518.10754) (xy 62.745868 -518.145486)
			(xy 62.80163 -518.189955) (xy 62.852063 -518.240388) (xy 62.896532 -518.29615) (xy 62.934478 -518.356541)
			(xy 62.965423 -518.4208) (xy 62.98898 -518.48812) (xy 63.00485 -518.557655) (xy 63.012836 -518.628529)
			(xy 63.012836 -518.699851) (xy 64.98259 -518.699851) (xy 64.98259 -518.628529) (xy 64.990576 -518.557655)
			(xy 65.006446 -518.48812) (xy 65.030003 -518.4208) (xy 65.060948 -518.356541) (xy 65.098894 -518.29615)
			(xy 65.143363 -518.240388) (xy 65.193796 -518.189955) (xy 65.249558 -518.145486) (xy 65.309949 -518.10754)
			(xy 65.374208 -518.076595) (xy 65.441528 -518.053038) (xy 65.511063 -518.037168) (xy 65.581937 -518.029182)
			(xy 65.617598 -518.028682) (xy 65.653259 -518.029182) (xy 65.724133 -518.037168) (xy 65.793668 -518.053038)
			(xy 65.860988 -518.076595) (xy 65.925247 -518.10754) (xy 65.985638 -518.145486) (xy 66.0414 -518.189955)
			(xy 66.091833 -518.240388) (xy 66.136302 -518.29615) (xy 66.174248 -518.356541) (xy 66.205193 -518.4208)
			(xy 66.22875 -518.48812) (xy 66.24462 -518.557655) (xy 66.252606 -518.628529) (xy 66.252606 -518.699851)
			(xy 67.974202 -518.699851) (xy 67.974202 -518.628529) (xy 67.982188 -518.557655) (xy 67.998058 -518.48812)
			(xy 68.021615 -518.4208) (xy 68.05256 -518.356541) (xy 68.090506 -518.29615) (xy 68.134975 -518.240388)
			(xy 68.185408 -518.189955) (xy 68.24117 -518.145486) (xy 68.301561 -518.10754) (xy 68.36582 -518.076595)
			(xy 68.43314 -518.053038) (xy 68.502675 -518.037168) (xy 68.573549 -518.029182) (xy 68.60921 -518.028682)
			(xy 68.644871 -518.029182) (xy 68.715745 -518.037168) (xy 68.78528 -518.053038) (xy 68.8526 -518.076595)
			(xy 68.916859 -518.10754) (xy 68.97725 -518.145486) (xy 69.033012 -518.189955) (xy 69.083445 -518.240388)
			(xy 69.127914 -518.29615) (xy 69.16586 -518.356541) (xy 69.196805 -518.4208) (xy 69.220362 -518.48812)
			(xy 69.236232 -518.557655) (xy 69.244218 -518.628529) (xy 69.244218 -518.699851) (xy 69.236232 -518.770725)
			(xy 69.220362 -518.84026) (xy 69.196805 -518.90758) (xy 69.16586 -518.971839) (xy 69.148755 -518.999062)
			(xy 72.868285 -518.999062) (xy 72.874295 -518.796361) (xy 72.888307 -518.594056) (xy 72.910302 -518.392462)
			(xy 72.940243 -518.191895) (xy 72.978084 -517.992667) (xy 73.023767 -517.795089) (xy 73.07722 -517.599471)
			(xy 73.138359 -517.406117) (xy 73.20709 -517.215329) (xy 73.283304 -517.027406) (xy 73.366883 -516.84264)
			(xy 73.457696 -516.661321) (xy 73.555601 -516.483731) (xy 73.660446 -516.310147) (xy 73.772067 -516.140841)
			(xy 73.890289 -515.976076) (xy 74.014929 -515.816111) (xy 74.14579 -515.661195) (xy 74.28267 -515.51157)
			(xy 74.425354 -515.36747) (xy 74.57362 -515.229118) (xy 74.727236 -515.096733) (xy 74.885961 -514.970519)
			(xy 75.04955 -514.850675) (xy 75.217745 -514.737387) (xy 75.390284 -514.630832) (xy 75.566899 -514.531177)
			(xy 75.747312 -514.438577) (xy 75.931243 -514.353177) (xy 76.118404 -514.27511) (xy 76.308504 -514.204498)
			(xy 76.501244 -514.141452) (xy 76.696325 -514.086069) (xy 76.893442 -514.038437) (xy 77.092286 -513.998629)
			(xy 77.292548 -513.966707) (xy 77.493914 -513.942723) (xy 77.696071 -513.926712) (xy 77.898703 -513.918701)
			(xy 78.000098 -513.9182) (xy 78.101493 -513.918701) (xy 78.304125 -513.926712) (xy 78.506282 -513.942723)
			(xy 78.707648 -513.966707) (xy 78.90791 -513.998629) (xy 79.106754 -514.038437) (xy 79.303871 -514.086069)
			(xy 79.498952 -514.141452) (xy 79.691692 -514.204498) (xy 79.881792 -514.27511) (xy 80.068953 -514.353177)
			(xy 80.252884 -514.438577) (xy 80.433297 -514.531177) (xy 80.609912 -514.630832) (xy 80.782451 -514.737387)
			(xy 80.950646 -514.850675) (xy 81.114235 -514.970519) (xy 81.27296 -515.096733) (xy 81.426576 -515.229118)
			(xy 81.574842 -515.36747) (xy 81.717526 -515.51157) (xy 81.854406 -515.661195) (xy 81.985267 -515.816111)
			(xy 82.109907 -515.976076) (xy 82.228129 -516.140841) (xy 82.33975 -516.310147) (xy 82.444595 -516.483731)
			(xy 82.5425 -516.661321) (xy 82.633313 -516.84264) (xy 82.716892 -517.027406) (xy 82.793106 -517.215329)
			(xy 82.861837 -517.406117) (xy 82.922976 -517.599471) (xy 82.976429 -517.795089) (xy 83.022112 -517.992667)
			(xy 83.059953 -518.191895) (xy 83.089894 -518.392462) (xy 83.111889 -518.594056) (xy 83.125901 -518.796361)
			(xy 83.131911 -518.999062) (xy 83.129907 -519.201842) (xy 83.119894 -519.404385) (xy 83.101887 -519.606374)
			(xy 83.075915 -519.807493) (xy 83.042017 -520.00743) (xy 83.000246 -520.205872) (xy 82.950669 -520.402508)
			(xy 82.893361 -520.597032) (xy 82.828414 -520.78914) (xy 82.755927 -520.978533) (xy 82.676015 -521.164914)
			(xy 82.588803 -521.347992) (xy 82.494425 -521.527482) (xy 82.39303 -521.703103) (xy 82.284776 -521.874582)
			(xy 82.169832 -522.041649) (xy 82.048377 -522.204046) (xy 81.920602 -522.361517) (xy 81.786705 -522.513817)
			(xy 81.646896 -522.660709) (xy 81.501392 -522.801962) (xy 81.350422 -522.937357) (xy 81.194221 -523.066682)
			(xy 81.033032 -523.189735) (xy 80.867108 -523.306324) (xy 80.696708 -523.416267) (xy 80.522097 -523.519392)
			(xy 80.343548 -523.615538) (xy 80.16134 -523.704556) (xy 79.975758 -523.786305) (xy 79.787091 -523.860659)
			(xy 79.595633 -523.927501) (xy 79.401685 -523.986727) (xy 79.205548 -524.038245) (xy 79.007529 -524.081974)
			(xy 78.807937 -524.117845) (xy 78.607083 -524.145804) (xy 78.405282 -524.165805) (xy 78.202848 -524.177818)
			(xy 78.000098 -524.181825) (xy 77.797348 -524.177818) (xy 77.594914 -524.165805) (xy 77.393113 -524.145804)
			(xy 77.192259 -524.117845) (xy 76.992667 -524.081974) (xy 76.794648 -524.038245) (xy 76.598511 -523.986727)
			(xy 76.404563 -523.927501) (xy 76.213105 -523.860659) (xy 76.024438 -523.786305) (xy 75.838856 -523.704556)
			(xy 75.656648 -523.615538) (xy 75.478099 -523.519392) (xy 75.303488 -523.416267) (xy 75.133088 -523.306324)
			(xy 74.967164 -523.189735) (xy 74.805975 -523.066682) (xy 74.649774 -522.937357) (xy 74.498804 -522.801962)
			(xy 74.3533 -522.660709) (xy 74.213491 -522.513817) (xy 74.079594 -522.361517) (xy 73.951819 -522.204046)
			(xy 73.830364 -522.041649) (xy 73.71542 -521.874582) (xy 73.607166 -521.703103) (xy 73.505771 -521.527482)
			(xy 73.411393 -521.347992) (xy 73.324181 -521.164914) (xy 73.244269 -520.978533) (xy 73.171782 -520.78914)
			(xy 73.106835 -520.597032) (xy 73.049527 -520.402508) (xy 72.99995 -520.205872) (xy 72.958179 -520.00743)
			(xy 72.924281 -519.807493) (xy 72.898309 -519.606374) (xy 72.880302 -519.404385) (xy 72.870289 -519.201842)
			(xy 72.868285 -518.999062) (xy 69.148755 -518.999062) (xy 69.127914 -519.03223) (xy 69.083445 -519.087992)
			(xy 69.033012 -519.138425) (xy 68.97725 -519.182894) (xy 68.916859 -519.22084) (xy 68.8526 -519.251785)
			(xy 68.78528 -519.275342) (xy 68.715745 -519.291212) (xy 68.644871 -519.299198) (xy 68.573549 -519.299198)
			(xy 68.502675 -519.291212) (xy 68.43314 -519.275342) (xy 68.36582 -519.251785) (xy 68.301561 -519.22084)
			(xy 68.24117 -519.182894) (xy 68.185408 -519.138425) (xy 68.134975 -519.087992) (xy 68.090506 -519.03223)
			(xy 68.05256 -518.971839) (xy 68.021615 -518.90758) (xy 67.998058 -518.84026) (xy 67.982188 -518.770725)
			(xy 67.974202 -518.699851) (xy 66.252606 -518.699851) (xy 66.24462 -518.770725) (xy 66.22875 -518.84026)
			(xy 66.205193 -518.90758) (xy 66.174248 -518.971839) (xy 66.136302 -519.03223) (xy 66.091833 -519.087992)
			(xy 66.0414 -519.138425) (xy 65.985638 -519.182894) (xy 65.925247 -519.22084) (xy 65.860988 -519.251785)
			(xy 65.793668 -519.275342) (xy 65.724133 -519.291212) (xy 65.653259 -519.299198) (xy 65.581937 -519.299198)
			(xy 65.511063 -519.291212) (xy 65.441528 -519.275342) (xy 65.374208 -519.251785) (xy 65.309949 -519.22084)
			(xy 65.249558 -519.182894) (xy 65.193796 -519.138425) (xy 65.143363 -519.087992) (xy 65.098894 -519.03223)
			(xy 65.060948 -518.971839) (xy 65.030003 -518.90758) (xy 65.006446 -518.84026) (xy 64.990576 -518.770725)
			(xy 64.98259 -518.699851) (xy 63.012836 -518.699851) (xy 63.00485 -518.770725) (xy 62.98898 -518.84026)
			(xy 62.965423 -518.90758) (xy 62.934478 -518.971839) (xy 62.896532 -519.03223) (xy 62.852063 -519.087992)
			(xy 62.80163 -519.138425) (xy 62.745868 -519.182894) (xy 62.685477 -519.22084) (xy 62.621218 -519.251785)
			(xy 62.553898 -519.275342) (xy 62.484363 -519.291212) (xy 62.413489 -519.299198) (xy 62.342167 -519.299198)
			(xy 62.271293 -519.291212) (xy 62.201758 -519.275342) (xy 62.134438 -519.251785) (xy 62.070179 -519.22084)
			(xy 62.009788 -519.182894) (xy 61.954026 -519.138425) (xy 61.903593 -519.087992) (xy 61.859124 -519.03223)
			(xy 61.821178 -518.971839) (xy 61.790233 -518.90758) (xy 61.766676 -518.84026) (xy 61.750806 -518.770725)
			(xy 61.74282 -518.699851) (xy 60.208422 -518.699851) (xy 60.200436 -518.770725) (xy 60.184566 -518.84026)
			(xy 60.161009 -518.90758) (xy 60.130064 -518.971839) (xy 60.092118 -519.03223) (xy 60.047649 -519.087992)
			(xy 59.997216 -519.138425) (xy 59.941454 -519.182894) (xy 59.881063 -519.22084) (xy 59.816804 -519.251785)
			(xy 59.749484 -519.275342) (xy 59.679949 -519.291212) (xy 59.609075 -519.299198) (xy 59.537753 -519.299198)
			(xy 59.466879 -519.291212) (xy 59.397344 -519.275342) (xy 59.330024 -519.251785) (xy 59.265765 -519.22084)
			(xy 59.205374 -519.182894) (xy 59.149612 -519.138425) (xy 59.099179 -519.087992) (xy 59.05471 -519.03223)
			(xy 59.016764 -518.971839) (xy 58.985819 -518.90758) (xy 58.962262 -518.84026) (xy 58.946392 -518.770725)
			(xy 58.938406 -518.699851) (xy 57.67655 -518.699851) (xy 57.668564 -518.770725) (xy 57.652694 -518.84026)
			(xy 57.629137 -518.90758) (xy 57.598192 -518.971839) (xy 57.560246 -519.03223) (xy 57.515777 -519.087992)
			(xy 57.465344 -519.138425) (xy 57.409582 -519.182894) (xy 57.349191 -519.22084) (xy 57.284932 -519.251785)
			(xy 57.217612 -519.275342) (xy 57.148077 -519.291212) (xy 57.077203 -519.299198) (xy 57.005881 -519.299198)
			(xy 56.935007 -519.291212) (xy 56.865472 -519.275342) (xy 56.798152 -519.251785) (xy 56.733893 -519.22084)
			(xy 56.673502 -519.182894) (xy 56.61774 -519.138425) (xy 56.567307 -519.087992) (xy 56.522838 -519.03223)
			(xy 56.484892 -518.971839) (xy 56.453947 -518.90758) (xy 56.43039 -518.84026) (xy 56.41452 -518.770725)
			(xy 56.406534 -518.699851) (xy 52.909428 -518.699851) (xy 52.926932 -518.742111) (xy 52.950477 -518.819727)
			(xy 52.9663 -518.899278) (xy 52.97425 -518.979997) (xy 52.97425 -519.061107) (xy 52.9663 -519.141826)
			(xy 52.950477 -519.221377) (xy 52.926932 -519.298993) (xy 52.895893 -519.373929) (xy 52.857658 -519.445461)
			(xy 52.812596 -519.512901) (xy 52.761141 -519.5756) (xy 52.703788 -519.632953) (xy 52.641089 -519.684408)
			(xy 52.573649 -519.72947) (xy 52.502117 -519.767705) (xy 52.427181 -519.798744) (xy 52.349565 -519.822289)
			(xy 52.270014 -519.838112) (xy 52.189295 -519.846062) (xy 52.108185 -519.846062) (xy 52.027466 -519.838112)
			(xy 51.947915 -519.822289) (xy 51.870299 -519.798744) (xy 51.795363 -519.767705) (xy 51.723831 -519.72947)
			(xy 51.656391 -519.684408) (xy 51.593692 -519.632953) (xy 51.536339 -519.5756) (xy 51.484884 -519.512901)
			(xy 51.439822 -519.445461) (xy 51.401587 -519.373929) (xy 51.370548 -519.298993) (xy 51.347003 -519.221377)
			(xy 51.33118 -519.141826) (xy 51.32323 -519.061107) (xy 12.063491 -519.061107) (xy 13.295671 -520.293362)
			(xy 29.519874 -520.293362) (xy 29.519874 -520.206462) (xy 29.527892 -520.119933) (xy 29.54386 -520.034513)
			(xy 29.567641 -519.950931) (xy 29.599033 -519.869899) (xy 29.637767 -519.79211) (xy 29.683514 -519.718226)
			(xy 29.735883 -519.648879) (xy 29.794427 -519.584659) (xy 29.858647 -519.526115) (xy 29.927994 -519.473746)
			(xy 30.001878 -519.427999) (xy 30.079667 -519.389265) (xy 30.160699 -519.357873) (xy 30.244281 -519.334092)
			(xy 30.329701 -519.318124) (xy 30.41623 -519.310106) (xy 30.45968 -519.309604) (xy 30.50313 -519.310106)
			(xy 30.589659 -519.318124) (xy 30.675079 -519.334092) (xy 30.758661 -519.357873) (xy 30.839693 -519.389265)
			(xy 30.917482 -519.427999) (xy 30.991366 -519.473746) (xy 31.060713 -519.526115) (xy 31.124933 -519.584659)
			(xy 31.183477 -519.648879) (xy 31.235846 -519.718226) (xy 31.281593 -519.79211) (xy 31.320327 -519.869899)
			(xy 31.351719 -519.950931) (xy 31.3755 -520.034513) (xy 31.391468 -520.119933) (xy 31.399486 -520.206462)
			(xy 31.399486 -520.293362) (xy 34.599874 -520.293362) (xy 34.599874 -520.206462) (xy 34.607892 -520.119933)
			(xy 34.62386 -520.034513) (xy 34.647641 -519.950931) (xy 34.679033 -519.869899) (xy 34.717767 -519.79211)
			(xy 34.763514 -519.718226) (xy 34.815883 -519.648879) (xy 34.874427 -519.584659) (xy 34.938647 -519.526115)
			(xy 35.007994 -519.473746) (xy 35.081878 -519.427999) (xy 35.159667 -519.389265) (xy 35.240699 -519.357873)
			(xy 35.324281 -519.334092) (xy 35.409701 -519.318124) (xy 35.49623 -519.310106) (xy 35.53968 -519.309604)
			(xy 35.58313 -519.310106) (xy 35.669659 -519.318124) (xy 35.755079 -519.334092) (xy 35.838661 -519.357873)
			(xy 35.919693 -519.389265) (xy 35.997482 -519.427999) (xy 36.071366 -519.473746) (xy 36.140713 -519.526115)
			(xy 36.204933 -519.584659) (xy 36.263477 -519.648879) (xy 36.315846 -519.718226) (xy 36.361593 -519.79211)
			(xy 36.400327 -519.869899) (xy 36.431719 -519.950931) (xy 36.4555 -520.034513) (xy 36.471468 -520.119933)
			(xy 36.479486 -520.206462) (xy 36.479486 -520.293362) (xy 36.471468 -520.379891) (xy 36.4555 -520.465311)
			(xy 36.431719 -520.548893) (xy 36.400327 -520.629925) (xy 36.361593 -520.707714) (xy 36.315846 -520.781598)
			(xy 36.263477 -520.850945) (xy 36.204933 -520.915165) (xy 36.140713 -520.973709) (xy 36.071366 -521.026078)
			(xy 35.998089 -521.071449) (xy 56.406534 -521.071449) (xy 56.406534 -521.000127) (xy 56.41452 -520.929253)
			(xy 56.43039 -520.859718) (xy 56.453947 -520.792398) (xy 56.484892 -520.728139) (xy 56.522838 -520.667748)
			(xy 56.567307 -520.611986) (xy 56.61774 -520.561553) (xy 56.673502 -520.517084) (xy 56.733893 -520.479138)
			(xy 56.798152 -520.448193) (xy 56.865472 -520.424636) (xy 56.935007 -520.408766) (xy 57.005881 -520.40078)
			(xy 57.041542 -520.40028) (xy 57.077203 -520.40078) (xy 57.148077 -520.408766) (xy 57.217612 -520.424636)
			(xy 57.284932 -520.448193) (xy 57.349191 -520.479138) (xy 57.409582 -520.517084) (xy 57.465344 -520.561553)
			(xy 57.515777 -520.611986) (xy 57.560246 -520.667748) (xy 57.598192 -520.728139) (xy 57.629137 -520.792398)
			(xy 57.652694 -520.859718) (xy 57.668564 -520.929253) (xy 57.67655 -521.000127) (xy 57.67655 -521.071449)
			(xy 58.938406 -521.071449) (xy 58.938406 -521.000127) (xy 58.946392 -520.929253) (xy 58.962262 -520.859718)
			(xy 58.985819 -520.792398) (xy 59.016764 -520.728139) (xy 59.05471 -520.667748) (xy 59.099179 -520.611986)
			(xy 59.149612 -520.561553) (xy 59.205374 -520.517084) (xy 59.265765 -520.479138) (xy 59.330024 -520.448193)
			(xy 59.397344 -520.424636) (xy 59.466879 -520.408766) (xy 59.537753 -520.40078) (xy 59.573414 -520.40028)
			(xy 59.609075 -520.40078) (xy 59.679949 -520.408766) (xy 59.749484 -520.424636) (xy 59.816804 -520.448193)
			(xy 59.881063 -520.479138) (xy 59.941454 -520.517084) (xy 59.997216 -520.561553) (xy 60.047649 -520.611986)
			(xy 60.092118 -520.667748) (xy 60.130064 -520.728139) (xy 60.161009 -520.792398) (xy 60.184566 -520.859718)
			(xy 60.200436 -520.929253) (xy 60.208422 -521.000127) (xy 60.208422 -521.071449) (xy 61.74282 -521.071449)
			(xy 61.74282 -521.000127) (xy 61.750806 -520.929253) (xy 61.766676 -520.859718) (xy 61.790233 -520.792398)
			(xy 61.821178 -520.728139) (xy 61.859124 -520.667748) (xy 61.903593 -520.611986) (xy 61.954026 -520.561553)
			(xy 62.009788 -520.517084) (xy 62.070179 -520.479138) (xy 62.134438 -520.448193) (xy 62.201758 -520.424636)
			(xy 62.271293 -520.408766) (xy 62.342167 -520.40078) (xy 62.377828 -520.40028) (xy 62.413489 -520.40078)
			(xy 62.484363 -520.408766) (xy 62.553898 -520.424636) (xy 62.621218 -520.448193) (xy 62.685477 -520.479138)
			(xy 62.745868 -520.517084) (xy 62.80163 -520.561553) (xy 62.852063 -520.611986) (xy 62.896532 -520.667748)
			(xy 62.934478 -520.728139) (xy 62.965423 -520.792398) (xy 62.98898 -520.859718) (xy 63.00485 -520.929253)
			(xy 63.012836 -521.000127) (xy 63.012836 -521.071449) (xy 64.98259 -521.071449) (xy 64.98259 -521.000127)
			(xy 64.990576 -520.929253) (xy 65.006446 -520.859718) (xy 65.030003 -520.792398) (xy 65.060948 -520.728139)
			(xy 65.098894 -520.667748) (xy 65.143363 -520.611986) (xy 65.193796 -520.561553) (xy 65.249558 -520.517084)
			(xy 65.309949 -520.479138) (xy 65.374208 -520.448193) (xy 65.441528 -520.424636) (xy 65.511063 -520.408766)
			(xy 65.581937 -520.40078) (xy 65.617598 -520.40028) (xy 65.653259 -520.40078) (xy 65.724133 -520.408766)
			(xy 65.793668 -520.424636) (xy 65.860988 -520.448193) (xy 65.925247 -520.479138) (xy 65.985638 -520.517084)
			(xy 66.0414 -520.561553) (xy 66.091833 -520.611986) (xy 66.136302 -520.667748) (xy 66.174248 -520.728139)
			(xy 66.205193 -520.792398) (xy 66.22875 -520.859718) (xy 66.24462 -520.929253) (xy 66.252606 -521.000127)
			(xy 66.252606 -521.071449) (xy 67.974202 -521.071449) (xy 67.974202 -521.000127) (xy 67.982188 -520.929253)
			(xy 67.998058 -520.859718) (xy 68.021615 -520.792398) (xy 68.05256 -520.728139) (xy 68.090506 -520.667748)
			(xy 68.134975 -520.611986) (xy 68.185408 -520.561553) (xy 68.24117 -520.517084) (xy 68.301561 -520.479138)
			(xy 68.36582 -520.448193) (xy 68.43314 -520.424636) (xy 68.502675 -520.408766) (xy 68.573549 -520.40078)
			(xy 68.60921 -520.40028) (xy 68.644871 -520.40078) (xy 68.715745 -520.408766) (xy 68.78528 -520.424636)
			(xy 68.8526 -520.448193) (xy 68.916859 -520.479138) (xy 68.97725 -520.517084) (xy 69.033012 -520.561553)
			(xy 69.083445 -520.611986) (xy 69.127914 -520.667748) (xy 69.16586 -520.728139) (xy 69.196805 -520.792398)
			(xy 69.220362 -520.859718) (xy 69.236232 -520.929253) (xy 69.244218 -521.000127) (xy 69.244218 -521.071449)
			(xy 69.236232 -521.142323) (xy 69.220362 -521.211858) (xy 69.196805 -521.279178) (xy 69.16586 -521.343437)
			(xy 69.127914 -521.403828) (xy 69.083445 -521.45959) (xy 69.033012 -521.510023) (xy 68.97725 -521.554492)
			(xy 68.916859 -521.592438) (xy 68.8526 -521.623383) (xy 68.78528 -521.64694) (xy 68.715745 -521.66281)
			(xy 68.644871 -521.670796) (xy 68.573549 -521.670796) (xy 68.502675 -521.66281) (xy 68.43314 -521.64694)
			(xy 68.36582 -521.623383) (xy 68.301561 -521.592438) (xy 68.24117 -521.554492) (xy 68.185408 -521.510023)
			(xy 68.134975 -521.45959) (xy 68.090506 -521.403828) (xy 68.05256 -521.343437) (xy 68.021615 -521.279178)
			(xy 67.998058 -521.211858) (xy 67.982188 -521.142323) (xy 67.974202 -521.071449) (xy 66.252606 -521.071449)
			(xy 66.24462 -521.142323) (xy 66.22875 -521.211858) (xy 66.205193 -521.279178) (xy 66.174248 -521.343437)
			(xy 66.136302 -521.403828) (xy 66.091833 -521.45959) (xy 66.0414 -521.510023) (xy 65.985638 -521.554492)
			(xy 65.925247 -521.592438) (xy 65.860988 -521.623383) (xy 65.793668 -521.64694) (xy 65.724133 -521.66281)
			(xy 65.653259 -521.670796) (xy 65.581937 -521.670796) (xy 65.511063 -521.66281) (xy 65.441528 -521.64694)
			(xy 65.374208 -521.623383) (xy 65.309949 -521.592438) (xy 65.249558 -521.554492) (xy 65.193796 -521.510023)
			(xy 65.143363 -521.45959) (xy 65.098894 -521.403828) (xy 65.060948 -521.343437) (xy 65.030003 -521.279178)
			(xy 65.006446 -521.211858) (xy 64.990576 -521.142323) (xy 64.98259 -521.071449) (xy 63.012836 -521.071449)
			(xy 63.00485 -521.142323) (xy 62.98898 -521.211858) (xy 62.965423 -521.279178) (xy 62.934478 -521.343437)
			(xy 62.896532 -521.403828) (xy 62.852063 -521.45959) (xy 62.80163 -521.510023) (xy 62.745868 -521.554492)
			(xy 62.685477 -521.592438) (xy 62.621218 -521.623383) (xy 62.553898 -521.64694) (xy 62.484363 -521.66281)
			(xy 62.413489 -521.670796) (xy 62.342167 -521.670796) (xy 62.271293 -521.66281) (xy 62.201758 -521.64694)
			(xy 62.134438 -521.623383) (xy 62.070179 -521.592438) (xy 62.009788 -521.554492) (xy 61.954026 -521.510023)
			(xy 61.903593 -521.45959) (xy 61.859124 -521.403828) (xy 61.821178 -521.343437) (xy 61.790233 -521.279178)
			(xy 61.766676 -521.211858) (xy 61.750806 -521.142323) (xy 61.74282 -521.071449) (xy 60.208422 -521.071449)
			(xy 60.200436 -521.142323) (xy 60.184566 -521.211858) (xy 60.161009 -521.279178) (xy 60.130064 -521.343437)
			(xy 60.092118 -521.403828) (xy 60.047649 -521.45959) (xy 59.997216 -521.510023) (xy 59.941454 -521.554492)
			(xy 59.881063 -521.592438) (xy 59.816804 -521.623383) (xy 59.749484 -521.64694) (xy 59.679949 -521.66281)
			(xy 59.609075 -521.670796) (xy 59.537753 -521.670796) (xy 59.466879 -521.66281) (xy 59.397344 -521.64694)
			(xy 59.330024 -521.623383) (xy 59.265765 -521.592438) (xy 59.205374 -521.554492) (xy 59.149612 -521.510023)
			(xy 59.099179 -521.45959) (xy 59.05471 -521.403828) (xy 59.016764 -521.343437) (xy 58.985819 -521.279178)
			(xy 58.962262 -521.211858) (xy 58.946392 -521.142323) (xy 58.938406 -521.071449) (xy 57.67655 -521.071449)
			(xy 57.668564 -521.142323) (xy 57.652694 -521.211858) (xy 57.629137 -521.279178) (xy 57.598192 -521.343437)
			(xy 57.560246 -521.403828) (xy 57.515777 -521.45959) (xy 57.465344 -521.510023) (xy 57.409582 -521.554492)
			(xy 57.349191 -521.592438) (xy 57.284932 -521.623383) (xy 57.217612 -521.64694) (xy 57.148077 -521.66281)
			(xy 57.077203 -521.670796) (xy 57.005881 -521.670796) (xy 56.935007 -521.66281) (xy 56.865472 -521.64694)
			(xy 56.798152 -521.623383) (xy 56.733893 -521.592438) (xy 56.673502 -521.554492) (xy 56.61774 -521.510023)
			(xy 56.567307 -521.45959) (xy 56.522838 -521.403828) (xy 56.484892 -521.343437) (xy 56.453947 -521.279178)
			(xy 56.43039 -521.211858) (xy 56.41452 -521.142323) (xy 56.406534 -521.071449) (xy 35.998089 -521.071449)
			(xy 35.997482 -521.071825) (xy 35.919693 -521.110559) (xy 35.838661 -521.141951) (xy 35.755079 -521.165732)
			(xy 35.669659 -521.1817) (xy 35.58313 -521.189718) (xy 35.49623 -521.189718) (xy 35.409701 -521.1817)
			(xy 35.324281 -521.165732) (xy 35.240699 -521.141951) (xy 35.159667 -521.110559) (xy 35.081878 -521.071825)
			(xy 35.007994 -521.026078) (xy 34.938647 -520.973709) (xy 34.874427 -520.915165) (xy 34.815883 -520.850945)
			(xy 34.763514 -520.781598) (xy 34.717767 -520.707714) (xy 34.679033 -520.629925) (xy 34.647641 -520.548893)
			(xy 34.62386 -520.465311) (xy 34.607892 -520.379891) (xy 34.599874 -520.293362) (xy 31.399486 -520.293362)
			(xy 31.391468 -520.379891) (xy 31.3755 -520.465311) (xy 31.351719 -520.548893) (xy 31.320327 -520.629925)
			(xy 31.281593 -520.707714) (xy 31.235846 -520.781598) (xy 31.183477 -520.850945) (xy 31.124933 -520.915165)
			(xy 31.060713 -520.973709) (xy 30.991366 -521.026078) (xy 30.917482 -521.071825) (xy 30.839693 -521.110559)
			(xy 30.758661 -521.141951) (xy 30.675079 -521.165732) (xy 30.589659 -521.1817) (xy 30.50313 -521.189718)
			(xy 30.41623 -521.189718) (xy 30.329701 -521.1817) (xy 30.244281 -521.165732) (xy 30.160699 -521.141951)
			(xy 30.079667 -521.110559) (xy 30.001878 -521.071825) (xy 29.927994 -521.026078) (xy 29.858647 -520.973709)
			(xy 29.794427 -520.915165) (xy 29.735883 -520.850945) (xy 29.683514 -520.781598) (xy 29.637767 -520.707714)
			(xy 29.599033 -520.629925) (xy 29.567641 -520.548893) (xy 29.54386 -520.465311) (xy 29.527892 -520.379891)
			(xy 29.519874 -520.293362) (xy 13.295671 -520.293362) (xy 13.712444 -520.71016) (xy 13.712444 -522.819122)
			(xy 13.712964 -522.833362) (xy 29.519874 -522.833362) (xy 29.519874 -522.746462) (xy 29.527892 -522.659933)
			(xy 29.54386 -522.574513) (xy 29.567641 -522.490931) (xy 29.599033 -522.409899) (xy 29.637767 -522.33211)
			(xy 29.683514 -522.258226) (xy 29.735883 -522.188879) (xy 29.794427 -522.124659) (xy 29.858647 -522.066115)
			(xy 29.927994 -522.013746) (xy 30.001878 -521.967999) (xy 30.079667 -521.929265) (xy 30.160699 -521.897873)
			(xy 30.244281 -521.874092) (xy 30.329701 -521.858124) (xy 30.41623 -521.850106) (xy 30.45968 -521.849604)
			(xy 30.50313 -521.850106) (xy 30.589659 -521.858124) (xy 30.675079 -521.874092) (xy 30.758661 -521.897873)
			(xy 30.839693 -521.929265) (xy 30.917482 -521.967999) (xy 30.991366 -522.013746) (xy 31.060713 -522.066115)
			(xy 31.124933 -522.124659) (xy 31.183477 -522.188879) (xy 31.235846 -522.258226) (xy 31.281593 -522.33211)
			(xy 31.320327 -522.409899) (xy 31.351719 -522.490931) (xy 31.3755 -522.574513) (xy 31.391468 -522.659933)
			(xy 31.399486 -522.746462) (xy 31.399486 -522.833362) (xy 34.599874 -522.833362) (xy 34.599874 -522.746462)
			(xy 34.607892 -522.659933) (xy 34.62386 -522.574513) (xy 34.647641 -522.490931) (xy 34.679033 -522.409899)
			(xy 34.717767 -522.33211) (xy 34.763514 -522.258226) (xy 34.815883 -522.188879) (xy 34.874427 -522.124659)
			(xy 34.938647 -522.066115) (xy 35.007994 -522.013746) (xy 35.081878 -521.967999) (xy 35.159667 -521.929265)
			(xy 35.240699 -521.897873) (xy 35.324281 -521.874092) (xy 35.409701 -521.858124) (xy 35.49623 -521.850106)
			(xy 35.53968 -521.849604) (xy 35.58313 -521.850106) (xy 35.669659 -521.858124) (xy 35.755079 -521.874092)
			(xy 35.838661 -521.897873) (xy 35.919693 -521.929265) (xy 35.997482 -521.967999) (xy 36.071366 -522.013746)
			(xy 36.140713 -522.066115) (xy 36.204933 -522.124659) (xy 36.263477 -522.188879) (xy 36.315846 -522.258226)
			(xy 36.361593 -522.33211) (xy 36.400327 -522.409899) (xy 36.431719 -522.490931) (xy 36.4555 -522.574513)
			(xy 36.471468 -522.659933) (xy 36.479486 -522.746462) (xy 36.479486 -522.833362) (xy 36.471468 -522.919891)
			(xy 36.4555 -523.005311) (xy 36.447235 -523.034361) (xy 56.406534 -523.034361) (xy 56.406534 -522.963039)
			(xy 56.41452 -522.892165) (xy 56.43039 -522.82263) (xy 56.453947 -522.75531) (xy 56.484892 -522.691051)
			(xy 56.522838 -522.63066) (xy 56.567307 -522.574898) (xy 56.61774 -522.524465) (xy 56.673502 -522.479996)
			(xy 56.733893 -522.44205) (xy 56.798152 -522.411105) (xy 56.865472 -522.387548) (xy 56.935007 -522.371678)
			(xy 57.005881 -522.363692) (xy 57.041542 -522.363192) (xy 57.077203 -522.363692) (xy 57.148077 -522.371678)
			(xy 57.217612 -522.387548) (xy 57.284932 -522.411105) (xy 57.349191 -522.44205) (xy 57.409582 -522.479996)
			(xy 57.465344 -522.524465) (xy 57.515777 -522.574898) (xy 57.560246 -522.63066) (xy 57.598192 -522.691051)
			(xy 57.629137 -522.75531) (xy 57.652694 -522.82263) (xy 57.668564 -522.892165) (xy 57.67655 -522.963039)
			(xy 57.67655 -523.034361) (xy 58.938406 -523.034361) (xy 58.938406 -522.963039) (xy 58.946392 -522.892165)
			(xy 58.962262 -522.82263) (xy 58.985819 -522.75531) (xy 59.016764 -522.691051) (xy 59.05471 -522.63066)
			(xy 59.099179 -522.574898) (xy 59.149612 -522.524465) (xy 59.205374 -522.479996) (xy 59.265765 -522.44205)
			(xy 59.330024 -522.411105) (xy 59.397344 -522.387548) (xy 59.466879 -522.371678) (xy 59.537753 -522.363692)
			(xy 59.573414 -522.363192) (xy 59.609075 -522.363692) (xy 59.679949 -522.371678) (xy 59.749484 -522.387548)
			(xy 59.816804 -522.411105) (xy 59.881063 -522.44205) (xy 59.941454 -522.479996) (xy 59.997216 -522.524465)
			(xy 60.047649 -522.574898) (xy 60.092118 -522.63066) (xy 60.130064 -522.691051) (xy 60.161009 -522.75531)
			(xy 60.184566 -522.82263) (xy 60.200436 -522.892165) (xy 60.208422 -522.963039) (xy 60.208422 -523.034361)
			(xy 61.74282 -523.034361) (xy 61.74282 -522.963039) (xy 61.750806 -522.892165) (xy 61.766676 -522.82263)
			(xy 61.790233 -522.75531) (xy 61.821178 -522.691051) (xy 61.859124 -522.63066) (xy 61.903593 -522.574898)
			(xy 61.954026 -522.524465) (xy 62.009788 -522.479996) (xy 62.070179 -522.44205) (xy 62.134438 -522.411105)
			(xy 62.201758 -522.387548) (xy 62.271293 -522.371678) (xy 62.342167 -522.363692) (xy 62.377828 -522.363192)
			(xy 62.413489 -522.363692) (xy 62.484363 -522.371678) (xy 62.553898 -522.387548) (xy 62.621218 -522.411105)
			(xy 62.685477 -522.44205) (xy 62.745868 -522.479996) (xy 62.80163 -522.524465) (xy 62.852063 -522.574898)
			(xy 62.896532 -522.63066) (xy 62.934478 -522.691051) (xy 62.965423 -522.75531) (xy 62.98898 -522.82263)
			(xy 63.00485 -522.892165) (xy 63.012836 -522.963039) (xy 63.012836 -523.034361) (xy 64.98259 -523.034361)
			(xy 64.98259 -522.963039) (xy 64.990576 -522.892165) (xy 65.006446 -522.82263) (xy 65.030003 -522.75531)
			(xy 65.060948 -522.691051) (xy 65.098894 -522.63066) (xy 65.143363 -522.574898) (xy 65.193796 -522.524465)
			(xy 65.249558 -522.479996) (xy 65.309949 -522.44205) (xy 65.374208 -522.411105) (xy 65.441528 -522.387548)
			(xy 65.511063 -522.371678) (xy 65.581937 -522.363692) (xy 65.617598 -522.363192) (xy 65.653259 -522.363692)
			(xy 65.724133 -522.371678) (xy 65.793668 -522.387548) (xy 65.860988 -522.411105) (xy 65.925247 -522.44205)
			(xy 65.985638 -522.479996) (xy 66.0414 -522.524465) (xy 66.091833 -522.574898) (xy 66.136302 -522.63066)
			(xy 66.174248 -522.691051) (xy 66.205193 -522.75531) (xy 66.22875 -522.82263) (xy 66.24462 -522.892165)
			(xy 66.252606 -522.963039) (xy 66.252606 -523.034361) (xy 67.974202 -523.034361) (xy 67.974202 -522.963039)
			(xy 67.982188 -522.892165) (xy 67.998058 -522.82263) (xy 68.021615 -522.75531) (xy 68.05256 -522.691051)
			(xy 68.090506 -522.63066) (xy 68.134975 -522.574898) (xy 68.185408 -522.524465) (xy 68.24117 -522.479996)
			(xy 68.301561 -522.44205) (xy 68.36582 -522.411105) (xy 68.43314 -522.387548) (xy 68.502675 -522.371678)
			(xy 68.573549 -522.363692) (xy 68.60921 -522.363192) (xy 68.644871 -522.363692) (xy 68.715745 -522.371678)
			(xy 68.78528 -522.387548) (xy 68.8526 -522.411105) (xy 68.916859 -522.44205) (xy 68.97725 -522.479996)
			(xy 69.033012 -522.524465) (xy 69.083445 -522.574898) (xy 69.127914 -522.63066) (xy 69.16586 -522.691051)
			(xy 69.196805 -522.75531) (xy 69.220362 -522.82263) (xy 69.236232 -522.892165) (xy 69.244218 -522.963039)
			(xy 69.244218 -523.034361) (xy 69.236232 -523.105235) (xy 69.220362 -523.17477) (xy 69.196805 -523.24209)
			(xy 69.16586 -523.306349) (xy 69.127914 -523.36674) (xy 69.083445 -523.422502) (xy 69.033012 -523.472935)
			(xy 68.97725 -523.517404) (xy 68.916859 -523.55535) (xy 68.8526 -523.586295) (xy 68.78528 -523.609852)
			(xy 68.715745 -523.625722) (xy 68.644871 -523.633708) (xy 68.573549 -523.633708) (xy 68.502675 -523.625722)
			(xy 68.43314 -523.609852) (xy 68.36582 -523.586295) (xy 68.301561 -523.55535) (xy 68.24117 -523.517404)
			(xy 68.185408 -523.472935) (xy 68.134975 -523.422502) (xy 68.090506 -523.36674) (xy 68.05256 -523.306349)
			(xy 68.021615 -523.24209) (xy 67.998058 -523.17477) (xy 67.982188 -523.105235) (xy 67.974202 -523.034361)
			(xy 66.252606 -523.034361) (xy 66.24462 -523.105235) (xy 66.22875 -523.17477) (xy 66.205193 -523.24209)
			(xy 66.174248 -523.306349) (xy 66.136302 -523.36674) (xy 66.091833 -523.422502) (xy 66.0414 -523.472935)
			(xy 65.985638 -523.517404) (xy 65.925247 -523.55535) (xy 65.860988 -523.586295) (xy 65.793668 -523.609852)
			(xy 65.724133 -523.625722) (xy 65.653259 -523.633708) (xy 65.581937 -523.633708) (xy 65.511063 -523.625722)
			(xy 65.441528 -523.609852) (xy 65.374208 -523.586295) (xy 65.309949 -523.55535) (xy 65.249558 -523.517404)
			(xy 65.193796 -523.472935) (xy 65.143363 -523.422502) (xy 65.098894 -523.36674) (xy 65.060948 -523.306349)
			(xy 65.030003 -523.24209) (xy 65.006446 -523.17477) (xy 64.990576 -523.105235) (xy 64.98259 -523.034361)
			(xy 63.012836 -523.034361) (xy 63.00485 -523.105235) (xy 62.98898 -523.17477) (xy 62.965423 -523.24209)
			(xy 62.934478 -523.306349) (xy 62.896532 -523.36674) (xy 62.852063 -523.422502) (xy 62.80163 -523.472935)
			(xy 62.745868 -523.517404) (xy 62.685477 -523.55535) (xy 62.621218 -523.586295) (xy 62.553898 -523.609852)
			(xy 62.484363 -523.625722) (xy 62.413489 -523.633708) (xy 62.342167 -523.633708) (xy 62.271293 -523.625722)
			(xy 62.201758 -523.609852) (xy 62.134438 -523.586295) (xy 62.070179 -523.55535) (xy 62.009788 -523.517404)
			(xy 61.954026 -523.472935) (xy 61.903593 -523.422502) (xy 61.859124 -523.36674) (xy 61.821178 -523.306349)
			(xy 61.790233 -523.24209) (xy 61.766676 -523.17477) (xy 61.750806 -523.105235) (xy 61.74282 -523.034361)
			(xy 60.208422 -523.034361) (xy 60.200436 -523.105235) (xy 60.184566 -523.17477) (xy 60.161009 -523.24209)
			(xy 60.130064 -523.306349) (xy 60.092118 -523.36674) (xy 60.047649 -523.422502) (xy 59.997216 -523.472935)
			(xy 59.941454 -523.517404) (xy 59.881063 -523.55535) (xy 59.816804 -523.586295) (xy 59.749484 -523.609852)
			(xy 59.679949 -523.625722) (xy 59.609075 -523.633708) (xy 59.537753 -523.633708) (xy 59.466879 -523.625722)
			(xy 59.397344 -523.609852) (xy 59.330024 -523.586295) (xy 59.265765 -523.55535) (xy 59.205374 -523.517404)
			(xy 59.149612 -523.472935) (xy 59.099179 -523.422502) (xy 59.05471 -523.36674) (xy 59.016764 -523.306349)
			(xy 58.985819 -523.24209) (xy 58.962262 -523.17477) (xy 58.946392 -523.105235) (xy 58.938406 -523.034361)
			(xy 57.67655 -523.034361) (xy 57.668564 -523.105235) (xy 57.652694 -523.17477) (xy 57.629137 -523.24209)
			(xy 57.598192 -523.306349) (xy 57.560246 -523.36674) (xy 57.515777 -523.422502) (xy 57.465344 -523.472935)
			(xy 57.409582 -523.517404) (xy 57.349191 -523.55535) (xy 57.284932 -523.586295) (xy 57.217612 -523.609852)
			(xy 57.148077 -523.625722) (xy 57.077203 -523.633708) (xy 57.005881 -523.633708) (xy 56.935007 -523.625722)
			(xy 56.865472 -523.609852) (xy 56.798152 -523.586295) (xy 56.733893 -523.55535) (xy 56.673502 -523.517404)
			(xy 56.61774 -523.472935) (xy 56.567307 -523.422502) (xy 56.522838 -523.36674) (xy 56.484892 -523.306349)
			(xy 56.453947 -523.24209) (xy 56.43039 -523.17477) (xy 56.41452 -523.105235) (xy 56.406534 -523.034361)
			(xy 36.447235 -523.034361) (xy 36.431719 -523.088893) (xy 36.400327 -523.169925) (xy 36.361593 -523.247714)
			(xy 36.315846 -523.321598) (xy 36.263477 -523.390945) (xy 36.204933 -523.455165) (xy 36.140713 -523.513709)
			(xy 36.071366 -523.566078) (xy 35.997482 -523.611825) (xy 35.919693 -523.650559) (xy 35.838661 -523.681951)
			(xy 35.755079 -523.705732) (xy 35.669659 -523.7217) (xy 35.58313 -523.729718) (xy 35.49623 -523.729718)
			(xy 35.409701 -523.7217) (xy 35.324281 -523.705732) (xy 35.240699 -523.681951) (xy 35.159667 -523.650559)
			(xy 35.081878 -523.611825) (xy 35.007994 -523.566078) (xy 34.938647 -523.513709) (xy 34.874427 -523.455165)
			(xy 34.815883 -523.390945) (xy 34.763514 -523.321598) (xy 34.717767 -523.247714) (xy 34.679033 -523.169925)
			(xy 34.647641 -523.088893) (xy 34.62386 -523.005311) (xy 34.607892 -522.919891) (xy 34.599874 -522.833362)
			(xy 31.399486 -522.833362) (xy 31.391468 -522.919891) (xy 31.3755 -523.005311) (xy 31.351719 -523.088893)
			(xy 31.320327 -523.169925) (xy 31.281593 -523.247714) (xy 31.235846 -523.321598) (xy 31.183477 -523.390945)
			(xy 31.124933 -523.455165) (xy 31.060713 -523.513709) (xy 30.991366 -523.566078) (xy 30.917482 -523.611825)
			(xy 30.839693 -523.650559) (xy 30.758661 -523.681951) (xy 30.675079 -523.705732) (xy 30.589659 -523.7217)
			(xy 30.50313 -523.729718) (xy 30.41623 -523.729718) (xy 30.329701 -523.7217) (xy 30.244281 -523.705732)
			(xy 30.160699 -523.681951) (xy 30.079667 -523.650559) (xy 30.001878 -523.611825) (xy 29.927994 -523.566078)
			(xy 29.858647 -523.513709) (xy 29.794427 -523.455165) (xy 29.735883 -523.390945) (xy 29.683514 -523.321598)
			(xy 29.637767 -523.247714) (xy 29.599033 -523.169925) (xy 29.567641 -523.088893) (xy 29.54386 -523.005311)
			(xy 29.527892 -522.919891) (xy 29.519874 -522.833362) (xy 13.712964 -522.833362) (xy 13.713074 -522.836372)
			(xy 13.722359 -522.869601) (xy 13.740193 -522.899136) (xy 13.765276 -522.922826) (xy 13.780262 -522.93139)
			(xy 13.815972 -522.950788) (xy 13.883773 -522.995599) (xy 13.946845 -523.046853) (xy 14.004579 -523.104053)
			(xy 14.056416 -523.166647) (xy 14.101855 -523.234029) (xy 14.140457 -523.305548) (xy 14.171848 -523.380512)
			(xy 14.195726 -523.458196) (xy 14.211859 -523.537851) (xy 14.22009 -523.618704) (xy 14.220342 -523.699975)
			(xy 14.212611 -523.780878) (xy 14.196971 -523.86063) (xy 14.173575 -523.938461) (xy 14.142648 -524.013618)
			(xy 14.10449 -524.085375) (xy 14.059468 -524.153037) (xy 14.00802 -524.21595) (xy 13.950641 -524.273506)
			(xy 13.887887 -524.325149) (xy 13.820365 -524.37038) (xy 13.748727 -524.40876) (xy 13.673666 -524.439919)
			(xy 13.595908 -524.463556) (xy 13.516204 -524.479443) (xy 13.435326 -524.487424) (xy 13.354054 -524.487424)
			(xy 13.273176 -524.479443) (xy 13.193472 -524.463556) (xy 13.115714 -524.439919) (xy 13.040653 -524.40876)
			(xy 12.969015 -524.37038) (xy 12.901493 -524.325149) (xy 12.838739 -524.273506) (xy 12.78136 -524.21595)
			(xy 12.729912 -524.153037) (xy 12.68489 -524.085375) (xy 12.646732 -524.013618) (xy 12.615805 -523.938461)
			(xy 12.592409 -523.86063) (xy 12.576769 -523.780878) (xy 12.569038 -523.699975) (xy 12.56929 -523.618704)
			(xy 12.577521 -523.537851) (xy 12.593654 -523.458196) (xy 12.617532 -523.380512) (xy 12.648923 -523.305548)
			(xy 12.687525 -523.234029) (xy 12.732964 -523.166647) (xy 12.784801 -523.104053) (xy 12.842535 -523.046853)
			(xy 12.905607 -522.995599) (xy 12.973408 -522.950788) (xy 13.009118 -522.93139) (xy 13.024138 -522.922866)
			(xy 13.049267 -522.899194) (xy 13.067114 -522.869643) (xy 13.076367 -522.836384) (xy 13.076936 -522.819122)
			(xy 13.076936 -521.94587) (xy 13.076468 -521.923632) (xy 13.068739 -521.879832) (xy 13.053503 -521.838047)
			(xy 13.031226 -521.799552) (xy 13.002589 -521.765522) (xy 12.968465 -521.736996) (xy 12.929897 -521.714845)
			(xy 12.888062 -521.699747) (xy 12.844238 -521.69216) (xy 12.799762 -521.692318) (xy 12.755992 -521.700216)
			(xy 12.714265 -521.715611) (xy 12.675856 -521.738035) (xy 12.658598 -521.752068) (xy 12.627085 -521.778121)
			(xy 12.559781 -521.824558) (xy 12.488218 -521.864118) (xy 12.413096 -521.896412) (xy 12.33515 -521.921124)
			(xy 12.255144 -521.938014) (xy 12.17386 -521.946914) (xy 12.092095 -521.947739) (xy 12.010648 -521.94048)
			(xy 11.930318 -521.925209) (xy 11.851889 -521.902074) (xy 11.776131 -521.871302) (xy 11.703784 -521.833194)
			(xy 11.635557 -521.788124) (xy 11.572117 -521.736533) (xy 11.514086 -521.678925) (xy 11.462032 -521.615865)
			(xy 11.416464 -521.547969) (xy 11.377828 -521.475903) (xy 11.346503 -521.400372) (xy 11.322795 -521.322115)
			(xy 11.306936 -521.241898) (xy 11.299081 -521.160507) (xy 11.299308 -521.078737) (xy 11.307613 -520.997391)
			(xy 11.323917 -520.917263) (xy 11.335512 -520.878054) (xy 11.340045 -520.86141) (xy 11.34099 -520.826939)
			(xy 11.3327 -520.793466) (xy 11.315778 -520.76342) (xy 11.304016 -520.7508) (xy 9.303766 -518.750296)
			(xy 9.287123 -518.734347) (xy 9.249193 -518.708163) (xy 9.207161 -518.689248) (xy 9.162408 -518.678224)
			(xy 9.116401 -518.675452) (xy 9.070647 -518.681023) (xy 9.026649 -518.694754) (xy 8.985849 -518.716195)
			(xy 8.949584 -518.744643) (xy 8.919045 -518.779164) (xy 8.895232 -518.818627) (xy 8.878927 -518.861738)
			(xy 8.870664 -518.907082) (xy 8.870188 -518.930128) (xy 8.870188 -521.97889) (xy 8.669782 -522.179296)
			(xy 8.658349 -522.191398) (xy 8.641648 -522.220187) (xy 8.63297 -522.252318) (xy 8.632444 -522.268958)
			(xy 8.632444 -522.819122) (xy 8.633074 -522.836372) (xy 8.642359 -522.869601) (xy 8.660193 -522.899136)
			(xy 8.685276 -522.922826) (xy 8.700262 -522.93139) (xy 8.736052 -522.950853) (xy 8.803997 -522.995813)
			(xy 8.867186 -523.047244) (xy 8.925005 -523.104645) (xy 8.976893 -523.167459) (xy 9.022346 -523.235075)
			(xy 9.060923 -523.306837) (xy 9.092247 -523.382049) (xy 9.116016 -523.459978) (xy 9.131999 -523.539869)
			(xy 9.140039 -523.620945) (xy 9.14006 -523.702418) (xy 9.13206 -523.783498) (xy 9.116118 -523.863397)
			(xy 9.092389 -523.941338) (xy 9.077198 -523.97914) (xy 9.06898 -524.000319) (xy 9.059246 -524.044687)
			(xy 9.057558 -524.090078) (xy 9.063969 -524.135045) (xy 9.078274 -524.178156) (xy 9.100019 -524.218035)
			(xy 9.128509 -524.253412) (xy 9.162837 -524.283157) (xy 9.201907 -524.306324) (xy 9.244475 -524.322173)
			(xy 9.289182 -524.330199) (xy 9.311894 -524.330676) (xy 9.736328 -524.330676) (xy 10.058908 -524.008096)
			(xy 10.075926 -523.939516) (xy 10.065512 -523.905734) (xy 10.053991 -523.866765) (xy 10.037742 -523.78714)
			(xy 10.029392 -523.706303) (xy 10.029021 -523.625037) (xy 10.036632 -523.544128) (xy 10.052153 -523.464358)
			(xy 10.075433 -523.386497) (xy 10.106246 -523.311298) (xy 10.144296 -523.23949) (xy 10.189213 -523.171765)
			(xy 10.240565 -523.108779) (xy 10.297854 -523.05114) (xy 10.360527 -522.999407) (xy 10.427977 -522.954078)
			(xy 10.499553 -522.915592) (xy 10.574563 -522.884322) (xy 10.65228 -522.860569) (xy 10.731955 -522.844564)
			(xy 10.812817 -522.83646) (xy 10.894083 -522.836337) (xy 10.974969 -522.844196) (xy 11.054692 -522.85996)
			(xy 11.132481 -522.883477) (xy 11.207585 -522.91452) (xy 11.279277 -522.952789) (xy 11.346864 -522.997913)
			(xy 11.409693 -523.049457) (xy 11.467157 -523.106921) (xy 11.518699 -523.169752) (xy 11.563822 -523.23734)
			(xy 11.602089 -523.309033) (xy 11.63313 -523.384138) (xy 11.656645 -523.461928) (xy 11.672407 -523.541651)
			(xy 11.680264 -523.622537) (xy 11.680139 -523.703803) (xy 11.672033 -523.784665) (xy 11.656026 -523.864339)
			(xy 11.632271 -523.942056) (xy 11.600999 -524.017065) (xy 11.562512 -524.08864) (xy 11.517181 -524.156089)
			(xy 11.465446 -524.218761) (xy 11.407806 -524.276048) (xy 11.344819 -524.327398) (xy 11.277093 -524.372315)
			(xy 11.205283 -524.410362) (xy 11.130084 -524.441174) (xy 11.052223 -524.464452) (xy 10.972452 -524.47997)
			(xy 10.891543 -524.48758) (xy 10.810277 -524.487207) (xy 10.729441 -524.478855) (xy 10.649815 -524.462604)
			(xy 10.61085 -524.451072) (xy 10.577068 -524.440658) (xy 10.508488 -524.457676) (xy 9.999472 -524.966692)
			(xy 7.808722 -524.966692) (xy 7.013956 -524.171926) (xy 7.013956 -522.234668) (xy 7.085076 -522.163548)
			(xy 7.096504 -522.151387) (xy 7.113214 -522.122517) (xy 7.121867 -522.090301) (xy 7.121873 -522.056944)
			(xy 7.113231 -522.024725) (xy 7.096532 -521.995849) (xy 7.085076 -521.983716) (xy 7.050786 -521.949426)
			(xy 7.002018 -521.946886) (xy 6.963661 -521.944479) (xy 6.887608 -521.933368) (xy 6.812916 -521.91524)
			(xy 6.740231 -521.890254) (xy 6.670181 -521.858624) (xy 6.603371 -521.820624) (xy 6.54038 -521.776584)
			(xy 6.510782 -521.752068) (xy 6.493524 -521.738041) (xy 6.455112 -521.715636) (xy 6.413387 -521.700255)
			(xy 6.369622 -521.69237) (xy 6.325153 -521.69222) (xy 6.281336 -521.699809) (xy 6.239508 -521.714907)
			(xy 6.200945 -521.737052) (xy 6.166823 -521.765569) (xy 6.138184 -521.799589) (xy 6.115901 -521.838072)
			(xy 6.100654 -521.879846) (xy 6.092908 -521.923635) (xy 6.092444 -521.94587) (xy 6.092444 -522.819122)
			(xy 6.093074 -522.836372) (xy 6.102359 -522.869601) (xy 6.120193 -522.899136) (xy 6.145276 -522.922826)
			(xy 6.160262 -522.93139) (xy 6.195972 -522.950788) (xy 6.263773 -522.995599) (xy 6.326845 -523.046853)
			(xy 6.384579 -523.104053) (xy 6.436416 -523.166647) (xy 6.481855 -523.234029) (xy 6.520457 -523.305548)
			(xy 6.551848 -523.380512) (xy 6.575726 -523.458196) (xy 6.591859 -523.537851) (xy 6.60009 -523.618704)
			(xy 6.600342 -523.699975) (xy 6.592611 -523.780878) (xy 6.576971 -523.86063) (xy 6.553575 -523.938461)
			(xy 6.522648 -524.013618) (xy 6.48449 -524.085375) (xy 6.439468 -524.153037) (xy 6.38802 -524.21595)
			(xy 6.330641 -524.273506) (xy 6.267887 -524.325149) (xy 6.200365 -524.37038) (xy 6.128727 -524.40876)
			(xy 6.053666 -524.439919) (xy 5.975908 -524.463556) (xy 5.896204 -524.479443) (xy 5.815326 -524.487424)
			(xy 5.734054 -524.487424) (xy 5.653176 -524.479443) (xy 5.573472 -524.463556) (xy 5.495714 -524.439919)
			(xy 5.420653 -524.40876) (xy 5.349015 -524.37038) (xy 5.281493 -524.325149) (xy 5.218739 -524.273506)
			(xy 5.16136 -524.21595) (xy 5.109912 -524.153037) (xy 5.06489 -524.085375) (xy 5.026732 -524.013618)
			(xy 4.995805 -523.938461) (xy 4.972409 -523.86063) (xy 4.956769 -523.780878) (xy 4.949038 -523.699975)
			(xy 4.94929 -523.618704) (xy 4.957521 -523.537851) (xy 4.973654 -523.458196) (xy 4.997532 -523.380512)
			(xy 5.028923 -523.305548) (xy 5.067525 -523.234029) (xy 5.112964 -523.166647) (xy 5.164801 -523.104053)
			(xy 5.222535 -523.046853) (xy 5.285607 -522.995599) (xy 5.353408 -522.950788) (xy 5.389118 -522.93139)
			(xy 5.404138 -522.922866) (xy 5.429267 -522.899194) (xy 5.447114 -522.869643) (xy 5.456367 -522.836384)
			(xy 5.456936 -522.819122) (xy 5.456936 -521.94587) (xy 5.456468 -521.923632) (xy 5.448739 -521.879832)
			(xy 5.433503 -521.838047) (xy 5.411226 -521.799552) (xy 5.382589 -521.765522) (xy 5.348465 -521.736996)
			(xy 5.309897 -521.714845) (xy 5.268062 -521.699747) (xy 5.224238 -521.69216) (xy 5.179762 -521.692318)
			(xy 5.135992 -521.700216) (xy 5.094265 -521.715611) (xy 5.055856 -521.738035) (xy 5.038598 -521.752068)
			(xy 5.007183 -521.778042) (xy 4.940099 -521.824353) (xy 4.868779 -521.863831) (xy 4.793916 -521.896091)
			(xy 4.71624 -521.920819) (xy 4.636506 -521.937775) (xy 4.555489 -521.946793) (xy 4.473977 -521.947787)
			(xy 4.392765 -521.940746) (xy 4.312641 -521.925739) (xy 4.234385 -521.902912) (xy 4.158758 -521.872487)
			(xy 4.086496 -521.83476) (xy 4.018303 -521.790098) (xy 3.954841 -521.738935) (xy 3.896727 -521.681769)
			(xy 3.844528 -521.619156) (xy 3.798751 -521.551706) (xy 3.759841 -521.480075) (xy 3.728177 -521.404958)
			(xy 3.704066 -521.327088) (xy 3.687744 -521.247222) (xy 3.679369 -521.166136) (xy 3.679023 -521.084619)
			(xy 3.686708 -521.003465) (xy 3.702351 -520.923462) (xy 3.725799 -520.84539) (xy 3.756824 -520.770008)
			(xy 3.795124 -520.698048) (xy 3.840326 -520.630211) (xy 3.891991 -520.567157) (xy 3.949617 -520.5095)
			(xy 4.012642 -520.4578) (xy 4.080453 -520.412559) (xy 4.152392 -520.37422) (xy 4.227757 -520.343153)
			(xy 4.305816 -520.319662) (xy 4.38581 -520.303974) (xy 4.46696 -520.296244) (xy 4.548477 -520.296545)
			(xy 4.629567 -520.304874) (xy 4.709443 -520.321152) (xy 4.74853 -520.332716) (xy 4.782312 -520.34313)
			(xy 4.850892 -520.326112) (xy 6.864096 -518.312908) (xy 6.864096 -512.347464) (xy 22.355048 -496.856512)
			(xy 22.355048 -471.5256) (xy 17.237456 -466.407754) (xy 17.237456 -463.695796) (xy 17.236934 -463.672735)
			(xy 17.228683 -463.627358) (xy 17.212379 -463.584215) (xy 17.188557 -463.544722) (xy 17.158 -463.510176)
			(xy 17.121712 -463.481711) (xy 17.080882 -463.460261) (xy 17.036852 -463.44653) (xy 16.991068 -463.44097)
			(xy 16.945032 -463.443763) (xy 16.900255 -463.454817) (xy 16.858208 -463.473769) (xy 16.820271 -463.499997)
			(xy 16.803624 -463.515964) (xy 9.117076 -471.202512) (xy 9.117076 -473.69984) (xy 11.345418 -473.69984)
			(xy 11.345925 -473.59666) (xy 11.354026 -473.390459) (xy 11.370217 -473.184735) (xy 11.394472 -472.979805)
			(xy 11.426754 -472.775985) (xy 11.467013 -472.57359) (xy 11.515187 -472.372931) (xy 11.571201 -472.174319)
			(xy 11.63497 -471.978059) (xy 11.706395 -471.784453) (xy 11.785365 -471.593801) (xy 11.87176 -471.406397)
			(xy 11.965446 -471.222528) (xy 12.066278 -471.04248) (xy 12.174101 -470.866529) (xy 12.288748 -470.694946)
			(xy 12.410044 -470.527998) (xy 12.5378 -470.365939) (xy 12.671821 -470.209022) (xy 12.811898 -470.057487)
			(xy 12.957817 -469.911568) (xy 13.109352 -469.771491) (xy 13.266269 -469.63747) (xy 13.428328 -469.509714)
			(xy 13.595276 -469.388418) (xy 13.766859 -469.273771) (xy 13.94281 -469.165948) (xy 14.122858 -469.065116)
			(xy 14.306727 -468.97143) (xy 14.494131 -468.885035) (xy 14.684783 -468.806065) (xy 14.878389 -468.73464)
			(xy 15.074649 -468.670871) (xy 15.273261 -468.614857) (xy 15.47392 -468.566683) (xy 15.676315 -468.526424)
			(xy 15.880135 -468.494142) (xy 16.085065 -468.469887) (xy 16.290789 -468.453696) (xy 16.49699 -468.445595)
			(xy 16.60017 -468.445088) (xy 16.70335 -468.445595) (xy 16.909551 -468.453696) (xy 17.115275 -468.469887)
			(xy 17.320205 -468.494142) (xy 17.524025 -468.526424) (xy 17.72642 -468.566683) (xy 17.927079 -468.614857)
			(xy 18.125691 -468.670871) (xy 18.321951 -468.73464) (xy 18.515557 -468.806065) (xy 18.706209 -468.885035)
			(xy 18.893613 -468.97143) (xy 19.077482 -469.065116) (xy 19.25753 -469.165948) (xy 19.433481 -469.273771)
			(xy 19.605064 -469.388418) (xy 19.772012 -469.509714) (xy 19.934071 -469.63747) (xy 20.090988 -469.771491)
			(xy 20.242523 -469.911568) (xy 20.388442 -470.057487) (xy 20.528519 -470.209022) (xy 20.66254 -470.365939)
			(xy 20.790296 -470.527998) (xy 20.911592 -470.694946) (xy 21.026239 -470.866529) (xy 21.134062 -471.04248)
			(xy 21.234894 -471.222528) (xy 21.32858 -471.406397) (xy 21.414975 -471.593801) (xy 21.493945 -471.784453)
			(xy 21.56537 -471.978059) (xy 21.629139 -472.174319) (xy 21.685153 -472.372931) (xy 21.733327 -472.57359)
			(xy 21.773586 -472.775985) (xy 21.805868 -472.979805) (xy 21.830123 -473.184735) (xy 21.846314 -473.390459)
			(xy 21.854415 -473.59666) (xy 21.854922 -473.69984) (xy 21.854428 -473.801746) (xy 21.846525 -474.005405)
			(xy 21.830731 -474.208605) (xy 21.80707 -474.411039) (xy 21.775577 -474.612404) (xy 21.7363 -474.812396)
			(xy 21.689297 -475.010715) (xy 21.634641 -475.207062) (xy 21.572411 -475.401142) (xy 21.502703 -475.592663)
			(xy 21.425622 -475.781337) (xy 21.341282 -475.96688) (xy 21.249811 -476.149013) (xy 21.151347 -476.327463)
			(xy 21.046037 -476.50196) (xy 20.93404 -476.672243) (xy 20.815525 -476.838055) (xy 20.690669 -476.999147)
			(xy 20.559661 -477.155277) (xy 20.422697 -477.306209) (xy 20.279984 -477.451716) (xy 20.131737 -477.591581)
			(xy 19.978177 -477.725592) (xy 19.819537 -477.853548) (xy 19.656054 -477.975256) (xy 19.487975 -478.090534)
			(xy 19.315552 -478.199208) (xy 19.139046 -478.301114) (xy 18.95872 -478.396099) (xy 18.774847 -478.484021)
			(xy 18.587703 -478.564747) (xy 18.39757 -478.638156) (xy 18.204733 -478.704137) (xy 18.009483 -478.762591)
			(xy 17.812113 -478.81343) (xy 17.61292 -478.856578) (xy 17.412204 -478.89197) (xy 17.210267 -478.919552)
			(xy 17.007412 -478.939283) (xy 16.803944 -478.951134) (xy 16.60017 -478.955086) (xy 16.396396 -478.951134)
			(xy 16.192928 -478.939283) (xy 15.990073 -478.919552) (xy 15.788136 -478.89197) (xy 15.58742 -478.856578)
			(xy 15.388227 -478.81343) (xy 15.190857 -478.762591) (xy 14.995607 -478.704137) (xy 14.80277 -478.638156)
			(xy 14.612637 -478.564747) (xy 14.425493 -478.484021) (xy 14.24162 -478.396099) (xy 14.061294 -478.301114)
			(xy 13.884788 -478.199208) (xy 13.712365 -478.090534) (xy 13.544286 -477.975256) (xy 13.380803 -477.853548)
			(xy 13.222163 -477.725592) (xy 13.068603 -477.591581) (xy 12.920356 -477.451716) (xy 12.777643 -477.306209)
			(xy 12.640679 -477.155277) (xy 12.509671 -476.999147) (xy 12.384815 -476.838055) (xy 12.2663 -476.672243)
			(xy 12.154303 -476.50196) (xy 12.048993 -476.327463) (xy 11.950529 -476.149013) (xy 11.859058 -475.96688)
			(xy 11.774718 -475.781337) (xy 11.697637 -475.592663) (xy 11.627929 -475.401142) (xy 11.565699 -475.207062)
			(xy 11.511043 -475.010715) (xy 11.46404 -474.812396) (xy 11.424763 -474.612404) (xy 11.39327 -474.411039)
			(xy 11.369609 -474.208605) (xy 11.353815 -474.005405) (xy 11.345912 -473.801746) (xy 11.345418 -473.69984)
			(xy 9.117076 -473.69984) (xy 9.117076 -488.294325) (xy 12.580876 -488.294325) (xy 12.582892 -488.164712)
			(xy 12.592962 -488.035476) (xy 12.611047 -487.907115) (xy 12.637077 -487.780127) (xy 12.670952 -487.655003)
			(xy 12.71254 -487.532227) (xy 12.761681 -487.412274) (xy 12.818184 -487.295609) (xy 12.881831 -487.182681)
			(xy 12.952375 -487.073929) (xy 13.029544 -486.969773) (xy 13.113039 -486.870616) (xy 13.202537 -486.776842)
			(xy 13.297692 -486.688813) (xy 13.398135 -486.60687) (xy 13.503478 -486.531331) (xy 13.613314 -486.462486)
			(xy 13.727218 -486.400603) (xy 13.844748 -486.345922) (xy 13.965451 -486.298652) (xy 14.088859 -486.258979)
			(xy 14.214495 -486.227054) (xy 14.341872 -486.203002) (xy 14.470498 -486.186915) (xy 14.599876 -486.178856)
			(xy 14.66469 -486.178352) (xy 14.729504 -486.178856) (xy 14.858882 -486.186915) (xy 14.987508 -486.203002)
			(xy 15.114885 -486.227054) (xy 15.240521 -486.258979) (xy 15.363929 -486.298652) (xy 15.484632 -486.345922)
			(xy 15.602162 -486.400603) (xy 15.716066 -486.462486) (xy 15.825902 -486.531331) (xy 15.931245 -486.60687)
			(xy 16.031688 -486.688813) (xy 16.126843 -486.776842) (xy 16.216341 -486.870616) (xy 16.299836 -486.969773)
			(xy 16.377005 -487.073929) (xy 16.447549 -487.182681) (xy 16.511196 -487.295609) (xy 16.567699 -487.412274)
			(xy 16.61684 -487.532227) (xy 16.658428 -487.655003) (xy 16.692303 -487.780127) (xy 16.718333 -487.907115)
			(xy 16.736418 -488.035476) (xy 16.746488 -488.164712) (xy 16.748504 -488.294325) (xy 16.742458 -488.423812)
			(xy 16.728374 -488.552673) (xy 16.706305 -488.680409) (xy 16.676338 -488.806526) (xy 16.638589 -488.930536)
			(xy 16.593202 -489.051959) (xy 16.540355 -489.170326) (xy 16.480251 -489.285178) (xy 16.413123 -489.396071)
			(xy 16.339231 -489.502577) (xy 16.25886 -489.604283) (xy 16.172322 -489.700795) (xy 16.07995 -489.79174)
			(xy 15.982104 -489.876767) (xy 15.879161 -489.955547) (xy 15.771519 -490.027774) (xy 15.659595 -490.093169)
			(xy 15.543822 -490.15148) (xy 15.424648 -490.20248) (xy 15.302534 -490.245972) (xy 15.177951 -490.281789)
			(xy 15.051384 -490.309791) (xy 14.92332 -490.32987) (xy 14.794256 -490.341949) (xy 14.66469 -490.34598)
			(xy 14.535124 -490.341949) (xy 14.40606 -490.32987) (xy 14.277996 -490.309791) (xy 14.151429 -490.281789)
			(xy 14.026846 -490.245972) (xy 13.904732 -490.20248) (xy 13.785558 -490.15148) (xy 13.669785 -490.093169)
			(xy 13.557861 -490.027774) (xy 13.450219 -489.955547) (xy 13.347276 -489.876767) (xy 13.24943 -489.79174)
			(xy 13.157058 -489.700795) (xy 13.07052 -489.604283) (xy 12.990149 -489.502577) (xy 12.916257 -489.396071)
			(xy 12.849129 -489.285178) (xy 12.789025 -489.170326) (xy 12.736178 -489.051959) (xy 12.690791 -488.930536)
			(xy 12.653042 -488.806526) (xy 12.623075 -488.680409) (xy 12.601006 -488.552673) (xy 12.586922 -488.423812)
			(xy 12.580876 -488.294325) (xy 9.117076 -488.294325) (xy 9.117076 -489.659168) (xy 9.11763 -489.675784)
			(xy 9.126224 -489.707885) (xy 9.142812 -489.736681) (xy 9.15416 -489.74883) (xy 14.720316 -495.314732)
			(xy 14.720316 -497.687346) (xy 13.85316 -498.554248) (xy 9.267698 -498.554248) (xy 8.685784 -497.972588)
			(xy 8.673185 -497.960791) (xy 8.643151 -497.943813) (xy 8.609662 -497.935523) (xy 8.575176 -497.93653)
			(xy 8.55853 -497.941092) (xy 8.519453 -497.952661) (xy 8.439597 -497.968955) (xy 8.358524 -497.977302)
			(xy 8.277023 -497.977621) (xy 8.195887 -497.96991) (xy 8.115906 -497.954242) (xy 8.037857 -497.930771)
			(xy 7.962501 -497.899724) (xy 7.89057 -497.861404) (xy 7.822764 -497.816184) (xy 7.790942 -497.790724)
			(xy 7.773548 -497.77717) (xy 7.735118 -497.75556) (xy 7.693533 -497.740909) (xy 7.650044 -497.733658)
			(xy 7.605955 -497.734023) (xy 7.562592 -497.741994) (xy 7.521256 -497.757332) (xy 7.483189 -497.779576)
			(xy 7.449533 -497.808058) (xy 7.4213 -497.841923) (xy 7.399337 -497.880153) (xy 7.384304 -497.921601)
			(xy 7.376652 -497.965022) (xy 7.37616 -497.987066) (xy 7.37616 -498.022118) (xy 6.41985 -498.978428)
			(xy 5.308346 -498.978428) (xy 4.186936 -497.856764) (xy 4.186936 -495.454686) (xy 4.18631 -495.437436)
			(xy 4.177026 -495.404206) (xy 4.15919 -495.37467) (xy 4.134105 -495.350981) (xy 4.119118 -495.342418)
			(xy 4.083236 -495.32298) (xy 4.01517 -495.277947) (xy 3.951878 -495.22642) (xy 3.893977 -495.168903)
			(xy 3.84203 -495.105956) (xy 3.796544 -495.038192) (xy 3.757964 -494.966273) (xy 3.726664 -494.890899)
			(xy 3.702951 -494.812806) (xy 3.687056 -494.732755) (xy 3.679132 -494.651526) (xy 3.679259 -494.569912)
			(xy 3.687434 -494.488709) (xy 3.703578 -494.408707) (xy 3.727533 -494.330688) (xy 3.759067 -494.255412)
			(xy 3.79787 -494.183613) (xy 3.843566 -494.115991) (xy 3.895707 -494.053205) (xy 3.953787 -493.995867)
			(xy 4.017239 -493.944538) (xy 4.085444 -493.899716) (xy 4.157736 -493.86184) (xy 4.233412 -493.831278)
			(xy 4.311733 -493.808329) (xy 4.391935 -493.793215) (xy 4.473237 -493.786086) (xy 4.554846 -493.787009)
			(xy 4.635966 -493.795977) (xy 4.715806 -493.812901) (xy 4.793587 -493.837618) (xy 4.868552 -493.869884)
			(xy 4.939969 -493.909387) (xy 5.007142 -493.955741) (xy 5.038598 -493.98174) (xy 5.05586 -493.995762)
			(xy 5.094272 -494.018166) (xy 5.135996 -494.033545) (xy 5.17976 -494.04143) (xy 5.224228 -494.04158)
			(xy 5.268044 -494.033991) (xy 5.309871 -494.018894) (xy 5.348433 -493.99675) (xy 5.382554 -493.968233)
			(xy 5.411193 -493.934215) (xy 5.433477 -493.895733) (xy 5.448725 -493.85396) (xy 5.456472 -493.810172)
			(xy 5.456936 -493.787938) (xy 5.456936 -493.071658) (xy 6.388608 -492.139732) (xy 6.388608 -470.229438)
			(xy 14.53896 -462.07934) (xy 14.550312 -462.067192) (xy 14.566915 -462.038401) (xy 14.575506 -462.006296)
			(xy 14.576044 -461.989678) (xy 14.576044 -413.08655) (xy 14.575468 -413.06333) (xy 14.567003 -413.017667)
			(xy 14.550383 -412.974303) (xy 14.526161 -412.934679) (xy 14.495143 -412.900116) (xy 14.458362 -412.871764)
			(xy 14.417041 -412.850566) (xy 14.372557 -412.837229) (xy 14.32639 -412.832195) (xy 14.280077 -412.835633)
			(xy 14.235159 -412.847429) (xy 14.193132 -412.867189) (xy 14.173962 -412.880302) (xy 14.141758 -412.902801)
			(xy 14.073677 -412.942006) (xy 14.002032 -412.974242) (xy 13.927535 -412.999188) (xy 13.850925 -413.016596)
			(xy 13.772963 -413.026295) (xy 13.694423 -413.028186) (xy 13.616085 -413.022253) (xy 13.538726 -413.008553)
			(xy 13.463114 -412.987223) (xy 13.39 -412.958474) (xy 13.32011 -412.922592) (xy 13.254138 -412.879933)
			(xy 13.192739 -412.830921) (xy 13.136521 -412.776041) (xy 13.086045 -412.71584) (xy 13.041809 -412.650914)
			(xy 13.004254 -412.581909) (xy 12.973753 -412.509508) (xy 12.950608 -412.434432) (xy 12.935049 -412.357425)
			(xy 12.927231 -412.279253) (xy 12.927231 -412.20069) (xy 12.935049 -412.122517) (xy 12.950608 -412.04551)
			(xy 12.973752 -411.970434) (xy 13.004253 -411.898034) (xy 13.041808 -411.829028) (xy 13.086043 -411.764102)
			(xy 13.13652 -411.7039) (xy 13.192737 -411.649021) (xy 13.254136 -411.600008) (xy 13.320108 -411.557349)
			(xy 13.389998 -411.521467) (xy 13.463112 -411.492718) (xy 13.538724 -411.471387) (xy 13.616083 -411.457687)
			(xy 13.694421 -411.451754) (xy 13.772961 -411.453645) (xy 13.850923 -411.463343) (xy 13.927533 -411.480752)
			(xy 14.00203 -411.505697) (xy 14.073675 -411.537933) (xy 14.141756 -411.577138) (xy 14.173962 -411.599634)
			(xy 14.193086 -411.612812) (xy 14.235126 -411.632551) (xy 14.28005 -411.644327) (xy 14.326367 -411.647749)
			(xy 14.372534 -411.642705) (xy 14.417018 -411.62936) (xy 14.45834 -411.608159) (xy 14.495124 -411.579808)
			(xy 14.526148 -411.545248) (xy 14.550381 -411.505628) (xy 14.567017 -411.462268) (xy 14.575502 -411.416607)
			(xy 14.576044 -411.393386) (xy 14.576044 -410.944568) (xy 14.575464 -410.927954) (xy 14.56688 -410.895854)
			(xy 14.550303 -410.867057) (xy 14.53896 -410.854906) (xy 13.59154 -409.90774) (xy 13.575101 -409.89191)
			(xy 13.537585 -409.865923) (xy 13.496032 -409.847055) (xy 13.451778 -409.83591) (xy 13.406244 -409.832847)
			(xy 13.360896 -409.837966) (xy 13.31719 -409.8511) (xy 13.276533 -409.871829) (xy 13.240231 -409.899484)
			(xy 13.209452 -409.933179) (xy 13.185184 -409.971828) (xy 13.17625 -409.99283) (xy 13.160947 -410.029704)
			(xy 13.12393 -410.100444) (xy 13.079948 -410.167077) (xy 13.029453 -410.228921) (xy 12.972964 -410.285342)
			(xy 12.911057 -410.335761) (xy 12.84437 -410.37966) (xy 12.773585 -410.416591) (xy 12.699428 -410.446174)
			(xy 12.622659 -410.468106) (xy 12.544066 -410.482161) (xy 12.464455 -410.488197) (xy 12.384641 -410.486151)
			(xy 12.305444 -410.476044) (xy 12.227674 -410.457979) (xy 12.15213 -410.432142) (xy 12.079587 -410.398799)
			(xy 12.010787 -410.358289) (xy 11.946436 -410.31103) (xy 11.887195 -410.257506) (xy 11.83367 -410.198264)
			(xy 11.786411 -410.133914) (xy 11.745902 -410.065114) (xy 11.712558 -409.992571) (xy 11.686721 -409.917027)
			(xy 11.668657 -409.839257) (xy 11.658549 -409.76006) (xy 11.656503 -409.680246) (xy 11.662538 -409.600635)
			(xy 11.676594 -409.522042) (xy 11.698526 -409.445273) (xy 11.728109 -409.371116) (xy 11.765039 -409.300331)
			(xy 11.808939 -409.233643) (xy 11.859357 -409.171737) (xy 11.915778 -409.115247) (xy 11.977622 -409.064753)
			(xy 12.044256 -409.020771) (xy 12.114995 -408.983754) (xy 12.151868 -408.968448) (xy 12.172868 -408.959514)
			(xy 12.211512 -408.935247) (xy 12.245202 -408.904469) (xy 12.272853 -408.868169) (xy 12.293577 -408.827514)
			(xy 12.306708 -408.783811) (xy 12.311823 -408.738467) (xy 12.308757 -408.692938) (xy 12.29761 -408.648688)
			(xy 12.278739 -408.60714) (xy 12.252752 -408.569631) (xy 12.236958 -408.553158) (xy 7.817612 -404.133558)
			(xy 7.817612 -394.59027) (xy 6.449568 -393.222226) (xy 6.449568 -380.16688) (xy 8.853424 -377.76277)
			(xy 8.853424 -350.54667) (xy 8.852909 -350.524562) (xy 8.845267 -350.481012) (xy 8.830202 -350.439441)
			(xy 8.808168 -350.401107) (xy 8.779832 -350.367165) (xy 8.746047 -350.33864) (xy 8.707835 -350.316395)
			(xy 8.666349 -350.3011) (xy 8.622841 -350.293217) (xy 8.578626 -350.292984) (xy 8.556752 -350.296226)
			(xy 8.521505 -350.30175) (xy 8.450273 -350.305803) (xy 8.379035 -350.301851) (xy 8.308688 -350.289945)
			(xy 8.240117 -350.270233) (xy 8.174186 -350.242965) (xy 8.111724 -350.208483) (xy 8.053518 -350.167222)
			(xy 8.0003 -350.1197) (xy 7.952741 -350.066516) (xy 7.911438 -350.008339) (xy 7.876911 -349.945902)
			(xy 7.849596 -349.87999) (xy 7.829836 -349.811433) (xy 7.817879 -349.741095) (xy 7.813877 -349.66986)
			(xy 7.817879 -349.598624) (xy 7.829836 -349.528286) (xy 7.849596 -349.459729) (xy 7.876911 -349.393818)
			(xy 7.911438 -349.331381) (xy 7.952741 -349.273204) (xy 8.000301 -349.22002) (xy 8.053519 -349.172498)
			(xy 8.111725 -349.131236) (xy 8.174187 -349.096755) (xy 8.240118 -349.069486) (xy 8.308688 -349.049775)
			(xy 8.379035 -349.037869) (xy 8.450273 -349.033917) (xy 8.521506 -349.03797) (xy 8.556752 -349.043498)
			(xy 8.578621 -349.046768) (xy 8.622837 -349.046519) (xy 8.666343 -349.038624) (xy 8.707827 -349.023321)
			(xy 8.746038 -349.001072) (xy 8.779824 -348.972547) (xy 8.808165 -348.938608) (xy 8.830206 -348.900277)
			(xy 8.845284 -348.85871) (xy 8.852943 -348.815162) (xy 8.853424 -348.793054) (xy 8.853424 -348.546674)
			(xy 8.852906 -348.524566) (xy 8.845264 -348.481016) (xy 8.8302 -348.439446) (xy 8.808167 -348.401111)
			(xy 8.77983 -348.367169) (xy 8.746046 -348.338644) (xy 8.707834 -348.316399) (xy 8.666348 -348.301104)
			(xy 8.622841 -348.293221) (xy 8.578626 -348.292988) (xy 8.556752 -348.29623) (xy 8.521507 -348.301766)
			(xy 8.450274 -348.305819) (xy 8.379035 -348.301867) (xy 8.308687 -348.289961) (xy 8.240116 -348.270249)
			(xy 8.174184 -348.242981) (xy 8.111722 -348.208499) (xy 8.053515 -348.167237) (xy 8.000297 -348.119715)
			(xy 7.952737 -348.06653) (xy 7.911433 -348.008353) (xy 7.876906 -347.945915) (xy 7.849591 -347.880003)
			(xy 7.82983 -347.811446) (xy 7.817873 -347.741107) (xy 7.813871 -347.669871) (xy 7.817873 -347.598635)
			(xy 7.82983 -347.528296) (xy 7.84959 -347.459738) (xy 7.876906 -347.393826) (xy 7.911432 -347.331388)
			(xy 7.952736 -347.273211) (xy 8.000296 -347.220026) (xy 8.053514 -347.172504) (xy 8.111721 -347.131242)
			(xy 8.174183 -347.09676) (xy 8.240115 -347.069491) (xy 8.308686 -347.049779) (xy 8.379034 -347.037873)
			(xy 8.450272 -347.033921) (xy 8.521505 -347.037974) (xy 8.556752 -347.043502) (xy 8.578622 -347.046768)
			(xy 8.622837 -347.046519) (xy 8.666343 -347.038624) (xy 8.707826 -347.023322) (xy 8.746037 -347.001073)
			(xy 8.779822 -346.972549) (xy 8.808163 -346.93861) (xy 8.830205 -346.900279) (xy 8.845283 -346.858714)
			(xy 8.852943 -346.815166) (xy 8.853424 -346.793058) (xy 8.853424 -344.546682) (xy 8.852898 -344.524574)
			(xy 8.845258 -344.481024) (xy 8.830195 -344.439454) (xy 8.808163 -344.401119) (xy 8.779827 -344.367177)
			(xy 8.746044 -344.338652) (xy 8.707832 -344.316407) (xy 8.666347 -344.301111) (xy 8.62284 -344.293228)
			(xy 8.578626 -344.292996) (xy 8.556752 -344.296238) (xy 8.521099 -344.301796) (xy 8.449048 -344.305759)
			(xy 8.377011 -344.301535) (xy 8.305916 -344.289179) (xy 8.236679 -344.268849) (xy 8.17019 -344.240808)
			(xy 8.107305 -344.205416) (xy 8.048833 -344.163129) (xy 7.995528 -344.114491) (xy 7.948075 -344.060127)
			(xy 7.907085 -344.000739) (xy 7.873086 -343.93709) (xy 7.846515 -343.87) (xy 7.827715 -343.800332)
			(xy 7.816926 -343.728982) (xy 7.814289 -343.65687) (xy 7.819837 -343.584923) (xy 7.833499 -343.514068)
			(xy 7.855099 -343.445216) (xy 7.884358 -343.379254) (xy 7.920901 -343.317031) (xy 7.964256 -343.259347)
			(xy 8.013867 -343.206945) (xy 8.069093 -343.1605) (xy 8.129225 -343.120609) (xy 8.193489 -343.087786)
			(xy 8.261056 -343.062454) (xy 8.331058 -343.044938) (xy 8.36676 -343.0397) (xy 8.388271 -343.03643)
			(xy 8.429819 -343.023518) (xy 8.468558 -343.003714) (xy 8.503356 -342.977598) (xy 8.533193 -342.945933)
			(xy 8.557199 -342.909647) (xy 8.574669 -342.869801) (xy 8.585093 -342.827561) (xy 8.588166 -342.784162)
			(xy 8.583798 -342.740874) (xy 8.572118 -342.698963) (xy 8.553465 -342.659657) (xy 8.528387 -342.624104)
			(xy 8.513318 -342.608408) (xy 7.807452 -341.902288) (xy 7.807452 -340.748366) (xy 7.806871 -340.731752)
			(xy 7.798287 -340.699652) (xy 7.781711 -340.670855) (xy 7.770368 -340.658704) (xy 6.95579 -339.84438)
			(xy 6.82752 -339.84438) (xy 6.805444 -339.844868) (xy 6.761961 -339.852526) (xy 6.720455 -339.867583)
			(xy 6.682177 -339.889588) (xy 6.648279 -339.917878) (xy 6.61978 -339.951602) (xy 6.597539 -339.989743)
			(xy 6.582226 -340.031155) (xy 6.5743 -340.07459) (xy 6.574002 -340.118742) (xy 6.581339 -340.16228)
			(xy 6.596091 -340.203895) (xy 6.60654 -340.223348) (xy 6.634361 -340.273515) (xy 6.683657 -340.37711)
			(xy 6.725485 -340.483938) (xy 6.759635 -340.593463) (xy 6.785936 -340.705132) (xy 6.804254 -340.818386)
			(xy 6.814498 -340.932653) (xy 6.816617 -341.047359) (xy 6.810598 -341.161926) (xy 6.796474 -341.275779)
			(xy 6.774314 -341.388343) (xy 6.744231 -341.499054) (xy 6.706375 -341.607354) (xy 6.660938 -341.712698)
			(xy 6.634988 -341.763858) (xy 6.625193 -341.783747) (xy 6.611932 -341.826049) (xy 6.606207 -341.87001)
			(xy 6.608191 -341.914297) (xy 6.617823 -341.95757) (xy 6.634812 -341.998517) (xy 6.658643 -342.035899)
			(xy 6.688594 -342.068583) (xy 6.723758 -342.095579) (xy 6.743192 -342.10625) (xy 6.774485 -342.123119)
			(xy 6.833489 -342.162778) (xy 6.887697 -342.208775) (xy 6.936433 -342.260536) (xy 6.979086 -342.317413)
			(xy 7.015123 -342.378696) (xy 7.044095 -342.443618) (xy 7.065639 -342.511368) (xy 7.079486 -342.5811)
			(xy 7.085463 -342.651942) (xy 7.083495 -342.723008) (xy 7.073607 -342.793411) (xy 7.055922 -342.86227)
			(xy 7.030662 -342.928724) (xy 6.998141 -342.991944) (xy 6.958768 -343.051138) (xy 6.913032 -343.105568)
			(xy 6.861507 -343.154552) (xy 6.804837 -343.197479) (xy 6.743729 -343.233812) (xy 6.678947 -343.263097)
			(xy 6.611301 -343.284967) (xy 6.541637 -343.299151) (xy 6.470825 -343.305469) (xy 6.39975 -343.303844)
			(xy 6.3293 -343.294296) (xy 6.260357 -343.276943) (xy 6.193781 -343.252004) (xy 6.130406 -343.219789)
			(xy 6.071022 -343.180701) (xy 6.016373 -343.135229) (xy 5.96714 -343.083941) (xy 5.92394 -343.027478)
			(xy 5.887313 -342.966546) (xy 5.857716 -342.901906) (xy 5.835519 -342.834367) (xy 5.827776 -342.79967)
			(xy 5.822798 -342.778068) (xy 5.806347 -342.736906) (xy 5.783004 -342.699222) (xy 5.753478 -342.66616)
			(xy 5.718664 -342.63872) (xy 5.679617 -342.617737) (xy 5.637523 -342.603845) (xy 5.593656 -342.597466)
			(xy 5.549349 -342.598794) (xy 5.527548 -342.60282) (xy 5.473606 -342.613548) (xy 5.364635 -342.628518)
			(xy 5.254898 -342.636041) (xy 5.144904 -342.636082) (xy 5.035162 -342.628641) (xy 4.92618 -342.613752)
			(xy 4.872228 -342.603074) (xy 4.850439 -342.599028) (xy 4.806148 -342.597667) (xy 4.762293 -342.604013)
			(xy 4.720204 -342.617873) (xy 4.681159 -342.638827) (xy 4.646344 -342.666239) (xy 4.616813 -342.699278)
			(xy 4.593465 -342.736939) (xy 4.577006 -342.778082) (xy 4.572 -342.79967) (xy 4.564252 -342.834367)
			(xy 4.542053 -342.90191) (xy 4.512454 -342.966552) (xy 4.475825 -343.027487) (xy 4.432624 -343.083953)
			(xy 4.38339 -343.135245) (xy 4.328739 -343.18072) (xy 4.269354 -343.219812) (xy 4.205977 -343.252031)
			(xy 4.139399 -343.276976) (xy 4.070454 -343.294333) (xy 4.000002 -343.303887) (xy 3.928924 -343.305517)
			(xy 3.858108 -343.299204) (xy 3.788439 -343.285026) (xy 3.720787 -343.263161) (xy 3.655999 -343.233882)
			(xy 3.594884 -343.197555) (xy 3.538206 -343.154633) (xy 3.486672 -343.105653) (xy 3.440927 -343.051227)
			(xy 3.401542 -342.992036) (xy 3.36901 -342.928818) (xy 3.343738 -342.862365) (xy 3.32604 -342.793506)
			(xy 3.316139 -342.723102) (xy 3.314157 -342.652033) (xy 3.32012 -342.581187) (xy 3.333954 -342.511448)
			(xy 3.355484 -342.44369) (xy 3.384443 -342.378758) (xy 3.420469 -342.317464) (xy 3.46311 -342.260574)
			(xy 3.511835 -342.208799) (xy 3.566034 -342.162786) (xy 3.62503 -342.12311) (xy 3.65633 -342.10625)
			(xy 3.675751 -342.095588) (xy 3.710895 -342.068619) (xy 3.740831 -342.035964) (xy 3.764651 -341.998614)
			(xy 3.781635 -341.957699) (xy 3.791266 -341.914459) (xy 3.793255 -341.870204) (xy 3.78754 -341.826274)
			(xy 3.774295 -341.784001) (xy 3.764534 -341.764112) (xy 3.739522 -341.714851) (xy 3.695492 -341.613513)
			(xy 3.658484 -341.509405) (xy 3.628672 -341.403013) (xy 3.606195 -341.294833) (xy 3.591158 -341.185371)
			(xy 3.583631 -341.075137) (xy 3.583178 -341.019892) (xy 3.583649 -340.964176) (xy 3.591313 -340.853007)
			(xy 3.606616 -340.74263) (xy 3.629486 -340.633569) (xy 3.659813 -340.526342) (xy 3.697453 -340.421459)
			(xy 3.742229 -340.319418) (xy 3.793926 -340.220703) (xy 3.8523 -340.125784) (xy 3.917073 -340.03511)
			(xy 3.987938 -339.949114) (xy 4.064558 -339.868202) (xy 4.146569 -339.792761) (xy 4.233582 -339.723147)
			(xy 4.325183 -339.659692) (xy 4.420937 -339.602697) (xy 4.520389 -339.552432) (xy 4.623067 -339.509138)
			(xy 4.728483 -339.473018) (xy 4.836137 -339.444245) (xy 4.945517 -339.422955) (xy 5.000752 -339.415628)
			(xy 5.022357 -339.412477) (xy 5.064119 -339.399756) (xy 5.103095 -339.380088) (xy 5.138137 -339.35405)
			(xy 5.168217 -339.322408) (xy 5.192448 -339.286093) (xy 5.21012 -339.246172) (xy 5.220712 -339.20382)
			(xy 5.223913 -339.16028) (xy 5.219629 -339.116834) (xy 5.207986 -339.074758) (xy 5.189325 -339.035289)
			(xy 5.164197 -338.999589) (xy 5.149088 -338.983828) (xy 4.963922 -338.798662) (xy 4.947218 -338.782653)
			(xy 4.90913 -338.756393) (xy 4.866917 -338.737461) (xy 4.821975 -338.726483) (xy 4.775789 -338.723821)
			(xy 4.729883 -338.729564) (xy 4.685776 -338.743522) (xy 4.644923 -338.765233) (xy 4.608675 -338.79398)
			(xy 4.57823 -338.828814) (xy 4.554593 -338.868583) (xy 4.546092 -338.890102) (xy 4.533427 -338.923013)
			(xy 4.501813 -338.986052) (xy 4.463416 -339.045204) (xy 4.418706 -339.099742) (xy 4.368235 -339.148996)
			(xy 4.312621 -339.19236) (xy 4.252549 -339.229301) (xy 4.188757 -339.259366) (xy 4.122029 -339.282184)
			(xy 4.053185 -339.297476) (xy 3.983071 -339.305053) (xy 3.91255 -339.304822) (xy 3.842487 -339.296786)
			(xy 3.773745 -339.281044) (xy 3.707168 -339.257789) (xy 3.643574 -339.227307) (xy 3.583745 -339.189973)
			(xy 3.528416 -339.146246) (xy 3.478268 -339.096663) (xy 3.433917 -339.041833) (xy 3.395908 -338.982431)
			(xy 3.364708 -338.919186) (xy 3.3407 -338.852877) (xy 3.324181 -338.784317) (xy 3.315352 -338.71435)
			(xy 3.314322 -338.643836) (xy 3.321104 -338.573641) (xy 3.335615 -338.504628) (xy 3.357676 -338.437646)
			(xy 3.387017 -338.373517) (xy 3.423275 -338.313031) (xy 3.466007 -338.256929) (xy 3.514686 -338.205903)
			(xy 3.568714 -338.160579) (xy 3.627427 -338.121514) (xy 3.690104 -338.089188) (xy 3.755974 -338.064)
			(xy 3.824227 -338.046257) (xy 3.894025 -338.036179) (xy 3.96451 -338.033889) (xy 4.034815 -338.039416)
			(xy 4.104076 -338.052691) (xy 4.171442 -338.073551) (xy 4.203954 -338.087208) (xy 4.225125 -338.095934)
			(xy 4.269689 -338.106444) (xy 4.315416 -338.108792) (xy 4.360822 -338.102902) (xy 4.404437 -338.088965)
			(xy 4.444845 -338.067434) (xy 4.480738 -338.039006) (xy 4.510951 -338.004602) (xy 4.534505 -337.965338)
			(xy 4.550637 -337.922487) (xy 4.558823 -337.877438) (xy 4.5593 -337.854544) (xy 4.5593 -337.485228)
			(xy 4.558817 -337.462347) (xy 4.550575 -337.417331) (xy 4.534407 -337.374519) (xy 4.510835 -337.335293)
			(xy 4.480622 -337.300922) (xy 4.444742 -337.272515) (xy 4.404356 -337.25099) (xy 4.360769 -337.237045)
			(xy 4.31539 -337.231128) (xy 4.269684 -337.233432) (xy 4.22513 -337.243881) (xy 4.203954 -337.252564)
			(xy 4.171697 -337.266101) (xy 4.10488 -337.286829) (xy 4.03619 -337.300093) (xy 3.966459 -337.305734)
			(xy 3.896531 -337.303682) (xy 3.827251 -337.293963) (xy 3.759457 -337.276695) (xy 3.69397 -337.252085)
			(xy 3.631581 -337.220433) (xy 3.573046 -337.18212) (xy 3.519073 -337.137611) (xy 3.470314 -337.087443)
			(xy 3.42736 -337.032224) (xy 3.39073 -336.972622) (xy 3.360867 -336.909358) (xy 3.338132 -336.843196)
			(xy 3.322801 -336.774938) (xy 3.315059 -336.705409) (xy 3.314999 -336.635451) (xy 3.322623 -336.565909)
			(xy 3.337838 -336.497625) (xy 3.36046 -336.431425) (xy 3.390216 -336.36811) (xy 3.426744 -336.308445)
			(xy 3.447796 -336.280506) (xy 3.47726 -336.242406) (xy 3.471418 -336.147156) (xy 2.999486 -335.675224)
			(xy 2.983052 -335.659511) (xy 2.9457 -335.633597) (xy 2.904332 -335.614743) (xy 2.86027 -335.60355)
			(xy 2.814919 -335.600376) (xy 2.769727 -335.605322) (xy 2.726137 -335.618231) (xy 2.685539 -335.63869)
			(xy 2.649229 -335.666046) (xy 2.618367 -335.699427) (xy 2.593936 -335.737767) (xy 2.576718 -335.779841)
			(xy 2.571496 -335.80197) (xy 2.563681 -335.836432) (xy 2.541413 -335.903498) (xy 2.511841 -335.96768)
			(xy 2.47533 -336.028185) (xy 2.432332 -336.084265) (xy 2.383377 -336.135228) (xy 2.32907 -336.180444)
			(xy 2.270081 -336.219356) (xy 2.207139 -336.251482) (xy 2.141021 -336.276427) (xy 2.072544 -336.293881)
			(xy 2.002553 -336.30363) (xy 1.931912 -336.305553) (xy 1.861494 -336.299626) (xy 1.792169 -336.285923)
			(xy 1.724792 -336.264613) (xy 1.660195 -336.235958) (xy 1.599177 -336.200313) (xy 1.54249 -336.158118)
			(xy 1.490835 -336.109894) (xy 1.44485 -336.056236) (xy 1.405102 -335.997807) (xy 1.372082 -335.935329)
			(xy 1.346199 -335.869573) (xy 1.327771 -335.801352) (xy 1.317026 -335.731506) (xy 1.314097 -335.6609)
			(xy 1.319021 -335.590405) (xy 1.331735 -335.520891) (xy 1.352084 -335.453218) (xy 1.379816 -335.38822)
			(xy 1.414588 -335.3267) (xy 1.455972 -335.269418) (xy 1.503455 -335.217081) (xy 1.556453 -335.170337)
			(xy 1.614309 -335.12976) (xy 1.676311 -335.095854) (xy 1.741691 -335.069037) (xy 1.809644 -335.049639)
			(xy 1.879329 -335.037901) (xy 1.949886 -335.033967) (xy 2.020444 -335.037886) (xy 2.055368 -335.043272)
			(xy 2.077234 -335.046472) (xy 2.121421 -335.046168) (xy 2.164888 -335.038223) (xy 2.206326 -335.022877)
			(xy 2.244484 -335.000594) (xy 2.278211 -334.972045) (xy 2.30649 -334.938091) (xy 2.328468 -334.899757)
			(xy 2.343482 -334.858198) (xy 2.35108 -334.814668) (xy 2.351532 -334.792574) (xy 2.351532 -333.398876)
			(xy 1.632204 -332.679548) (xy 1.632204 -332.289404) (xy 1.63177 -332.274344) (xy 1.62472 -332.245061)
			(xy 1.610991 -332.218253) (xy 1.59135 -332.195419) (xy 1.579372 -332.18628) (xy 1.55034 -332.164819)
			(xy 1.496833 -332.116346) (xy 1.449165 -332.062121) (xy 1.40795 -332.002843) (xy 1.373719 -331.939275)
			(xy 1.346912 -331.872237) (xy 1.327877 -331.802594) (xy 1.316857 -331.731241) (xy 1.313995 -331.659099)
			(xy 1.319328 -331.587098) (xy 1.332787 -331.516165) (xy 1.354198 -331.447215) (xy 1.383286 -331.381135)
			(xy 1.419676 -331.318778) (xy 1.462899 -331.260947) (xy 1.512398 -331.208388) (xy 1.567534 -331.161777)
			(xy 1.627599 -331.121716) (xy 1.691816 -331.08872) (xy 1.75936 -331.063215) (xy 1.829358 -331.045529)
			(xy 1.900911 -331.035891) (xy 1.973094 -331.034425) (xy 2.044979 -331.041149) (xy 2.115638 -331.055976)
			(xy 2.184162 -331.078717) (xy 2.249667 -331.109078) (xy 2.311308 -331.146666) (xy 2.368293 -331.190999)
			(xy 2.419885 -331.241505) (xy 2.465421 -331.297533) (xy 2.504314 -331.35836) (xy 2.536062 -331.423204)
			(xy 2.548636 -331.457046) (xy 2.548636 -331.4573) (xy 2.554391 -331.471804) (xy 2.571769 -331.497707)
			(xy 2.594904 -331.518628) (xy 2.622419 -331.53332) (xy 2.652674 -331.540909) (xy 2.66827 -331.541374)
			(xy 2.668524 -331.541374) (xy 2.685182 -331.540926) (xy 2.717361 -331.532297) (xy 2.746211 -331.515633)
			(xy 2.769764 -331.492071) (xy 2.786416 -331.463215) (xy 2.795033 -331.431032) (xy 2.795524 -331.414374)
			(xy 2.795524 -331.375004) (xy 3.287268 -330.883006) (xy 3.297598 -330.872052) (xy 3.31328 -330.846358)
			(xy 3.32252 -330.81771) (xy 3.324808 -330.787696) (xy 3.322828 -330.77277) (xy 3.317227 -330.735094)
			(xy 3.313961 -330.658992) (xy 3.31981 -330.583045) (xy 3.33469 -330.50834) (xy 3.358389 -330.435949)
			(xy 3.390567 -330.366907) (xy 3.430763 -330.302204) (xy 3.454146 -330.272136) (xy 3.46376 -330.259506)
			(xy 3.476878 -330.230607) (xy 3.482447 -330.199363) (xy 3.480122 -330.167711) (xy 3.470047 -330.137616)
			(xy 3.452846 -330.110945) (xy 3.429588 -330.089352) (xy 3.401714 -330.074177) (xy 3.370955 -330.066361)
			(xy 3.355086 -330.065888) (xy 3.267202 -330.065888) (xy 3.226562 -330.024994) (xy 3.214407 -330.013491)
			(xy 3.185443 -329.996749) (xy 3.15312 -329.988121) (xy 3.136392 -329.987656) (xy 2.569464 -329.987656)
			(xy 2.554404 -329.988079) (xy 2.525121 -329.995135) (xy 2.498314 -330.008868) (xy 2.475479 -330.02851)
			(xy 2.46634 -330.040488) (xy 2.445192 -330.06911) (xy 2.3975 -330.121934) (xy 2.344206 -330.1691)
			(xy 2.285977 -330.210016) (xy 2.223541 -330.244172) (xy 2.15768 -330.271139) (xy 2.089219 -330.290579)
			(xy 2.019015 -330.30225) (xy 1.947946 -330.306005) (xy 1.876903 -330.301797) (xy 1.806775 -330.289679)
			(xy 1.738439 -330.269802) (xy 1.672751 -330.242416) (xy 1.610535 -330.207863) (xy 1.552567 -330.166576)
			(xy 1.499575 -330.119071) (xy 1.452221 -330.065944) (xy 1.411099 -330.00786) (xy 1.376724 -329.945545)
			(xy 1.349524 -329.87978) (xy 1.329842 -329.811388) (xy 1.317924 -329.741225) (xy 1.313918 -329.67017)
			(xy 1.317875 -329.599112) (xy 1.329745 -329.528942) (xy 1.349381 -329.460536) (xy 1.376535 -329.394752)
			(xy 1.410868 -329.332414) (xy 1.45195 -329.274301) (xy 1.499267 -329.221142) (xy 1.552227 -329.173601)
			(xy 1.610166 -329.132274) (xy 1.672359 -329.097678) (xy 1.738028 -329.070247) (xy 1.80635 -329.050323)
			(xy 1.87647 -329.038157) (xy 1.94751 -329.033901) (xy 2.018581 -329.037607) (xy 2.088794 -329.049229)
			(xy 2.157268 -329.068623) (xy 2.223147 -329.095545) (xy 2.285607 -329.129657) (xy 2.343864 -329.170534)
			(xy 2.39719 -329.217663) (xy 2.444918 -329.270455) (xy 2.466086 -329.299062) (xy 2.48412 -329.324208)
			(xy 2.538476 -329.352148) (xy 2.56921 -329.352148) (xy 2.592274 -329.351678) (xy 2.637655 -329.343424)
			(xy 2.680803 -329.327117) (xy 2.720299 -329.303291) (xy 2.754848 -329.27273) (xy 2.783315 -329.236436)
			(xy 2.804766 -329.195602) (xy 2.818496 -329.151566) (xy 2.824054 -329.105776) (xy 2.821259 -329.059735)
			(xy 2.810201 -329.014954) (xy 2.791245 -328.972903) (xy 2.765011 -328.934964) (xy 2.749042 -328.918316)
			(xy 2.163064 -328.332592) (xy 2.152104 -328.322269) (xy 2.126412 -328.306586) (xy 2.097766 -328.297343)
			(xy 2.067753 -328.295053) (xy 2.052828 -328.297032) (xy 2.017637 -328.302304) (xy 1.946567 -328.305906)
			(xy 1.87554 -328.301546) (xy 1.805445 -328.289279) (xy 1.737158 -328.269258) (xy 1.671536 -328.241734)
			(xy 1.609399 -328.207051) (xy 1.551526 -328.165644) (xy 1.49864 -328.118032) (xy 1.451405 -328.064809)
			(xy 1.410411 -328.006642) (xy 1.376171 -327.94426) (xy 1.349114 -327.878444) (xy 1.329579 -327.810017)
			(xy 1.317811 -327.739836) (xy 1.313956 -327.66878) (xy 1.318063 -327.597738) (xy 1.330081 -327.527599)
			(xy 1.349859 -327.459242) (xy 1.377149 -327.393522) (xy 1.411611 -327.331262) (xy 1.452811 -327.273242)
			(xy 1.500236 -327.220187) (xy 1.55329 -327.172763) (xy 1.61131 -327.131562) (xy 1.67357 -327.0971)
			(xy 1.73929 -327.06981) (xy 1.807647 -327.050032) (xy 1.877785 -327.038014) (xy 1.948828 -327.033906)
			(xy 2.019884 -327.037761) (xy 2.090065 -327.049529) (xy 2.158492 -327.069063) (xy 2.224308 -327.09612)
			(xy 2.28669 -327.130359) (xy 2.344857 -327.171353) (xy 2.39808 -327.218589) (xy 2.445693 -327.271474)
			(xy 2.4871 -327.329347) (xy 2.521783 -327.391484) (xy 2.549307 -327.457106) (xy 2.569328 -327.525392)
			(xy 2.581596 -327.595488) (xy 2.585956 -327.666515) (xy 2.582354 -327.737585) (xy 2.577084 -327.772776)
			(xy 2.575055 -327.787705) (xy 2.577284 -327.817741) (xy 2.586531 -327.846406) (xy 2.602273 -327.872084)
			(xy 2.612644 -327.883012) (xy 3.05308 -328.323448) (xy 3.068915 -328.338571) (xy 3.104737 -328.363742)
			(xy 3.144343 -328.382401) (xy 3.186562 -328.393996) (xy 3.230143 -328.398183) (xy 3.273796 -328.394838)
			(xy 3.31623 -328.384061) (xy 3.35619 -328.366171) (xy 3.392491 -328.341696) (xy 3.424061 -328.311361)
			(xy 3.437382 -328.293984) (xy 3.458494 -328.265992) (xy 3.505928 -328.214355) (xy 3.558757 -328.168252)
			(xy 3.616338 -328.128244) (xy 3.677973 -328.094815) (xy 3.742912 -328.068373) (xy 3.810367 -328.049238)
			(xy 3.879518 -328.037643) (xy 3.949525 -328.033729) (xy 4.019537 -328.037543) (xy 4.088705 -328.049039)
			(xy 4.156187 -328.068077) (xy 4.221164 -328.094427) (xy 4.282847 -328.127767) (xy 4.340485 -328.167693)
			(xy 4.39338 -328.21372) (xy 4.440887 -328.265289) (xy 4.482431 -328.321773) (xy 4.500372 -328.351896)
			(xy 4.544822 -328.351896) (xy 4.83997 -328.647044) (xy 4.852123 -328.6584) (xy 4.880931 -328.674998)
			(xy 4.913051 -328.683585) (xy 4.946299 -328.683579) (xy 4.978415 -328.674979) (xy 5.007217 -328.658369)
			(xy 5.030747 -328.63488) (xy 5.047405 -328.606106) (xy 5.05606 -328.574005) (xy 5.056632 -328.557382)
			(xy 5.056632 -328.226166) (xy 4.16306 -327.332594) (xy 4.152101 -327.322269) (xy 4.126409 -327.306586)
			(xy 4.097763 -327.297343) (xy 4.067749 -327.295054) (xy 4.052824 -327.297034) (xy 4.017633 -327.30231)
			(xy 3.946563 -327.305912) (xy 3.875535 -327.301553) (xy 3.805438 -327.289286) (xy 3.737151 -327.269265)
			(xy 3.671528 -327.241741) (xy 3.60939 -327.207059) (xy 3.551515 -327.165652) (xy 3.498629 -327.118039)
			(xy 3.451393 -327.064816) (xy 3.410397 -327.006649) (xy 3.376157 -326.944267) (xy 3.349099 -326.87845)
			(xy 3.329564 -326.810022) (xy 3.317795 -326.73984) (xy 3.31394 -326.668783) (xy 3.318047 -326.59774)
			(xy 3.330064 -326.527601) (xy 3.349842 -326.459243) (xy 3.377133 -326.393522) (xy 3.411594 -326.331261)
			(xy 3.452795 -326.27324) (xy 3.50022 -326.220185) (xy 3.553275 -326.172759) (xy 3.611295 -326.131558)
			(xy 3.673556 -326.097096) (xy 3.739276 -326.069804) (xy 3.807634 -326.050026) (xy 3.877773 -326.038007)
			(xy 3.948816 -326.0339) (xy 4.019873 -326.037754) (xy 4.090055 -326.049522) (xy 4.158483 -326.069057)
			(xy 4.2243 -326.096114) (xy 4.286683 -326.130354) (xy 4.344851 -326.171348) (xy 4.398074 -326.218584)
			(xy 4.445688 -326.27147) (xy 4.487095 -326.329344) (xy 4.521778 -326.391481) (xy 4.549303 -326.457104)
			(xy 4.569324 -326.525392) (xy 4.581592 -326.595488) (xy 4.585952 -326.666516) (xy 4.58235 -326.737586)
			(xy 4.57708 -326.772778) (xy 4.575051 -326.787707) (xy 4.57728 -326.817743) (xy 4.586527 -326.846408)
			(xy 4.60227 -326.872085) (xy 4.61264 -326.883014) (xy 5.557012 -327.827386) (xy 5.569183 -327.838739)
			(xy 5.598022 -327.855328) (xy 5.630166 -327.863913) (xy 5.663436 -327.863913) (xy 5.69558 -327.855328)
			(xy 5.724419 -327.838739) (xy 5.73659 -327.827386) (xy 6.211824 -327.352152) (xy 7.830312 -327.352152)
			(xy 7.845406 -327.351773) (xy 7.874761 -327.34474) (xy 7.901638 -327.331) (xy 7.92453 -327.311323)
			(xy 7.93369 -327.29932) (xy 7.954841 -327.270747) (xy 8.002519 -327.218012) (xy 8.055784 -327.170928)
			(xy 8.113973 -327.130084) (xy 8.176356 -327.095989) (xy 8.242156 -327.069071) (xy 8.310548 -327.049665)
			(xy 8.38068 -327.038014) (xy 8.451673 -327.034264) (xy 8.522642 -327.038461) (xy 8.592698 -327.050554)
			(xy 8.660967 -327.07039) (xy 8.726596 -327.097722) (xy 8.788763 -327.132209) (xy 8.846693 -327.173419)
			(xy 8.899661 -327.220838) (xy 8.947006 -327.273872) (xy 8.988135 -327.33186) (xy 9.022534 -327.394075)
			(xy 9.049775 -327.459742) (xy 9.069516 -327.528039) (xy 9.08151 -327.598112) (xy 9.085608 -327.669086)
			(xy 9.081759 -327.740075) (xy 9.07001 -327.81019) (xy 9.050508 -327.878555) (xy 9.023498 -327.944317)
			(xy 9.00684 -327.975722) (xy 8.996627 -327.995158) (xy 8.982456 -328.036714) (xy 8.975635 -328.080087)
			(xy 8.976369 -328.123986) (xy 8.984634 -328.167107) (xy 9.000185 -328.208166) (xy 9.02256 -328.245942)
			(xy 9.051093 -328.279313) (xy 9.084935 -328.307284) (xy 9.12308 -328.329025) (xy 9.164393 -328.343889)
			(xy 9.207645 -328.351433) (xy 9.229598 -328.351896) (xy 11.369548 -328.351896) (xy 13.546836 -330.529438)
			(xy 13.563534 -330.545342) (xy 13.601471 -330.571543) (xy 13.643512 -330.590473) (xy 13.688277 -330.601511)
			(xy 13.734299 -330.604296) (xy 13.780068 -330.598735) (xy 13.824084 -330.585011) (xy 13.864904 -330.563574)
			(xy 13.901188 -330.535128) (xy 13.931748 -330.500604) (xy 13.95558 -330.461135) (xy 13.971904 -330.418016)
			(xy 13.980184 -330.372659) (xy 13.980668 -330.349606) (xy 13.980668 -322.022978) (xy 13.980161 -322.006359)
			(xy 13.97155 -321.974254) (xy 13.954942 -321.945461) (xy 13.943584 -321.933316) (xy 8.99795 -316.987936)
			(xy 7.069328 -316.987936) (xy 7.054233 -316.988307) (xy 7.024875 -316.995337) (xy 6.997996 -317.009079)
			(xy 6.975107 -317.028761) (xy 6.96595 -317.040768) (xy 6.944789 -317.069375) (xy 6.897072 -317.122164)
			(xy 6.843758 -317.169293) (xy 6.785512 -317.210172) (xy 6.723065 -317.244288) (xy 6.657198 -317.271216)
			(xy 6.588735 -317.290617) (xy 6.518534 -317.30225) (xy 6.447472 -317.305968) (xy 6.37644 -317.301726)
			(xy 6.306326 -317.289575) (xy 6.238008 -317.269668) (xy 6.172342 -317.242255) (xy 6.110148 -317.207679)
			(xy 6.052206 -317.166371) (xy 5.999241 -317.11885) (xy 5.951916 -317.06571) (xy 5.910822 -317.007616)
			(xy 5.876475 -316.945295) (xy 5.849304 -316.879528) (xy 5.82965 -316.811137) (xy 5.817758 -316.740979)
			(xy 5.813777 -316.669932) (xy 5.817758 -316.598884) (xy 5.829649 -316.528726) (xy 5.849303 -316.460335)
			(xy 5.876474 -316.394568) (xy 5.91082 -316.332247) (xy 5.951914 -316.274153) (xy 5.999239 -316.221012)
			(xy 6.052204 -316.173491) (xy 6.110146 -316.132183) (xy 6.172339 -316.097606) (xy 6.238005 -316.070193)
			(xy 6.306323 -316.050286) (xy 6.376437 -316.038135) (xy 6.447469 -316.033892) (xy 6.518531 -316.037609)
			(xy 6.588732 -316.049242) (xy 6.657195 -316.068643) (xy 6.723062 -316.09557) (xy 6.78551 -316.129687)
			(xy 6.843755 -316.170565) (xy 6.89707 -316.217694) (xy 6.944787 -316.270483) (xy 6.96595 -316.299088)
			(xy 6.975114 -316.311085) (xy 6.998011 -316.330748) (xy 7.024887 -316.344482) (xy 7.054237 -316.351518)
			(xy 7.069328 -316.35192) (xy 7.670038 -316.35192) (xy 7.691989 -316.35144) (xy 7.73524 -316.343905)
			(xy 7.776552 -316.329049) (xy 7.814696 -316.307313) (xy 7.848536 -316.279345) (xy 7.877066 -316.245977)
			(xy 7.899436 -316.208202) (xy 7.914982 -316.167144) (xy 7.923239 -316.124026) (xy 7.923962 -316.08013)
			(xy 7.91713 -316.036762) (xy 7.902946 -315.995215) (xy 7.892796 -315.975746) (xy 7.876159 -315.944427)
			(xy 7.849163 -315.878847) (xy 7.829636 -315.810668) (xy 7.817822 -315.740739) (xy 7.813868 -315.66993)
			(xy 7.817822 -315.599121) (xy 7.829636 -315.529192) (xy 7.849163 -315.461013) (xy 7.876159 -315.395433)
			(xy 7.892796 -315.364114) (xy 7.902933 -315.344641) (xy 7.917105 -315.303094) (xy 7.923927 -315.25973)
			(xy 7.923197 -315.215838) (xy 7.914937 -315.172725) (xy 7.899392 -315.131672) (xy 7.877026 -315.0939)
			(xy 7.848502 -315.060533) (xy 7.814669 -315.032563) (xy 7.776534 -315.010821) (xy 7.73523 -314.995955)
			(xy 7.691987 -314.988406) (xy 7.670038 -314.98794) (xy 7.069328 -314.98794) (xy 7.054267 -314.988344)
			(xy 7.024984 -314.995407) (xy 6.998177 -315.009146) (xy 6.975343 -315.028793) (xy 6.966204 -315.040772)
			(xy 6.944615 -315.069959) (xy 6.895839 -315.123731) (xy 6.841253 -315.171596) (xy 6.781568 -315.212929)
			(xy 6.717563 -315.247191) (xy 6.65007 -315.273938) (xy 6.579969 -315.29282) (xy 6.508173 -315.303591)
			(xy 6.435618 -315.306111) (xy 6.363248 -315.300348) (xy 6.292006 -315.286375) (xy 6.22282 -315.264376)
			(xy 6.156591 -315.234637) (xy 6.094183 -315.197545) (xy 6.036407 -315.153584) (xy 5.984017 -315.103325)
			(xy 5.937695 -315.047424) (xy 5.898044 -314.986609) (xy 5.865581 -314.921672) (xy 5.840729 -314.853459)
			(xy 5.823811 -314.782859) (xy 5.815048 -314.71079) (xy 5.814554 -314.638193) (xy 5.822335 -314.566012)
			(xy 5.829808 -314.530486) (xy 5.834384 -314.508173) (xy 5.836255 -314.462665) (xy 5.829989 -314.417551)
			(xy 5.815787 -314.374275) (xy 5.794102 -314.334222) (xy 5.76563 -314.298672) (xy 5.73128 -314.268762)
			(xy 5.692151 -314.24545) (xy 5.649495 -314.229482) (xy 5.604677 -314.221367) (xy 5.581904 -314.22086)
			(xy 4.817872 -314.22086) (xy 4.795099 -314.221365) (xy 4.75028 -314.229466) (xy 4.707623 -314.245426)
			(xy 4.668493 -314.268734) (xy 4.634145 -314.298643) (xy 4.605678 -314.334197) (xy 4.584005 -314.374255)
			(xy 4.569819 -314.417534) (xy 4.563576 -314.46265) (xy 4.565474 -314.508155) (xy 4.569968 -314.530486)
			(xy 4.577295 -314.565325) (xy 4.585056 -314.636097) (xy 4.584858 -314.707293) (xy 4.576704 -314.77802)
			(xy 4.560697 -314.847393) (xy 4.537035 -314.914542) (xy 4.506018 -314.978626) (xy 4.468032 -315.038842)
			(xy 4.423553 -315.094435) (xy 4.37314 -315.144708) (xy 4.317424 -315.189032) (xy 4.257103 -315.22685)
			(xy 4.192934 -315.25769) (xy 4.125719 -315.281165) (xy 4.056302 -315.29698) (xy 3.985552 -315.304937)
			(xy 3.914356 -315.304937) (xy 3.843606 -315.29698) (xy 3.774189 -315.281165) (xy 3.706974 -315.25769)
			(xy 3.642805 -315.22685) (xy 3.582484 -315.189032) (xy 3.526768 -315.144708) (xy 3.476355 -315.094435)
			(xy 3.431876 -315.038842) (xy 3.39389 -314.978626) (xy 3.362873 -314.914542) (xy 3.339211 -314.847393)
			(xy 3.323204 -314.77802) (xy 3.31505 -314.707293) (xy 3.314852 -314.636097) (xy 3.322613 -314.565325)
			(xy 3.32994 -314.530486) (xy 3.334484 -314.508168) (xy 3.336355 -314.462664) (xy 3.330089 -314.417554)
			(xy 3.315889 -314.374282) (xy 3.294208 -314.334231) (xy 3.26574 -314.298682) (xy 3.231395 -314.268773)
			(xy 3.192271 -314.24546) (xy 3.149621 -314.229489) (xy 3.104807 -314.22137) (xy 3.082036 -314.22086)
			(xy 2.268474 -314.22086) (xy 2.241042 -314.23483) (xy 2.209317 -314.25063) (xy 2.143093 -314.275884)
			(xy 2.074469 -314.293612) (xy 2.0043 -314.303594) (xy 1.933455 -314.305706) (xy 1.862815 -314.299922)
			(xy 1.793258 -314.286313) (xy 1.725646 -314.265049) (xy 1.660821 -314.236393) (xy 1.599588 -314.200702)
			(xy 1.542705 -314.158419) (xy 1.490882 -314.110069) (xy 1.44476 -314.056252) (xy 1.404913 -313.997637)
			(xy 1.371836 -313.934953) (xy 1.345939 -313.868977) (xy 1.327545 -313.800529) (xy 1.316882 -313.73046)
			(xy 1.314081 -313.659639) (xy 1.319179 -313.588946) (xy 1.332111 -313.51926) (xy 1.352718 -313.451445)
			(xy 1.380742 -313.386345) (xy 1.415837 -313.324767) (xy 1.457565 -313.267477) (xy 1.50541 -313.215186)
			(xy 1.558775 -313.168543) (xy 1.617 -313.128129) (xy 1.67936 -313.094444) (xy 1.745081 -313.067908)
			(xy 1.813347 -313.048849) (xy 1.88331 -313.037505) (xy 1.9541 -313.034017) (xy 2.024839 -313.038428)
			(xy 2.094648 -313.050682) (xy 2.162659 -313.070629) (xy 2.228029 -313.098019) (xy 2.289945 -313.132514)
			(xy 2.347638 -313.173684) (xy 2.400391 -313.221018) (xy 2.44755 -313.273928) (xy 2.488529 -313.331757)
			(xy 2.522818 -313.393787) (xy 2.549991 -313.459247) (xy 2.56032 -313.49315) (xy 2.56032 -313.493404)
			(xy 2.565331 -313.508999) (xy 2.582213 -313.537061) (xy 2.605682 -313.559902) (xy 2.634193 -313.576016)
			(xy 2.665865 -313.584342) (xy 2.68224 -313.584844) (xy 4.108958 -313.584844) (xy 4.125579 -313.584276)
			(xy 4.157677 -313.575614) (xy 4.186445 -313.558952) (xy 4.20993 -313.535422) (xy 4.226537 -313.506622)
			(xy 4.235138 -313.474508) (xy 4.235147 -313.441263) (xy 4.226565 -313.409144) (xy 4.209974 -313.380335)
			(xy 4.19862 -313.368182) (xy 4.16306 -313.332622) (xy 4.152111 -313.322287) (xy 4.126414 -313.30661)
			(xy 4.097765 -313.297371) (xy 4.06775 -313.295083) (xy 4.052824 -313.297062) (xy 4.017633 -313.302339)
			(xy 3.946563 -313.305942) (xy 3.875535 -313.301583) (xy 3.805439 -313.289316) (xy 3.737152 -313.269295)
			(xy 3.671528 -313.241771) (xy 3.60939 -313.207089) (xy 3.551516 -313.165682) (xy 3.49863 -313.118069)
			(xy 3.451393 -313.064846) (xy 3.410398 -313.00668) (xy 3.376157 -312.944297) (xy 3.3491 -312.87848)
			(xy 3.329564 -312.810053) (xy 3.317795 -312.739871) (xy 3.31394 -312.668814) (xy 3.318047 -312.597771)
			(xy 3.330064 -312.527632) (xy 3.349842 -312.459274) (xy 3.377132 -312.393553) (xy 3.411594 -312.331292)
			(xy 3.452795 -312.273271) (xy 3.500219 -312.220216) (xy 3.553274 -312.17279) (xy 3.611294 -312.131589)
			(xy 3.673555 -312.097126) (xy 3.739275 -312.069835) (xy 3.807633 -312.050056) (xy 3.877772 -312.038038)
			(xy 3.948815 -312.03393) (xy 4.019872 -312.037784) (xy 4.090054 -312.049552) (xy 4.158482 -312.069087)
			(xy 4.224299 -312.096143) (xy 4.286682 -312.130383) (xy 4.344849 -312.171377) (xy 4.398073 -312.218613)
			(xy 4.445686 -312.271499) (xy 4.487094 -312.329373) (xy 4.521777 -312.39151) (xy 4.549302 -312.457133)
			(xy 4.569324 -312.52542) (xy 4.581591 -312.595516) (xy 4.585952 -312.666544) (xy 4.58235 -312.737614)
			(xy 4.57708 -312.772806) (xy 4.57708 -312.77306) (xy 4.575171 -312.787958) (xy 4.577491 -312.817894)
			(xy 4.58672 -312.846466) (xy 4.602349 -312.872103) (xy 4.61264 -312.883042) (xy 4.847336 -313.117738)
			(xy 4.85942 -313.129193) (xy 4.888218 -313.145886) (xy 4.920356 -313.154555) (xy 4.936998 -313.155076)
			(xy 6.83006 -313.155076) (xy 7.777988 -312.207148) (xy 7.806944 -312.207148) (xy 7.82359 -312.206596)
			(xy 7.855747 -312.197972) (xy 7.884578 -312.181322) (xy 7.90812 -312.157781) (xy 7.92477 -312.128951)
			(xy 7.933395 -312.096794) (xy 7.933944 -312.080148) (xy 7.933944 -312.043064) (xy 7.914132 -312.011822)
			(xy 7.892288 -311.974992) (xy 7.880513 -311.954536) (xy 7.850635 -311.918004) (xy 7.814528 -311.887614)
			(xy 7.773434 -311.864407) (xy 7.728763 -311.849183) (xy 7.68205 -311.842462) (xy 7.634899 -311.844477)
			(xy 7.588929 -311.855158) (xy 7.54572 -311.874138) (xy 7.506755 -311.900766) (xy 7.489698 -311.91708)
			(xy 7.24916 -312.157872) (xy 4.988306 -312.157872) (xy 4.16306 -311.332626) (xy 4.152111 -311.322291)
			(xy 4.126414 -311.306614) (xy 4.097765 -311.297375) (xy 4.06775 -311.295087) (xy 4.052824 -311.297066)
			(xy 4.017541 -311.302376) (xy 3.946278 -311.305975) (xy 3.87506 -311.30157) (xy 3.804784 -311.289214)
			(xy 3.736335 -311.269065) (xy 3.670572 -311.241376) (xy 3.608325 -311.206494) (xy 3.550377 -311.16486)
			(xy 3.497457 -311.116997) (xy 3.450232 -311.063508) (xy 3.409294 -311.005066) (xy 3.375161 -310.942406)
			(xy 3.348261 -310.876316) (xy 3.328933 -310.80763) (xy 3.31742 -310.737211) (xy 3.313867 -310.665946)
			(xy 3.318319 -310.594731) (xy 3.33072 -310.524463) (xy 3.340354 -310.490108) (xy 3.346489 -310.467289)
			(xy 3.351295 -310.42029) (xy 3.347335 -310.373212) (xy 3.334745 -310.327676) (xy 3.313959 -310.28525)
			(xy 3.285692 -310.247395) (xy 3.250917 -310.215414) (xy 3.210833 -310.190409) (xy 3.166819 -310.17324)
			(xy 3.12039 -310.164499) (xy 3.096768 -310.163972) (xy 2.3495 -310.163972) (xy 2.321545 -310.185933)
			(xy 2.261617 -310.224179) (xy 2.197795 -310.255498) (xy 2.130876 -310.279499) (xy 2.061697 -310.295881)
			(xy 1.991122 -310.30444) (xy 1.920033 -310.305068) (xy 1.849317 -310.297759) (xy 1.779859 -310.282604)
			(xy 1.712526 -310.259791) (xy 1.64816 -310.229606) (xy 1.587565 -310.192426) (xy 1.531498 -310.148716)
			(xy 1.480659 -310.099021) (xy 1.435685 -310.043963) (xy 1.397135 -309.98423) (xy 1.365494 -309.920567)
			(xy 1.341155 -309.853771) (xy 1.324423 -309.784675) (xy 1.315507 -309.714144) (xy 1.314518 -309.643059)
			(xy 1.321469 -309.572307) (xy 1.336273 -309.502773) (xy 1.358744 -309.435326) (xy 1.388603 -309.370808)
			(xy 1.425476 -309.310025) (xy 1.468902 -309.253738) (xy 1.518339 -309.202648) (xy 1.573168 -309.157395)
			(xy 1.632706 -309.118544) (xy 1.696207 -309.086581) (xy 1.76288 -309.061904) (xy 1.831889 -309.044823)
			(xy 1.902374 -309.03555) (xy 1.973454 -309.034201) (xy 2.04424 -309.040794) (xy 2.113848 -309.055245)
			(xy 2.181408 -309.077375) (xy 2.246076 -309.106907) (xy 2.307045 -309.143471) (xy 2.363552 -309.186612)
			(xy 2.414891 -309.235789) (xy 2.460421 -309.290389) (xy 2.499572 -309.349729) (xy 2.531857 -309.413068)
			(xy 2.544826 -309.446168) (xy 2.55067 -309.460427) (xy 2.568107 -309.485823) (xy 2.591129 -309.506293)
			(xy 2.618389 -309.520643) (xy 2.648295 -309.528034) (xy 2.663698 -309.528464) (xy 2.745486 -309.528464)
			(xy 2.76855 -309.527998) (xy 2.813933 -309.519745) (xy 2.857081 -309.503438) (xy 2.896578 -309.479612)
			(xy 2.931128 -309.449051) (xy 2.959595 -309.412756) (xy 2.981046 -309.371921) (xy 2.994776 -309.327885)
			(xy 3.000334 -309.282094) (xy 2.997538 -309.236052) (xy 2.98648 -309.19127) (xy 2.967522 -309.149219)
			(xy 2.941288 -309.111279) (xy 2.925318 -309.094632) (xy 2.163064 -308.332632) (xy 2.152112 -308.3223)
			(xy 2.126416 -308.306622) (xy 2.097768 -308.297382) (xy 2.067754 -308.295093) (xy 2.052828 -308.297072)
			(xy 2.017637 -308.302344) (xy 1.946567 -308.305946) (xy 1.87554 -308.301586) (xy 1.805445 -308.289319)
			(xy 1.737158 -308.269298) (xy 1.671536 -308.241774) (xy 1.609399 -308.207091) (xy 1.551526 -308.165684)
			(xy 1.49864 -308.118072) (xy 1.451405 -308.064849) (xy 1.410411 -308.006682) (xy 1.376171 -307.9443)
			(xy 1.349114 -307.878484) (xy 1.329579 -307.810057) (xy 1.317811 -307.739876) (xy 1.313956 -307.66882)
			(xy 1.318063 -307.597778) (xy 1.330081 -307.527639) (xy 1.349859 -307.459282) (xy 1.377149 -307.393562)
			(xy 1.411611 -307.331302) (xy 1.452811 -307.273282) (xy 1.500236 -307.220227) (xy 1.55329 -307.172803)
			(xy 1.61131 -307.131602) (xy 1.67357 -307.09714) (xy 1.73929 -307.06985) (xy 1.807647 -307.050072)
			(xy 1.877785 -307.038054) (xy 1.948828 -307.033946) (xy 2.019884 -307.037801) (xy 2.090065 -307.049569)
			(xy 2.158492 -307.069103) (xy 2.224308 -307.09616) (xy 2.28669 -307.130399) (xy 2.344857 -307.171393)
			(xy 2.39808 -307.218629) (xy 2.445693 -307.271514) (xy 2.4871 -307.329387) (xy 2.521783 -307.391524)
			(xy 2.549307 -307.457146) (xy 2.569328 -307.525432) (xy 2.581596 -307.595528) (xy 2.585956 -307.666555)
			(xy 2.582354 -307.737625) (xy 2.577084 -307.772816) (xy 2.575025 -307.787742) (xy 2.577263 -307.817782)
			(xy 2.586518 -307.846448) (xy 2.602269 -307.872125) (xy 2.612644 -307.883052) (xy 3.05308 -308.323488)
			(xy 3.068909 -308.338619) (xy 3.10473 -308.363797) (xy 3.144337 -308.382461) (xy 3.186558 -308.394059)
			(xy 3.230141 -308.398247) (xy 3.273798 -308.394902) (xy 3.316235 -308.384122) (xy 3.356195 -308.366227)
			(xy 3.392496 -308.341746) (xy 3.424063 -308.311405) (xy 3.437382 -308.294024) (xy 3.458457 -308.266093)
			(xy 3.50578 -308.214548) (xy 3.558481 -308.168517) (xy 3.615923 -308.128558) (xy 3.677409 -308.095154)
			(xy 3.742193 -308.06871) (xy 3.809492 -308.049548) (xy 3.878489 -308.037898) (xy 3.948348 -308.033903)
			(xy 4.018224 -308.03761) (xy 4.052824 -308.042818) (xy 4.067749 -308.044883) (xy 4.097789 -308.042643)
			(xy 4.126456 -308.033386) (xy 4.152133 -308.017633) (xy 4.16306 -308.007258) (xy 4.854702 -307.315616)
			(xy 5.651246 -307.315616) (xy 5.674658 -307.315096) (xy 5.720689 -307.306512) (xy 5.764369 -307.289642)
			(xy 5.80422 -307.265058) (xy 5.838895 -307.233591) (xy 5.86722 -307.196306) (xy 5.888237 -307.154463)
			(xy 5.901236 -307.109479) (xy 5.905776 -307.062876) (xy 5.901703 -307.016229) (xy 5.889156 -306.971117)
			(xy 5.879338 -306.949856) (xy 5.864012 -306.917511) (xy 5.839904 -306.850116) (xy 5.823522 -306.780438)
			(xy 5.815072 -306.709361) (xy 5.814664 -306.637785) (xy 5.822301 -306.566616) (xy 5.837887 -306.496756)
			(xy 5.861224 -306.42909) (xy 5.892017 -306.364475) (xy 5.929876 -306.303729) (xy 5.974321 -306.247623)
			(xy 6.024789 -306.196866) (xy 6.080641 -306.152101) (xy 6.141169 -306.113896) (xy 6.205608 -306.082734)
			(xy 6.273139 -306.059011) (xy 6.342909 -306.043027) (xy 6.414033 -306.034984) (xy 6.485611 -306.034984)
			(xy 6.556735 -306.043027) (xy 6.626505 -306.059011) (xy 6.694036 -306.082734) (xy 6.758475 -306.113896)
			(xy 6.819003 -306.152101) (xy 6.874855 -306.196866) (xy 6.925323 -306.247623) (xy 6.969768 -306.303729)
			(xy 7.007627 -306.364475) (xy 7.03842 -306.42909) (xy 7.061757 -306.496756) (xy 7.077343 -306.566616)
			(xy 7.08498 -306.637785) (xy 7.084572 -306.709361) (xy 7.076122 -306.780438) (xy 7.05974 -306.850116)
			(xy 7.035632 -306.917511) (xy 7.020306 -306.949856) (xy 7.010467 -306.971108) (xy 6.997917 -307.016221)
			(xy 6.993843 -307.062871) (xy 6.998383 -307.109477) (xy 7.011382 -307.154463) (xy 7.032402 -307.196306)
			(xy 7.060731 -307.233592) (xy 7.09541 -307.265057) (xy 7.135266 -307.289638) (xy 7.17895 -307.306503)
			(xy 7.224985 -307.315081) (xy 7.248398 -307.315616) (xy 7.405624 -307.315616) (xy 8.188452 -308.098444)
			(xy 13.644118 -308.098444) (xy 21.353526 -315.807852) (xy 21.365696 -315.819185) (xy 21.394501 -315.835773)
			(xy 21.426614 -315.844353) (xy 21.459854 -315.844344) (xy 21.491963 -315.835746) (xy 21.520759 -315.819143)
			(xy 21.544287 -315.795663) (xy 21.560948 -315.7669) (xy 21.56961 -315.734809) (xy 21.570188 -315.71819)
			(xy 21.570188 -315.37148) (xy 9.660128 -303.46142) (xy 9.660128 -303.329848) (xy 8.662924 -302.332644)
			(xy 8.651991 -302.322291) (xy 8.626288 -302.306615) (xy 8.597634 -302.297381) (xy 8.567615 -302.2951)
			(xy 8.552688 -302.297084) (xy 8.517552 -302.302341) (xy 8.446598 -302.305943) (xy 8.375684 -302.301608)
			(xy 8.305696 -302.289392) (xy 8.237507 -302.269446) (xy 8.171968 -302.242019) (xy 8.109898 -302.207453)
			(xy 8.052069 -302.16618) (xy 7.999205 -302.118715) (xy 7.951965 -302.06565) (xy 7.910938 -302.007647)
			(xy 7.876636 -301.94543) (xy 7.849488 -301.879775) (xy 7.829831 -301.811502) (xy 7.817912 -301.741463)
			(xy 7.813879 -301.670531) (xy 7.817782 -301.599592) (xy 7.829574 -301.529531) (xy 7.849105 -301.461223)
			(xy 7.876134 -301.395519) (xy 7.892796 -301.364142) (xy 7.902898 -301.344651) (xy 7.917072 -301.303108)
			(xy 7.923898 -301.259747) (xy 7.923171 -301.215859) (xy 7.914914 -301.172747) (xy 7.899373 -301.131696)
			(xy 7.877009 -301.093926) (xy 7.848489 -301.060559) (xy 7.814659 -301.03259) (xy 7.776527 -301.010849)
			(xy 7.735226 -300.995983) (xy 7.691985 -300.988434) (xy 7.670038 -300.987968) (xy 7.069328 -300.987968)
			(xy 7.054235 -300.988367) (xy 7.024881 -300.995392) (xy 6.998003 -301.009127) (xy 6.975111 -301.028799)
			(xy 6.96595 -301.0408) (xy 6.944787 -301.069405) (xy 6.89707 -301.122194) (xy 6.843756 -301.169323)
			(xy 6.78551 -301.210201) (xy 6.723063 -301.244318) (xy 6.657196 -301.271245) (xy 6.588734 -301.290647)
			(xy 6.518532 -301.302279) (xy 6.447471 -301.305997) (xy 6.376438 -301.301754) (xy 6.306325 -301.289603)
			(xy 6.238007 -301.269697) (xy 6.172341 -301.242284) (xy 6.110148 -301.207707) (xy 6.052206 -301.166399)
			(xy 5.999241 -301.118878) (xy 5.951915 -301.065738) (xy 5.910822 -301.007644) (xy 5.876475 -300.945323)
			(xy 5.849305 -300.879556) (xy 5.829651 -300.811165) (xy 5.817759 -300.741007) (xy 5.813778 -300.66996)
			(xy 5.817759 -300.598913) (xy 5.829651 -300.528755) (xy 5.849305 -300.460364) (xy 5.876475 -300.394597)
			(xy 5.910822 -300.332276) (xy 5.951915 -300.274182) (xy 5.999241 -300.221042) (xy 6.052206 -300.173521)
			(xy 6.110148 -300.132213) (xy 6.172341 -300.097636) (xy 6.238007 -300.070223) (xy 6.306325 -300.050317)
			(xy 6.376438 -300.038166) (xy 6.447471 -300.033923) (xy 6.518532 -300.037641) (xy 6.588734 -300.049273)
			(xy 6.657196 -300.068675) (xy 6.723063 -300.095602) (xy 6.78551 -300.129719) (xy 6.843756 -300.170597)
			(xy 6.89707 -300.217726) (xy 6.944787 -300.270515) (xy 6.96595 -300.29912) (xy 6.975106 -300.311124)
			(xy 6.998007 -300.330783) (xy 7.024885 -300.344515) (xy 7.054236 -300.351551) (xy 7.069328 -300.351952)
			(xy 7.670038 -300.351952) (xy 7.69199 -300.351491) (xy 7.735244 -300.343957) (xy 7.776558 -300.3291)
			(xy 7.814705 -300.307364) (xy 7.848547 -300.279394) (xy 7.877078 -300.246024) (xy 7.899449 -300.208246)
			(xy 7.914994 -300.167185) (xy 7.92325 -300.124064) (xy 7.923971 -300.080165) (xy 7.917136 -300.036796)
			(xy 7.902949 -299.995247) (xy 7.892796 -299.975778) (xy 7.876161 -299.944458) (xy 7.849164 -299.878878)
			(xy 7.829637 -299.8107) (xy 7.817823 -299.740771) (xy 7.813869 -299.669962) (xy 7.817823 -299.599152)
			(xy 7.829637 -299.529224) (xy 7.849163 -299.461045) (xy 7.876159 -299.395465) (xy 7.892796 -299.364146)
			(xy 7.902893 -299.344653) (xy 7.917068 -299.30311) (xy 7.923893 -299.25975) (xy 7.923167 -299.215861)
			(xy 7.914911 -299.172751) (xy 7.89937 -299.1317) (xy 7.877007 -299.093929) (xy 7.848487 -299.060563)
			(xy 7.814658 -299.032594) (xy 7.776526 -299.010853) (xy 7.735225 -298.995987) (xy 7.691985 -298.988438)
			(xy 7.670038 -298.987972) (xy 7.069328 -298.987972) (xy 7.054235 -298.988369) (xy 7.02488 -298.995395)
			(xy 6.998002 -299.00913) (xy 6.97511 -299.028802) (xy 6.96595 -299.040804) (xy 6.944783 -299.069406)
			(xy 6.897066 -299.122195) (xy 6.843752 -299.169323) (xy 6.785506 -299.210201) (xy 6.723059 -299.244317)
			(xy 6.657192 -299.271244) (xy 6.58873 -299.290645) (xy 6.518529 -299.302277) (xy 6.447467 -299.305995)
			(xy 6.376435 -299.301752) (xy 6.306322 -299.2896) (xy 6.238005 -299.269694) (xy 6.172339 -299.24228)
			(xy 6.110146 -299.207703) (xy 6.052205 -299.166395) (xy 5.99924 -299.118874) (xy 5.951915 -299.065734)
			(xy 5.910822 -299.00764) (xy 5.876476 -298.945319) (xy 5.849306 -298.879552) (xy 5.829652 -298.811162)
			(xy 5.817761 -298.741004) (xy 5.813781 -298.669957) (xy 5.817762 -298.59891) (xy 5.829654 -298.528752)
			(xy 5.849308 -298.460362) (xy 5.876479 -298.394595) (xy 5.910826 -298.332275) (xy 5.951919 -298.274181)
			(xy 5.999245 -298.221041) (xy 6.05221 -298.173521) (xy 6.110152 -298.132214) (xy 6.172345 -298.097637)
			(xy 6.238011 -298.070224) (xy 6.306328 -298.050318) (xy 6.376442 -298.038168) (xy 6.447474 -298.033925)
			(xy 6.518535 -298.037643) (xy 6.588736 -298.049276) (xy 6.657199 -298.068678) (xy 6.723065 -298.095606)
			(xy 6.785512 -298.129722) (xy 6.843757 -298.170601) (xy 6.897071 -298.21773) (xy 6.944787 -298.270519)
			(xy 6.96595 -298.299124) (xy 6.975105 -298.311128) (xy 6.998007 -298.330788) (xy 7.024885 -298.344519)
			(xy 7.054236 -298.351555) (xy 7.069328 -298.351956) (xy 8.786876 -298.351956) (xy 9.148826 -298.71416)
			(xy 9.165434 -298.73016) (xy 9.203386 -298.756355) (xy 9.245439 -298.775278) (xy 9.290215 -298.786309)
			(xy 9.336246 -298.789085) (xy 9.382023 -298.783515) (xy 9.426045 -298.769783) (xy 9.46687 -298.748339)
			(xy 9.50316 -298.719884) (xy 9.533724 -298.685353) (xy 9.55756 -298.645877) (xy 9.573888 -298.60275)
			(xy 9.582172 -298.557386) (xy 9.582658 -298.534328) (xy 9.582404 -298.008802) (xy 8.561578 -296.987976)
			(xy 7.069328 -296.987976) (xy 7.054235 -296.988372) (xy 7.02488 -296.995397) (xy 6.998002 -297.009133)
			(xy 6.97511 -297.028806) (xy 6.96595 -297.040808) (xy 6.944532 -297.069753) (xy 6.896171 -297.123104)
			(xy 6.84209 -297.170648) (xy 6.782981 -297.211774) (xy 6.719603 -297.245956) (xy 6.652768 -297.272755)
			(xy 6.583332 -297.291829) (xy 6.512185 -297.302932) (xy 6.44024 -297.305922) (xy 6.368417 -297.300761)
			(xy 6.297637 -297.287516) (xy 6.228809 -297.266355) (xy 6.162813 -297.237551) (xy 6.100496 -297.201472)
			(xy 6.042656 -297.15858) (xy 5.990034 -297.109426) (xy 5.943306 -297.054639) (xy 5.922772 -297.02506)
			(xy 5.909841 -297.00676) (xy 5.878669 -296.974577) (xy 5.842336 -296.94836) (xy 5.801967 -296.928923)
			(xy 5.758815 -296.916869) (xy 5.714217 -296.91257) (xy 5.669557 -296.916161) (xy 5.626219 -296.92753)
			(xy 5.585547 -296.946324) (xy 5.548803 -296.971961) (xy 5.532628 -296.987468) (xy 4.437634 -298.082462)
			(xy 4.426746 -298.094015) (xy 4.410527 -298.121292) (xy 4.401556 -298.151733) (xy 4.40039 -298.183447)
			(xy 4.407103 -298.214464) (xy 4.421276 -298.242859) (xy 4.431284 -298.255182) (xy 4.454074 -298.282389)
			(xy 4.494116 -298.340989) (xy 4.527379 -298.403686) (xy 4.553448 -298.4697) (xy 4.572001 -298.538206)
			(xy 4.582804 -298.608354) (xy 4.585724 -298.679268) (xy 4.580725 -298.750066) (xy 4.567868 -298.819866)
			(xy 4.547314 -298.887799) (xy 4.519318 -298.953019) (xy 4.48423 -299.014713) (xy 4.442486 -299.072114)
			(xy 4.394606 -299.124505) (xy 4.341187 -299.171236) (xy 4.282894 -299.211724) (xy 4.220452 -299.245464)
			(xy 4.15464 -299.272037) (xy 4.086277 -299.291111) (xy 4.016214 -299.302449) (xy 3.945324 -299.30591)
			(xy 3.87449 -299.301451) (xy 3.804593 -299.289126) (xy 3.736506 -299.269091) (xy 3.671074 -299.241594)
			(xy 3.609114 -299.206977) (xy 3.551397 -299.165672) (xy 3.498641 -299.118194) (xy 3.451505 -299.065132)
			(xy 3.410574 -299.00715) (xy 3.376358 -298.944967) (xy 3.349284 -298.879359) (xy 3.329689 -298.811144)
			(xy 3.317817 -298.741169) (xy 3.313815 -298.670308) (xy 3.317734 -298.599442) (xy 3.329525 -298.529453)
			(xy 3.349041 -298.461215) (xy 3.376038 -298.395576) (xy 3.410181 -298.333353) (xy 3.451044 -298.275323)
			(xy 3.498119 -298.222207) (xy 3.550819 -298.174666) (xy 3.579368 -298.153582) (xy 3.591322 -298.144416)
			(xy 3.610959 -298.121585) (xy 3.624696 -298.094787) (xy 3.631768 -298.065515) (xy 3.6322 -298.050458)
			(xy 3.6322 -297.98899) (xy 5.42036 -296.20083) (xy 5.436276 -296.184158) (xy 5.462461 -296.146231)
			(xy 5.481375 -296.104204) (xy 5.4924 -296.059455) (xy 5.495174 -296.013452) (xy 5.489606 -295.967702)
			(xy 5.475877 -295.923707) (xy 5.45444 -295.882909) (xy 5.425996 -295.846647) (xy 5.391478 -295.816109)
			(xy 5.352019 -295.792297) (xy 5.308912 -295.775992) (xy 5.263572 -295.767729) (xy 5.240528 -295.767252)
			(xy 4.064762 -295.767252) (xy 3.355086 -296.476928) (xy 3.343639 -296.489018) (xy 3.326942 -296.517813)
			(xy 3.31827 -296.549948) (xy 3.317748 -296.56659) (xy 3.317748 -296.744136) (xy 3.015488 -297.04665)
			(xy 3.015488 -297.054016) (xy 2.612644 -297.45686) (xy 2.6023 -297.467802) (xy 2.586623 -297.493501)
			(xy 2.577387 -297.522153) (xy 2.575102 -297.552169) (xy 2.577084 -297.567096) (xy 2.582354 -297.602288)
			(xy 2.585957 -297.673358) (xy 2.581597 -297.744385) (xy 2.56933 -297.814481) (xy 2.549309 -297.882768)
			(xy 2.521784 -297.94839) (xy 2.487102 -298.010528) (xy 2.445695 -298.068401) (xy 2.398082 -298.121287)
			(xy 2.344859 -298.168523) (xy 2.286692 -298.209518) (xy 2.22431 -298.243758) (xy 2.158493 -298.270814)
			(xy 2.090066 -298.290349) (xy 2.019884 -298.302118) (xy 1.948827 -298.305973) (xy 1.877785 -298.301865)
			(xy 1.807646 -298.289847) (xy 1.739288 -298.270069) (xy 1.673568 -298.242779) (xy 1.611308 -298.208317)
			(xy 1.553288 -298.167116) (xy 1.500233 -298.119691) (xy 1.452808 -298.066636) (xy 1.411607 -298.008616)
			(xy 1.377145 -297.946356) (xy 1.349855 -297.880636) (xy 1.330077 -297.812278) (xy 1.318059 -297.742139)
			(xy 1.313951 -297.671097) (xy 1.317806 -297.60004) (xy 1.329575 -297.529858) (xy 1.34911 -297.461431)
			(xy 1.376166 -297.395614) (xy 1.410406 -297.333232) (xy 1.451401 -297.275065) (xy 1.498637 -297.221842)
			(xy 1.551523 -297.174229) (xy 1.609396 -297.132822) (xy 1.671534 -297.09814) (xy 1.737156 -297.070615)
			(xy 1.805443 -297.050594) (xy 1.875539 -297.038327) (xy 1.946566 -297.033967) (xy 2.017636 -297.03757)
			(xy 2.052828 -297.04284) (xy 2.067753 -297.044901) (xy 2.097793 -297.042661) (xy 2.126459 -297.033405)
			(xy 2.152136 -297.017654) (xy 2.163064 -297.00728) (xy 2.379472 -296.790872) (xy 2.379472 -296.783506)
			(xy 2.644902 -296.518076) (xy 2.656346 -296.505982) (xy 2.673044 -296.47719) (xy 2.681717 -296.445055)
			(xy 2.68224 -296.428414) (xy 2.68224 -296.250868) (xy 3.477768 -295.455086) (xy 3.492809 -295.439478)
			(xy 3.517849 -295.4041) (xy 3.536518 -295.364983) (xy 3.548273 -295.323265) (xy 3.552773 -295.280156)
			(xy 3.549888 -295.236909) (xy 3.539701 -295.19478) (xy 3.522508 -295.154993) (xy 3.498809 -295.118703)
			(xy 3.484372 -295.102534) (xy 3.47191 -295.088981) (xy 3.448399 -295.060643) (xy 3.437382 -295.045892)
			(xy 3.424071 -295.028499) (xy 3.392513 -294.998133) (xy 3.356214 -294.97363) (xy 3.316249 -294.955719)
			(xy 3.273804 -294.944929) (xy 3.230137 -294.941581) (xy 3.186543 -294.945774) (xy 3.144315 -294.957384)
			(xy 3.104705 -294.976066) (xy 3.068887 -295.001267) (xy 3.05308 -295.016428) (xy 2.612644 -295.456864)
			(xy 2.602298 -295.467803) (xy 2.586621 -295.493504) (xy 2.577385 -295.522156) (xy 2.575102 -295.552173)
			(xy 2.577084 -295.5671) (xy 2.582356 -295.602291) (xy 2.585958 -295.673361) (xy 2.581598 -295.744389)
			(xy 2.569331 -295.814484) (xy 2.54931 -295.882771) (xy 2.521786 -295.948394) (xy 2.487104 -296.010531)
			(xy 2.445697 -296.068405) (xy 2.398084 -296.121291) (xy 2.344861 -296.168526) (xy 2.286694 -296.209521)
			(xy 2.224312 -296.243761) (xy 2.158496 -296.270818) (xy 2.090068 -296.290353) (xy 2.019887 -296.302121)
			(xy 1.94883 -296.305976) (xy 1.877788 -296.301869) (xy 1.807649 -296.289851) (xy 1.739291 -296.270073)
			(xy 1.673571 -296.242783) (xy 1.611311 -296.208321) (xy 1.553291 -296.16712) (xy 1.500236 -296.119696)
			(xy 1.452811 -296.066641) (xy 1.41161 -296.008621) (xy 1.377148 -295.946361) (xy 1.349857 -295.880641)
			(xy 1.330079 -295.812283) (xy 1.318061 -295.742144) (xy 1.313954 -295.671102) (xy 1.317808 -295.600045)
			(xy 1.329577 -295.529864) (xy 1.349111 -295.461437) (xy 1.376168 -295.39562) (xy 1.410408 -295.333238)
			(xy 1.451402 -295.275071) (xy 1.498638 -295.221848) (xy 1.551523 -295.174235) (xy 1.609397 -295.132827)
			(xy 1.671534 -295.098145) (xy 1.737157 -295.07062) (xy 1.805443 -295.050599) (xy 1.875539 -295.038332)
			(xy 1.946567 -295.033972) (xy 2.017636 -295.037574) (xy 2.052828 -295.042844) (xy 2.067753 -295.044904)
			(xy 2.097793 -295.042664) (xy 2.126459 -295.033408) (xy 2.152136 -295.017658) (xy 2.163064 -295.007284)
			(xy 3.603498 -293.56685) (xy 3.618647 -293.551038) (xy 3.643821 -293.515213) (xy 3.662481 -293.475603)
			(xy 3.674076 -293.43338) (xy 3.678261 -293.389795) (xy 3.674914 -293.346138) (xy 3.664133 -293.3037)
			(xy 3.646237 -293.263739) (xy 3.621756 -293.227437) (xy 3.591415 -293.195868) (xy 3.574034 -293.182548)
			(xy 3.548192 -293.163047) (xy 3.500186 -293.119606) (xy 3.456832 -293.071522) (xy 3.437382 -293.045642)
			(xy 3.424068 -293.02825) (xy 3.392513 -292.997878) (xy 3.356215 -292.973372) (xy 3.31625 -292.955457)
			(xy 3.273804 -292.944665) (xy 3.230136 -292.941317) (xy 3.186541 -292.945511) (xy 3.144312 -292.957123)
			(xy 3.104702 -292.975809) (xy 3.068885 -293.001014) (xy 3.05308 -293.016178) (xy 2.612644 -293.456614)
			(xy 2.602327 -293.467579) (xy 2.586645 -293.49327) (xy 2.577402 -293.521914) (xy 2.575108 -293.551925)
			(xy 2.577084 -293.56685) (xy 2.582356 -293.602041) (xy 2.585958 -293.673111) (xy 2.581598 -293.744139)
			(xy 2.569331 -293.814234) (xy 2.54931 -293.882521) (xy 2.521786 -293.948144) (xy 2.487104 -294.010281)
			(xy 2.445697 -294.068155) (xy 2.398084 -294.121041) (xy 2.344861 -294.168276) (xy 2.286694 -294.209271)
			(xy 2.224312 -294.243511) (xy 2.158496 -294.270568) (xy 2.090068 -294.290103) (xy 2.019887 -294.301871)
			(xy 1.94883 -294.305726) (xy 1.877788 -294.301619) (xy 1.807649 -294.289601) (xy 1.739291 -294.269823)
			(xy 1.673571 -294.242533) (xy 1.611311 -294.208071) (xy 1.553291 -294.16687) (xy 1.500236 -294.119446)
			(xy 1.452811 -294.066391) (xy 1.41161 -294.008371) (xy 1.377148 -293.946111) (xy 1.349857 -293.880391)
			(xy 1.330079 -293.812033) (xy 1.318061 -293.741894) (xy 1.313954 -293.670852) (xy 1.317808 -293.599795)
			(xy 1.329577 -293.529614) (xy 1.349111 -293.461187) (xy 1.376168 -293.39537) (xy 1.410408 -293.332988)
			(xy 1.451402 -293.274821) (xy 1.498638 -293.221598) (xy 1.551523 -293.173985) (xy 1.609397 -293.132577)
			(xy 1.671534 -293.097895) (xy 1.737157 -293.07037) (xy 1.805443 -293.050349) (xy 1.875539 -293.038082)
			(xy 1.946567 -293.033722) (xy 2.017636 -293.037324) (xy 2.052828 -293.042594) (xy 2.067752 -293.044669)
			(xy 2.097794 -293.042427) (xy 2.126461 -293.033168) (xy 2.152138 -293.017411) (xy 2.163064 -293.007034)
			(xy 3.603244 -291.566854) (xy 3.618408 -291.55104) (xy 3.643617 -291.515209) (xy 3.662312 -291.475589)
			(xy 3.67394 -291.433351) (xy 3.678158 -291.389744) (xy 3.67484 -291.34606) (xy 3.664084 -291.303591)
			(xy 3.646209 -291.263594) (xy 3.621744 -291.227252) (xy 3.591413 -291.19564) (xy 3.574034 -291.182298)
			(xy 3.545917 -291.161072) (xy 3.494075 -291.113365) (xy 3.447828 -291.060217) (xy 3.407744 -291.00228)
			(xy 3.374315 -290.940264) (xy 3.34795 -290.874931) (xy 3.328974 -290.807083) (xy 3.317619 -290.737552)
			(xy 3.314025 -290.667192) (xy 3.318236 -290.596866) (xy 3.3302 -290.527437) (xy 3.34977 -290.459758)
			(xy 3.376707 -290.394658) (xy 3.410679 -290.332938) (xy 3.45127 -290.275355) (xy 3.497981 -290.222614)
			(xy 3.550239 -290.175364) (xy 3.607404 -290.134185) (xy 3.668772 -290.099581) (xy 3.733591 -290.071978)
			(xy 3.801066 -290.051715) (xy 3.870369 -290.039039) (xy 3.940648 -290.034107) (xy 4.011041 -290.036979)
			(xy 4.080685 -290.04762) (xy 4.148725 -290.065899) (xy 4.214324 -290.091592) (xy 4.27668 -290.124384)
			(xy 4.335025 -290.163871) (xy 4.388645 -290.209571) (xy 4.436881 -290.260921) (xy 4.47914 -290.317291)
			(xy 4.514905 -290.37799) (xy 4.543736 -290.442272) (xy 4.56528 -290.50935) (xy 4.579272 -290.578398)
			(xy 4.585541 -290.648571) (xy 4.584009 -290.719006) (xy 4.574695 -290.78884) (xy 4.566666 -290.823142)
			(xy 4.561584 -290.84565) (xy 4.558702 -290.891698) (xy 4.564184 -290.937509) (xy 4.57785 -290.981577)
			(xy 4.59925 -291.022451) (xy 4.627681 -291.058789) (xy 4.662208 -291.089393) (xy 4.701694 -291.113258)
			(xy 4.744841 -291.1296) (xy 4.79023 -291.137879) (xy 4.8133 -291.138356) (xy 5.586476 -291.138356)
			(xy 5.609539 -291.13788) (xy 5.654908 -291.129563) (xy 5.698032 -291.113198) (xy 5.737496 -291.089322)
			(xy 5.772006 -291.058717) (xy 5.800428 -291.022389) (xy 5.82183 -290.98153) (xy 5.835509 -290.93748)
			(xy 5.841018 -290.891685) (xy 5.838174 -290.845647) (xy 5.83311 -290.823142) (xy 5.825093 -290.78892)
			(xy 5.815785 -290.719248) (xy 5.814223 -290.648975) (xy 5.820426 -290.578958) (xy 5.834318 -290.510054)
			(xy 5.85573 -290.443104) (xy 5.884401 -290.378926) (xy 5.919979 -290.318304) (xy 5.96203 -290.261979)
			(xy 6.01004 -290.210639) (xy 6.063424 -290.164912) (xy 6.121528 -290.125355) (xy 6.183642 -290.092453)
			(xy 6.249009 -290.066606) (xy 6.316829 -290.048132) (xy 6.386273 -290.037256) (xy 6.456493 -290.03411)
			(xy 6.526632 -290.038733) (xy 6.595832 -290.051069) (xy 6.663248 -290.070967) (xy 6.728056 -290.098183)
			(xy 6.789464 -290.132386) (xy 6.846722 -290.173157) (xy 6.899131 -290.219998) (xy 6.946051 -290.272337)
			(xy 6.986907 -290.329534) (xy 7.021201 -290.390892) (xy 7.035292 -290.423092) (xy 7.044524 -290.443751)
			(xy 7.069198 -290.481676) (xy 7.100199 -290.514631) (xy 7.136546 -290.541575) (xy 7.177091 -290.561655)
			(xy 7.220551 -290.574237) (xy 7.265553 -290.578923) (xy 7.310673 -290.575565) (xy 7.354485 -290.564268)
			(xy 7.395604 -290.54539) (xy 7.432729 -290.519529) (xy 7.449058 -290.503864) (xy 7.884668 -290.068254)
			(xy 7.897876 -289.987736) (xy 7.879842 -289.95116) (xy 7.864537 -289.919025) (xy 7.840374 -289.85207)
			(xy 7.823843 -289.782834) (xy 7.815152 -289.712185) (xy 7.81441 -289.641007) (xy 7.821625 -289.570193)
			(xy 7.836707 -289.500627) (xy 7.859467 -289.433183) (xy 7.889621 -289.368703) (xy 7.92679 -289.307997)
			(xy 7.970509 -289.251824) (xy 8.020231 -289.200887) (xy 8.075333 -289.155825) (xy 8.135125 -289.117202)
			(xy 8.198858 -289.085502) (xy 8.265734 -289.061121) (xy 8.334915 -289.044365) (xy 8.405535 -289.035444)
			(xy 8.47671 -289.034469) (xy 8.547548 -289.041453) (xy 8.617162 -289.056308) (xy 8.684681 -289.078848)
			(xy 8.749258 -289.108791) (xy 8.810085 -289.145762) (xy 8.866401 -289.189298) (xy 8.917499 -289.238854)
			(xy 8.962741 -289.293808) (xy 9.001558 -289.353474) (xy 9.033467 -289.417103) (xy 9.058066 -289.483899)
			(xy 9.067038 -289.518344) (xy 9.072855 -289.539985) (xy 9.090987 -289.580958) (xy 9.116025 -289.618115)
			(xy 9.147192 -289.650305) (xy 9.183523 -289.676528) (xy 9.22389 -289.695973) (xy 9.267042 -289.708035)
			(xy 9.311641 -289.712341) (xy 9.356303 -289.708757) (xy 9.399645 -289.697395) (xy 9.440322 -289.678607)
			(xy 9.477072 -289.652974) (xy 9.49325 -289.63747) (xy 12.13739 -286.993584) (xy 22.584918 -286.993584)
			(xy 22.607976 -286.993138) (xy 22.65334 -286.984851) (xy 22.696465 -286.968517) (xy 22.735935 -286.94467)
			(xy 22.770456 -286.914094) (xy 22.798894 -286.877792) (xy 22.820317 -286.836955) (xy 22.834021 -286.792924)
			(xy 22.839556 -286.747143) (xy 22.836742 -286.701114) (xy 22.82567 -286.656348) (xy 22.806704 -286.614314)
			(xy 22.780466 -286.576391) (xy 22.764496 -286.559752) (xy 22.192234 -285.987744) (xy 9.069324 -285.987744)
			(xy 9.054266 -285.988213) (xy 9.024987 -285.995255) (xy 8.998179 -286.008974) (xy 8.975342 -286.028604)
			(xy 8.9662 -286.040576) (xy 8.944843 -286.069475) (xy 8.896621 -286.122753) (xy 8.842697 -286.170253)
			(xy 8.78376 -286.211367) (xy 8.720561 -286.245571) (xy 8.653908 -286.272428) (xy 8.584651 -286.291595)
			(xy 8.513673 -286.302828) (xy 8.441882 -286.305984) (xy 8.370192 -286.301022) (xy 8.29952 -286.288005)
			(xy 8.230767 -286.2671) (xy 8.164811 -286.238573) (xy 8.102494 -286.202789) (xy 8.04461 -286.160204)
			(xy 7.9919 -286.111362) (xy 7.945035 -286.056886) (xy 7.904613 -285.997471) (xy 7.871151 -285.933877)
			(xy 7.845076 -285.866913) (xy 7.826721 -285.797436) (xy 7.816319 -285.726332) (xy 7.814003 -285.654509)
			(xy 7.819804 -285.582883) (xy 7.833647 -285.512368) (xy 7.844028 -285.477966) (xy 7.850137 -285.457158)
			(xy 7.855962 -285.414186) (xy 7.854409 -285.37085) (xy 7.845524 -285.328405) (xy 7.829564 -285.288085)
			(xy 7.806992 -285.251058) (xy 7.778463 -285.218399) (xy 7.744805 -285.191056) (xy 7.706995 -285.169823)
			(xy 7.666129 -285.155315) (xy 7.623394 -285.147953) (xy 7.601712 -285.147512) (xy 7.374128 -285.147512)
			(xy 7.214616 -284.988) (xy 7.069328 -284.988) (xy 7.054234 -284.988386) (xy 7.024878 -284.995413)
			(xy 6.998 -285.009151) (xy 6.975109 -285.028828) (xy 6.96595 -285.040832) (xy 6.945116 -285.069026)
			(xy 6.898179 -285.121101) (xy 6.845797 -285.167695) (xy 6.788605 -285.208242) (xy 6.727299 -285.242249)
			(xy 6.662623 -285.269303) (xy 6.595362 -285.289075) (xy 6.526334 -285.301326) (xy 6.456378 -285.305906)
			(xy 6.386342 -285.30276) (xy 6.317077 -285.291927) (xy 6.249426 -285.273537) (xy 6.184209 -285.247813)
			(xy 6.122219 -285.21507) (xy 6.092952 -285.195772) (xy 6.073686 -285.18328) (xy 6.031669 -285.164771)
			(xy 5.987012 -285.154104) (xy 5.941166 -285.151627) (xy 5.895619 -285.157419) (xy 5.851852 -285.171293)
			(xy 5.811287 -285.192798) (xy 5.77524 -285.221236) (xy 5.744884 -285.255681) (xy 5.721204 -285.295017)
			(xy 5.704969 -285.337964) (xy 5.696706 -285.383128) (xy 5.696204 -285.406084) (xy 5.696204 -285.414466)
			(xy 5.69676 -285.431101) (xy 5.70545 -285.463218) (xy 5.722142 -285.492) (xy 5.733542 -285.504128)
			(xy 6.236716 -286.007302) (xy 6.247688 -286.017612) (xy 6.273375 -286.033298) (xy 6.302017 -286.042545)
			(xy 6.332028 -286.044839) (xy 6.346952 -286.042862) (xy 6.382144 -286.037595) (xy 6.453214 -286.033993)
			(xy 6.524241 -286.038353) (xy 6.594337 -286.050621) (xy 6.662623 -286.070642) (xy 6.728246 -286.098166)
			(xy 6.790383 -286.132849) (xy 6.848256 -286.174256) (xy 6.901142 -286.221869) (xy 6.948377 -286.275092)
			(xy 6.989371 -286.333259) (xy 7.023611 -286.395641) (xy 7.050668 -286.461458) (xy 7.070202 -286.529885)
			(xy 7.08197 -286.600066) (xy 7.085825 -286.671123) (xy 7.081717 -286.742165) (xy 7.069699 -286.812304)
			(xy 7.049921 -286.880661) (xy 7.02263 -286.946381) (xy 6.988168 -287.008641) (xy 6.946967 -287.066661)
			(xy 6.899542 -287.119716) (xy 6.846488 -287.16714) (xy 6.788467 -287.208341) (xy 6.726207 -287.242802)
			(xy 6.660487 -287.270092) (xy 6.59213 -287.28987) (xy 6.521991 -287.301888) (xy 6.450948 -287.305995)
			(xy 6.379892 -287.30214) (xy 6.309711 -287.290371) (xy 6.241283 -287.270836) (xy 6.175467 -287.243779)
			(xy 6.113085 -287.209539) (xy 6.054919 -287.168544) (xy 6.001696 -287.121308) (xy 5.954083 -287.068423)
			(xy 5.912676 -287.010549) (xy 5.877994 -286.948412) (xy 5.85047 -286.882789) (xy 5.83045 -286.814502)
			(xy 5.818183 -286.744407) (xy 5.813823 -286.673379) (xy 5.817425 -286.602309) (xy 5.822696 -286.567118)
			(xy 5.824735 -286.55219) (xy 5.822504 -286.522152) (xy 5.813255 -286.493487) (xy 5.797509 -286.46781)
			(xy 5.787136 -286.456882) (xy 5.060696 -285.730188) (xy 5.060696 -284.245304) (xy 5.809742 -283.496004)
			(xy 7.383272 -283.496004) (xy 7.433818 -283.54655) (xy 7.450593 -283.562593) (xy 7.488833 -283.588893)
			(xy 7.531213 -283.607812) (xy 7.576324 -283.61872) (xy 7.622666 -283.621255) (xy 7.668698 -283.615333)
			(xy 7.712889 -283.60115) (xy 7.75377 -283.579178) (xy 7.789981 -283.550148) (xy 7.820319 -283.515025)
			(xy 7.843774 -283.474977) (xy 7.852156 -283.453332) (xy 7.864957 -283.419439) (xy 7.897182 -283.354548)
			(xy 7.936577 -283.293742) (xy 7.98263 -283.23781) (xy 8.034746 -283.187478) (xy 8.092247 -283.1434)
			(xy 8.154387 -283.106145) (xy 8.220361 -283.076199) (xy 8.289312 -283.05395) (xy 8.360346 -283.039685)
			(xy 8.432541 -283.033591) (xy 8.504961 -283.035746) (xy 8.576667 -283.046123) (xy 8.646727 -283.064586)
			(xy 8.714233 -283.090897) (xy 8.778309 -283.124713) (xy 8.838124 -283.165597) (xy 8.892902 -283.213018)
			(xy 8.941932 -283.266359) (xy 8.984578 -283.324931) (xy 9.020287 -283.387972) (xy 9.048595 -283.454665)
			(xy 9.069136 -283.524144) (xy 9.081642 -283.595509) (xy 9.08431 -283.63164) (xy 9.087358 -283.681932)
			(xy 9.16051 -283.75102) (xy 9.468358 -283.75102) (xy 9.491401 -283.750546) (xy 9.536739 -283.742274)
			(xy 9.579842 -283.725963) (xy 9.619298 -283.702147) (xy 9.653812 -283.671607) (xy 9.682254 -283.635345)
			(xy 9.703692 -283.594548) (xy 9.717421 -283.550554) (xy 9.722994 -283.504806) (xy 9.720226 -283.458803)
			(xy 9.709208 -283.414053) (xy 9.690302 -283.372024) (xy 9.664128 -283.334092) (xy 9.64819 -283.317442)
			(xy 8.662924 -282.33243) (xy 8.651993 -282.322075) (xy 8.626289 -282.306401) (xy 8.597634 -282.297167)
			(xy 8.567615 -282.294886) (xy 8.552688 -282.29687) (xy 8.517553 -282.302133) (xy 8.446598 -282.305735)
			(xy 8.375684 -282.3014) (xy 8.305695 -282.289184) (xy 8.237506 -282.269238) (xy 8.171967 -282.24181)
			(xy 8.109896 -282.207244) (xy 8.052067 -282.165971) (xy 7.999203 -282.118505) (xy 7.951963 -282.06544)
			(xy 7.910936 -282.007436) (xy 7.876634 -281.945219) (xy 7.849485 -281.879564) (xy 7.829829 -281.81129)
			(xy 7.81791 -281.741251) (xy 7.813877 -281.670319) (xy 7.817781 -281.599379) (xy 7.829572 -281.529318)
			(xy 7.849104 -281.461009) (xy 7.876133 -281.395305) (xy 7.892796 -281.363928) (xy 7.90294 -281.344447)
			(xy 7.917127 -281.302884) (xy 7.923963 -281.259501) (xy 7.923244 -281.21559) (xy 7.914991 -281.172454)
			(xy 7.899451 -281.131378) (xy 7.877085 -281.093582) (xy 7.848559 -281.06019) (xy 7.81472 -281.032196)
			(xy 7.776574 -281.010431) (xy 7.735257 -280.995543) (xy 7.691997 -280.987975) (xy 7.670038 -280.9875)
			(xy 7.069328 -280.9875) (xy 7.054265 -280.98788) (xy 7.024979 -280.994947) (xy 6.998171 -281.008693)
			(xy 6.97534 -281.028348) (xy 6.966204 -281.040332) (xy 6.945194 -281.068764) (xy 6.897846 -281.121264)
			(xy 6.844965 -281.168186) (xy 6.787203 -281.20895) (xy 6.725274 -281.243051) (xy 6.659943 -281.27007)
			(xy 6.592017 -281.289672) (xy 6.522335 -281.301615) (xy 6.451759 -281.305751) (xy 6.38116 -281.302029)
			(xy 6.311409 -281.290496) (xy 6.243369 -281.271294) (xy 6.177881 -281.24466) (xy 6.115753 -281.210923)
			(xy 6.057752 -281.170499) (xy 6.004595 -281.123889) (xy 5.95694 -281.071668) (xy 5.915373 -281.01448)
			(xy 5.88041 -280.953034) (xy 5.852482 -280.888086) (xy 5.841746 -280.854404) (xy 5.832602 -280.823924)
			(xy 5.81025 -280.801572) (xy 5.798118 -280.790111) (xy 5.769239 -280.773402) (xy 5.737016 -280.764751)
			(xy 5.703652 -280.764751) (xy 5.671429 -280.773402) (xy 5.64255 -280.790111) (xy 5.630418 -280.801572)
			(xy 5.472176 -280.959814) (xy 5.472176 -281.5971) (xy 4.61264 -282.456636) (xy 4.60231 -282.467589)
			(xy 4.586631 -282.493284) (xy 4.57739 -282.521932) (xy 4.575101 -282.551946) (xy 4.57708 -282.566872)
			(xy 4.582332 -282.601868) (xy 4.58597 -282.672542) (xy 4.581734 -282.743184) (xy 4.569676 -282.812918)
			(xy 4.549947 -282.88088) (xy 4.52279 -282.94623) (xy 4.488541 -283.008159) (xy 4.447625 -283.0659)
			(xy 4.400548 -283.118739) (xy 4.347892 -283.16602) (xy 4.29031 -283.207159) (xy 4.228514 -283.241647)
			(xy 4.163269 -283.269057) (xy 4.095383 -283.289049) (xy 4.025697 -283.301375) (xy 3.955072 -283.305884)
			(xy 3.884384 -283.30252) (xy 3.814507 -283.291324) (xy 3.746306 -283.272434) (xy 3.680626 -283.246085)
			(xy 3.618279 -283.212603) (xy 3.560038 -283.172402) (xy 3.506623 -283.125979) (xy 3.458696 -283.073911)
			(xy 3.437382 -283.045662) (xy 3.424067 -283.02827) (xy 3.392513 -282.997897) (xy 3.356216 -282.973389)
			(xy 3.316251 -282.955472) (xy 3.273804 -282.94468) (xy 3.230136 -282.941331) (xy 3.18654 -282.945526)
			(xy 3.144311 -282.957139) (xy 3.104701 -282.975826) (xy 3.068885 -283.001034) (xy 3.05308 -283.016198)
			(xy 2.612644 -283.456634) (xy 2.602315 -283.467589) (xy 2.586636 -283.493283) (xy 2.577395 -283.521931)
			(xy 2.575105 -283.551944) (xy 2.577084 -283.56687) (xy 2.582356 -283.602061) (xy 2.585958 -283.673131)
			(xy 2.581598 -283.744159) (xy 2.569331 -283.814254) (xy 2.54931 -283.882541) (xy 2.521786 -283.948164)
			(xy 2.487104 -284.010301) (xy 2.445697 -284.068175) (xy 2.398084 -284.121061) (xy 2.344861 -284.168296)
			(xy 2.286694 -284.209291) (xy 2.224312 -284.243531) (xy 2.158496 -284.270588) (xy 2.090068 -284.290123)
			(xy 2.019887 -284.301891) (xy 1.94883 -284.305746) (xy 1.877788 -284.301639) (xy 1.807649 -284.289621)
			(xy 1.739291 -284.269843) (xy 1.673571 -284.242553) (xy 1.611311 -284.208091) (xy 1.553291 -284.16689)
			(xy 1.500236 -284.119466) (xy 1.452811 -284.066411) (xy 1.41161 -284.008391) (xy 1.377148 -283.946131)
			(xy 1.349857 -283.880411) (xy 1.330079 -283.812053) (xy 1.318061 -283.741914) (xy 1.313954 -283.670872)
			(xy 1.317808 -283.599815) (xy 1.329577 -283.529634) (xy 1.349111 -283.461207) (xy 1.376168 -283.39539)
			(xy 1.410408 -283.333008) (xy 1.451402 -283.274841) (xy 1.498638 -283.221618) (xy 1.551523 -283.174005)
			(xy 1.609397 -283.132597) (xy 1.671534 -283.097915) (xy 1.737157 -283.07039) (xy 1.805443 -283.050369)
			(xy 1.875539 -283.038102) (xy 1.946567 -283.033742) (xy 2.017636 -283.037344) (xy 2.052828 -283.042614)
			(xy 2.067753 -283.044683) (xy 2.097794 -283.042442) (xy 2.12646 -283.033184) (xy 2.152137 -283.01743)
			(xy 2.163064 -283.007054) (xy 3.603498 -281.56662) (xy 3.618647 -281.550808) (xy 3.643821 -281.514983)
			(xy 3.662481 -281.475373) (xy 3.674076 -281.43315) (xy 3.678261 -281.389565) (xy 3.674914 -281.345908)
			(xy 3.664133 -281.30347) (xy 3.646237 -281.263509) (xy 3.621756 -281.227207) (xy 3.591415 -281.195638)
			(xy 3.574034 -281.182318) (xy 3.545916 -281.161112) (xy 3.494071 -281.113443) (xy 3.447816 -281.060333)
			(xy 3.40772 -281.002432) (xy 3.374273 -280.940452) (xy 3.347886 -280.875152) (xy 3.328884 -280.807335)
			(xy 3.317498 -280.737833) (xy 3.31387 -280.667497) (xy 3.318043 -280.597192) (xy 3.329967 -280.527779)
			(xy 3.349494 -280.460112) (xy 3.376386 -280.395019) (xy 3.392932 -280.36393) (xy 3.403019 -280.344433)
			(xy 3.417189 -280.302892) (xy 3.42401 -280.259534) (xy 3.423282 -280.215648) (xy 3.415025 -280.17254)
			(xy 3.399484 -280.131492) (xy 3.377123 -280.093724) (xy 3.348606 -280.060359) (xy 3.31478 -280.03239)
			(xy 3.276652 -280.010647) (xy 3.235356 -279.995778) (xy 3.19212 -279.988225) (xy 3.170174 -279.987756)
			(xy 2.569464 -279.987756) (xy 2.554373 -279.988185) (xy 2.52502 -279.995201) (xy 2.498142 -280.008927)
			(xy 2.475248 -280.028591) (xy 2.466086 -280.040588) (xy 2.444925 -280.069195) (xy 2.397209 -280.121983)
			(xy 2.343894 -280.169112) (xy 2.285649 -280.20999) (xy 2.223202 -280.244106) (xy 2.157335 -280.271033)
			(xy 2.088873 -280.290435) (xy 2.018672 -280.302067) (xy 1.947611 -280.305785) (xy 1.876579 -280.301542)
			(xy 1.806466 -280.289392) (xy 1.738148 -280.269485) (xy 1.672482 -280.242072) (xy 1.610289 -280.207495)
			(xy 1.552348 -280.166188) (xy 1.499383 -280.118667) (xy 1.452058 -280.065527) (xy 1.410965 -280.007434)
			(xy 1.376618 -279.945113) (xy 1.349447 -279.879347) (xy 1.329793 -279.810956) (xy 1.317901 -279.740799)
			(xy 1.31392 -279.669752) (xy 1.317901 -279.598705) (xy 1.329792 -279.528547) (xy 1.349446 -279.460157)
			(xy 1.376616 -279.39439) (xy 1.410963 -279.332069) (xy 1.452056 -279.273975) (xy 1.499381 -279.220835)
			(xy 1.552345 -279.173314) (xy 1.610286 -279.132006) (xy 1.672479 -279.09743) (xy 1.738145 -279.070016)
			(xy 1.806462 -279.050109) (xy 1.876576 -279.037958) (xy 1.947607 -279.033715) (xy 2.018669 -279.037433)
			(xy 2.08887 -279.049065) (xy 2.157332 -279.068466) (xy 2.223199 -279.095393) (xy 2.285646 -279.129508)
			(xy 2.343892 -279.170386) (xy 2.397206 -279.217514) (xy 2.444923 -279.270303) (xy 2.466086 -279.298908)
			(xy 2.475224 -279.310926) (xy 2.498131 -279.330585) (xy 2.525014 -279.344313) (xy 2.55437 -279.351343)
			(xy 2.569464 -279.35174) (xy 3.170174 -279.35174) (xy 3.192127 -279.351279) (xy 3.23538 -279.343745)
			(xy 3.276695 -279.328889) (xy 3.314842 -279.307153) (xy 3.348684 -279.279183) (xy 3.377216 -279.245813)
			(xy 3.399587 -279.208035) (xy 3.415132 -279.166974) (xy 3.423387 -279.123852) (xy 3.424108 -279.079954)
			(xy 3.417273 -279.036584) (xy 3.403085 -278.995035) (xy 3.392932 -278.975566) (xy 3.376295 -278.944247)
			(xy 3.349299 -278.878667) (xy 3.329772 -278.810488) (xy 3.317958 -278.740559) (xy 3.314004 -278.66975)
			(xy 3.317958 -278.598941) (xy 3.329772 -278.529012) (xy 3.349299 -278.460833) (xy 3.376295 -278.395253)
			(xy 3.392932 -278.363934) (xy 3.403014 -278.344434) (xy 3.417184 -278.302894) (xy 3.424006 -278.259536)
			(xy 3.423278 -278.215651) (xy 3.415021 -278.172544) (xy 3.399482 -278.131496) (xy 3.377121 -278.093728)
			(xy 3.348604 -278.060363) (xy 3.314779 -278.032394) (xy 3.276651 -278.010651) (xy 3.235356 -277.995782)
			(xy 3.192119 -277.988229) (xy 3.170174 -277.98776) (xy 2.569464 -277.98776) (xy 2.554373 -277.988187)
			(xy 2.52502 -277.995204) (xy 2.498142 -278.00893) (xy 2.475248 -278.028594) (xy 2.466086 -278.040592)
			(xy 2.444921 -278.069196) (xy 2.397205 -278.121984) (xy 2.34389 -278.169112) (xy 2.285645 -278.20999)
			(xy 2.223198 -278.244105) (xy 2.157332 -278.271032) (xy 2.088869 -278.290433) (xy 2.018668 -278.302065)
			(xy 1.947607 -278.305783) (xy 1.876576 -278.30154) (xy 1.806463 -278.289389) (xy 1.738146 -278.269482)
			(xy 1.67248 -278.242068) (xy 1.610288 -278.207492) (xy 1.552347 -278.166184) (xy 1.499382 -278.118663)
			(xy 1.452058 -278.065523) (xy 1.410965 -278.00743) (xy 1.376618 -277.945109) (xy 1.349448 -277.879343)
			(xy 1.329795 -277.810953) (xy 1.317903 -277.740795) (xy 1.313923 -277.669748) (xy 1.317903 -277.598702)
			(xy 1.329795 -277.528544) (xy 1.349449 -277.460154) (xy 1.37662 -277.394388) (xy 1.410967 -277.332068)
			(xy 1.45206 -277.273974) (xy 1.499385 -277.220835) (xy 1.552349 -277.173314) (xy 1.61029 -277.132007)
			(xy 1.672483 -277.09743) (xy 1.738149 -277.070017) (xy 1.806466 -277.050111) (xy 1.876579 -277.03796)
			(xy 1.947611 -277.033717) (xy 2.018672 -277.037435) (xy 2.088873 -277.049068) (xy 2.157335 -277.068469)
			(xy 2.223201 -277.095396) (xy 2.285648 -277.129512) (xy 2.343893 -277.17039) (xy 2.397207 -277.217518)
			(xy 2.444923 -277.270307) (xy 2.466086 -277.298912) (xy 2.475223 -277.310931) (xy 2.49813 -277.330589)
			(xy 2.525014 -277.344317) (xy 2.55437 -277.351347) (xy 2.569464 -277.351744) (xy 3.956812 -277.351744)
			(xy 4.538218 -276.770338) (xy 4.549635 -276.758222) (xy 4.566341 -276.72944) (xy 4.575025 -276.697314)
			(xy 4.575556 -276.680676) (xy 4.575556 -276.47138) (xy 5.889244 -275.157438) (xy 5.900866 -275.145068)
			(xy 5.917693 -275.115605) (xy 5.926148 -275.082745) (xy 5.925633 -275.04882) (xy 5.916184 -275.016232)
			(xy 5.907786 -275.001482) (xy 5.889457 -274.970577) (xy 5.859102 -274.905446) (xy 5.836287 -274.837307)
			(xy 5.821304 -274.76703) (xy 5.814345 -274.695511) (xy 5.815497 -274.623663) (xy 5.824746 -274.552404)
			(xy 5.841975 -274.482644) (xy 5.866963 -274.415271) (xy 5.899391 -274.351148) (xy 5.938846 -274.291092)
			(xy 5.984823 -274.23587) (xy 6.036736 -274.186186) (xy 6.093922 -274.142676) (xy 6.155651 -274.105894)
			(xy 6.221136 -274.07631) (xy 6.289539 -274.054301) (xy 6.359989 -274.04015) (xy 6.431585 -274.034035)
			(xy 6.503414 -274.036036) (xy 6.574559 -274.046126) (xy 6.644111 -274.064177) (xy 6.711184 -274.089959)
			(xy 6.77492 -274.123142) (xy 6.834506 -274.163303) (xy 6.889181 -274.209929) (xy 6.938248 -274.262425)
			(xy 6.98108 -274.320121) (xy 7.017131 -274.382281) (xy 7.03199 -274.414996) (xy 7.041441 -274.435368)
			(xy 7.066401 -274.472696) (xy 7.097534 -274.505055) (xy 7.133869 -274.531439) (xy 7.174276 -274.551026)
			(xy 7.217496 -274.563207) (xy 7.262185 -274.567602) (xy 7.30695 -274.564074) (xy 7.350398 -274.552733)
			(xy 7.391177 -274.533932) (xy 7.428017 -274.508257) (xy 7.444232 -274.49272) (xy 7.850632 -274.08632)
			(xy 7.861304 -274.074939) (xy 7.877324 -274.048179) (xy 7.886363 -274.01833) (xy 7.88788 -273.987178)
			(xy 7.881785 -273.956591) (xy 7.875524 -273.942302) (xy 7.875524 -273.942048) (xy 7.860547 -273.909279)
			(xy 7.837245 -273.841098) (xy 7.821805 -273.770719) (xy 7.814424 -273.699045) (xy 7.815198 -273.626997)
			(xy 7.824116 -273.555498) (xy 7.841064 -273.485467) (xy 7.865825 -273.417802) (xy 7.898081 -273.353373)
			(xy 7.937417 -273.293005) (xy 7.983329 -273.237474) (xy 8.035228 -273.187493) (xy 8.092446 -273.143703)
			(xy 8.154251 -273.106665) (xy 8.219849 -273.076857) (xy 8.288397 -273.054659) (xy 8.359016 -273.040357)
			(xy 8.4308 -273.034135) (xy 8.502826 -273.036073) (xy 8.574171 -273.046144) (xy 8.64392 -273.064222)
			(xy 8.711175 -273.090072) (xy 8.775076 -273.123364) (xy 8.8348 -273.16367) (xy 8.889582 -273.210473)
			(xy 8.938719 -273.263172) (xy 8.981579 -273.321091) (xy 9.017614 -273.383486) (xy 9.046359 -273.449556)
			(xy 9.067447 -273.518454) (xy 9.080606 -273.589294) (xy 9.085668 -273.661169) (xy 9.082567 -273.733155)
			(xy 9.077452 -273.76882) (xy 9.074496 -273.790579) (xy 9.075211 -273.834482) (xy 9.083461 -273.877609)
			(xy 9.099 -273.918676) (xy 9.121367 -273.956462) (xy 9.149894 -273.989841) (xy 9.183734 -274.01782)
			(xy 9.221879 -274.039567) (xy 9.263194 -274.054435) (xy 9.30645 -274.061981) (xy 9.328404 -274.062444)
			(xy 10.429494 -274.062444) (xy 17.202912 -267.28928) (xy 17.218933 -267.272689) (xy 17.245136 -267.234736)
			(xy 17.264066 -267.192679) (xy 17.275101 -267.147899) (xy 17.277879 -267.101863) (xy 17.27231 -267.05608)
			(xy 17.258576 -267.012052) (xy 17.237127 -266.971223) (xy 17.208668 -266.934931) (xy 17.17413 -266.904367)
			(xy 17.134646 -266.880531) (xy 17.091512 -266.864207) (xy 17.04614 -266.85593) (xy 17.02308 -266.855448)
			(xy 10.713466 -266.855448) (xy 8.767572 -268.801342) (xy 8.767572 -269.050262) (xy 8.76797 -269.065324)
			(xy 8.775033 -269.094608) (xy 8.788774 -269.121415) (xy 8.808423 -269.144248) (xy 8.820404 -269.153386)
			(xy 8.849027 -269.174532) (xy 8.901851 -269.222224) (xy 8.949017 -269.275517) (xy 8.989934 -269.333747)
			(xy 9.024089 -269.396183) (xy 9.051056 -269.462043) (xy 9.070497 -269.530504) (xy 9.082167 -269.600708)
			(xy 9.085922 -269.671777) (xy 9.081715 -269.74282) (xy 9.069597 -269.812948) (xy 9.04972 -269.881284)
			(xy 9.022334 -269.946971) (xy 8.987781 -270.009188) (xy 8.946494 -270.067156) (xy 8.89899 -270.120148)
			(xy 8.845863 -270.167501) (xy 8.787779 -270.208624) (xy 8.725464 -270.242999) (xy 8.659699 -270.270199)
			(xy 8.591307 -270.289881) (xy 8.521144 -270.3018) (xy 8.45009 -270.305806) (xy 8.379032 -270.301849)
			(xy 8.308861 -270.289979) (xy 8.240456 -270.270344) (xy 8.174672 -270.24319) (xy 8.112334 -270.208857)
			(xy 8.054221 -270.167775) (xy 8.001061 -270.120458) (xy 7.95352 -270.067498) (xy 7.912193 -270.00956)
			(xy 7.877597 -269.947367) (xy 7.850166 -269.881698) (xy 7.830242 -269.813376) (xy 7.818076 -269.743256)
			(xy 7.813819 -269.672216) (xy 7.817525 -269.601145) (xy 7.829147 -269.530933) (xy 7.848541 -269.462458)
			(xy 7.875462 -269.396579) (xy 7.909574 -269.33412) (xy 7.950451 -269.275862) (xy 7.99758 -269.222536)
			(xy 8.050371 -269.174808) (xy 8.078978 -269.15364) (xy 8.104124 -269.135606) (xy 8.13181 -269.080996)
			(xy 8.13181 -269.050516) (xy 8.1313 -269.027474) (xy 8.123029 -268.98214) (xy 8.10672 -268.93904)
			(xy 8.082907 -268.899587) (xy 8.05237 -268.865075) (xy 8.016111 -268.836634) (xy 7.975318 -268.815197)
			(xy 7.931329 -268.801467) (xy 7.885585 -268.795894) (xy 7.839585 -268.79866) (xy 7.794838 -268.809675)
			(xy 7.752811 -268.828577) (xy 7.714881 -268.854748) (xy 7.698232 -268.870684) (xy 6.767576 -269.80134)
			(xy 6.767576 -270.05026) (xy 6.767974 -270.065322) (xy 6.775037 -270.094606) (xy 6.788777 -270.121414)
			(xy 6.808427 -270.144246) (xy 6.820408 -270.153384) (xy 6.849034 -270.174538) (xy 6.901864 -270.222241)
			(xy 6.949035 -270.275548) (xy 6.989954 -270.333792) (xy 7.024109 -270.396243) (xy 7.051074 -270.462119)
			(xy 7.070509 -270.530595) (xy 7.082172 -270.600814) (xy 7.085917 -270.671896) (xy 7.081696 -270.742951)
			(xy 7.069563 -270.81309) (xy 7.04967 -270.881435) (xy 7.022265 -270.947128) (xy 6.987692 -271.009349)
			(xy 6.946384 -271.067317) (xy 6.898858 -271.120308) (xy 6.845709 -271.167656) (xy 6.787602 -271.20877)
			(xy 6.725266 -271.243134) (xy 6.659481 -271.270319) (xy 6.591071 -271.289983) (xy 6.520891 -271.301881)
			(xy 6.449822 -271.305864) (xy 6.378753 -271.301881) (xy 6.308573 -271.289983) (xy 6.240163 -271.270319)
			(xy 6.174378 -271.243134) (xy 6.112042 -271.20877) (xy 6.053935 -271.167656) (xy 6.000786 -271.120308)
			(xy 5.95326 -271.067317) (xy 5.911952 -271.009349) (xy 5.877379 -270.947128) (xy 5.849974 -270.881435)
			(xy 5.830081 -270.81309) (xy 5.817948 -270.742951) (xy 5.813727 -270.671896) (xy 5.817472 -270.600814)
			(xy 5.829135 -270.530595) (xy 5.84857 -270.462119) (xy 5.875535 -270.396243) (xy 5.90969 -270.333792)
			(xy 5.950609 -270.275548) (xy 5.99778 -270.222241) (xy 6.05061 -270.174538) (xy 6.079236 -270.153384)
			(xy 6.091183 -270.144208) (xy 6.110822 -270.121381) (xy 6.124561 -270.094586) (xy 6.131636 -270.065316)
			(xy 6.132068 -270.05026) (xy 6.132068 -269.538196) (xy 6.273038 -269.397226) (xy 6.284438 -269.385075)
			(xy 6.301113 -269.356245) (xy 6.309748 -269.324079) (xy 6.309755 -269.290773) (xy 6.301133 -269.258604)
			(xy 6.28447 -269.229767) (xy 6.273038 -269.217648) (xy 6.262324 -269.207563) (xy 6.237328 -269.19206)
			(xy 6.209444 -269.182701) (xy 6.180157 -269.179982) (xy 6.151026 -269.18405) (xy 6.123604 -269.194687)
			(xy 6.11124 -269.202662) (xy 6.064236 -269.234221) (xy 5.966533 -269.291443) (xy 5.865061 -269.341679)
			(xy 5.760319 -269.384683) (xy 5.652822 -269.420243) (xy 5.543097 -269.448184) (xy 5.431684 -269.46837)
			(xy 5.319131 -269.480701) (xy 5.205991 -269.485116) (xy 5.092819 -269.481593) (xy 4.980172 -269.470151)
			(xy 4.868604 -269.450845) (xy 4.758662 -269.42377) (xy 4.650887 -269.389059) (xy 4.545809 -269.346882)
			(xy 4.443944 -269.297448) (xy 4.345793 -269.240999) (xy 4.251837 -269.177812) (xy 4.162539 -269.108198)
			(xy 4.078338 -269.032498) (xy 3.999647 -268.951086) (xy 3.926853 -268.864361) (xy 3.860314 -268.772749)
			(xy 3.800356 -268.6767) (xy 3.747275 -268.576687) (xy 3.701331 -268.473201) (xy 3.66275 -268.36675)
			(xy 3.631722 -268.257858) (xy 3.608399 -268.147059) (xy 3.592895 -268.034899) (xy 3.585288 -267.921929)
			(xy 3.585614 -267.808703) (xy 3.593871 -267.695778) (xy 3.61002 -267.583709) (xy 3.63398 -267.473046)
			(xy 3.665635 -267.364334) (xy 3.704827 -267.258108) (xy 3.751366 -267.154887) (xy 3.805022 -267.055181)
			(xy 3.865531 -266.959479) (xy 3.932596 -266.868252) (xy 4.005888 -266.781947) (xy 4.085046 -266.700989)
			(xy 4.169682 -266.625775) (xy 4.259379 -266.556676) (xy 4.353696 -266.494031) (xy 4.452171 -266.438147)
			(xy 4.554319 -266.3893) (xy 4.659638 -266.347729) (xy 4.767611 -266.313638) (xy 4.877706 -266.287197)
			(xy 4.989384 -266.268533) (xy 5.102095 -266.257739) (xy 5.215285 -266.254868) (xy 5.328398 -266.259934)
			(xy 5.440878 -266.272912) (xy 5.552173 -266.293738) (xy 5.661735 -266.322311) (xy 5.769026 -266.358489)
			(xy 5.873519 -266.402095) (xy 5.9747 -266.452914) (xy 6.072073 -266.510697) (xy 6.165157 -266.57516)
			(xy 6.253497 -266.645986) (xy 6.336658 -266.722827) (xy 6.414231 -266.805306) (xy 6.485835 -266.893016)
			(xy 6.551118 -266.985527) (xy 6.60976 -267.082385) (xy 6.661471 -267.183113) (xy 6.705999 -267.287216)
			(xy 6.743124 -267.394184) (xy 6.772664 -267.503489) (xy 6.794473 -267.614595) (xy 6.808445 -267.726956)
			(xy 6.814511 -267.84002) (xy 6.81264 -267.953231) (xy 6.802843 -268.066033) (xy 6.785167 -268.177871)
			(xy 6.77291 -268.233144) (xy 6.768364 -268.254575) (xy 6.765935 -268.298314) (xy 6.771044 -268.341823)
			(xy 6.783539 -268.38381) (xy 6.80305 -268.423033) (xy 6.828998 -268.458328) (xy 6.860615 -268.48865)
			(xy 6.896964 -268.5131) (xy 6.936968 -268.530955) (xy 6.979441 -268.541684) (xy 7.023125 -268.544969)
			(xy 7.066725 -268.540715) (xy 7.10895 -268.529045) (xy 7.148547 -268.510307) (xy 7.184345 -268.485056)
			(xy 7.200138 -268.469872) (xy 9.789668 -265.880596) (xy 10.785602 -265.880596) (xy 10.808666 -265.88013)
			(xy 10.854048 -265.871876) (xy 10.897195 -265.855569) (xy 10.936692 -265.831743) (xy 10.971241 -265.801181)
			(xy 10.999708 -265.764887) (xy 11.021159 -265.724052) (xy 11.034889 -265.680016) (xy 11.040447 -265.634226)
			(xy 11.037652 -265.588184) (xy 11.026594 -265.543403) (xy 11.007637 -265.501352) (xy 10.981403 -265.463412)
			(xy 10.965434 -265.446764) (xy 6.131052 -260.612382) (xy 6.131052 -260.290056) (xy 6.130631 -260.274996)
			(xy 6.123574 -260.245713) (xy 6.10984 -260.218906) (xy 6.090198 -260.196072) (xy 6.07822 -260.186932)
			(xy 6.049816 -260.166038) (xy 5.997429 -260.118831) (xy 5.950589 -260.066116) (xy 5.909872 -260.00854)
			(xy 5.875778 -259.946811) (xy 5.848726 -259.881688) (xy 5.829048 -259.81397) (xy 5.816987 -259.744491)
			(xy 5.812691 -259.674103) (xy 5.816212 -259.603673) (xy 5.827507 -259.534064) (xy 5.846437 -259.466134)
			(xy 5.87277 -259.400717) (xy 5.906182 -259.338616) (xy 5.946263 -259.280595) (xy 5.992519 -259.227368)
			(xy 6.044383 -259.179587) (xy 6.101217 -259.13784) (xy 6.162322 -259.102641) (xy 6.226948 -259.074421)
			(xy 6.294301 -259.053529) (xy 6.363552 -259.040219) (xy 6.433851 -259.034657) (xy 6.504333 -259.03691)
			(xy 6.574133 -259.046951) (xy 6.642393 -259.064655) (xy 6.708274 -259.089807) (xy 6.770966 -259.122096)
			(xy 6.800596 -259.141214) (xy 6.819905 -259.153451) (xy 6.861886 -259.171533) (xy 6.906424 -259.181818)
			(xy 6.952082 -259.183975) (xy 6.997391 -259.177934) (xy 7.040889 -259.16389) (xy 7.081176 -259.142295)
			(xy 7.116953 -259.113846) (xy 7.147068 -259.079458) (xy 7.170549 -259.040241) (xy 7.18664 -258.997458)
			(xy 7.194823 -258.952487) (xy 7.195312 -258.929632) (xy 7.195312 -258.918964) (xy 7.194734 -258.902331)
			(xy 7.186053 -258.870215) (xy 7.16937 -258.841432) (xy 7.157974 -258.829302) (xy 6.661912 -258.33324)
			(xy 6.650985 -258.322879) (xy 6.62528 -258.307205) (xy 6.596624 -258.297973) (xy 6.566604 -258.295695)
			(xy 6.551676 -258.29768) (xy 6.517642 -258.302789) (xy 6.448918 -258.306523) (xy 6.380193 -258.30281)
			(xy 6.312272 -258.291692) (xy 6.24595 -258.273299) (xy 6.182004 -258.247847) (xy 6.121182 -258.215635)
			(xy 6.064198 -258.177038) (xy 6.011718 -258.13251) (xy 5.964357 -258.082572) (xy 5.92267 -258.027808)
			(xy 5.887144 -257.96886) (xy 5.858197 -257.906419) (xy 5.836166 -257.841215) (xy 5.828284 -257.807714)
			(xy 5.82041 -257.771646) (xy 5.793994 -257.74523) (xy 5.781876 -257.733791) (xy 5.753037 -257.717115)
			(xy 5.720862 -257.708483) (xy 5.687548 -257.708483) (xy 5.655373 -257.717115) (xy 5.626534 -257.733791)
			(xy 5.614416 -257.74523) (xy 5.54863 -257.81127) (xy 5.53724 -257.823405) (xy 5.520547 -257.852182)
			(xy 5.51187 -257.884299) (xy 5.511292 -257.900932) (xy 5.511292 -259.698236) (xy 4.221226 -260.988556)
			(xy 2.568448 -260.988556) (xy 2.553356 -260.988974) (xy 2.524003 -260.995994) (xy 2.497125 -261.009723)
			(xy 2.474232 -261.029389) (xy 2.46507 -261.041388) (xy 2.443909 -261.069995) (xy 2.396192 -261.122784)
			(xy 2.342878 -261.169913) (xy 2.284632 -261.210792) (xy 2.222185 -261.244908) (xy 2.156318 -261.271836)
			(xy 2.087855 -261.291237) (xy 2.017654 -261.30287) (xy 1.946592 -261.306588) (xy 1.87556 -261.302346)
			(xy 1.805446 -261.290195) (xy 1.737128 -261.270288) (xy 1.671462 -261.242875) (xy 1.609268 -261.208299)
			(xy 1.551326 -261.166991) (xy 1.498361 -261.11947) (xy 1.451036 -261.06633) (xy 1.409942 -261.008236)
			(xy 1.375595 -260.945915) (xy 1.348424 -260.880148) (xy 1.32877 -260.811757) (xy 1.316878 -260.741599)
			(xy 1.312897 -260.670552) (xy 1.316878 -260.599504) (xy 1.328769 -260.529346) (xy 1.348423 -260.460955)
			(xy 1.375594 -260.395188) (xy 1.40994 -260.332867) (xy 1.451034 -260.274773) (xy 1.498359 -260.221632)
			(xy 1.551324 -260.174111) (xy 1.609266 -260.132803) (xy 1.671459 -260.098226) (xy 1.737125 -260.070813)
			(xy 1.805443 -260.050906) (xy 1.875557 -260.038755) (xy 1.946589 -260.034512) (xy 2.017651 -260.038229)
			(xy 2.087852 -260.049862) (xy 2.156315 -260.069263) (xy 2.222182 -260.09619) (xy 2.28463 -260.130307)
			(xy 2.342875 -260.171185) (xy 2.39619 -260.218314) (xy 2.443907 -260.271103) (xy 2.46507 -260.299708)
			(xy 2.474217 -260.311719) (xy 2.497121 -260.331378) (xy 2.524002 -260.345108) (xy 2.553355 -260.352141)
			(xy 2.568448 -260.35254) (xy 3.169158 -260.35254) (xy 3.191111 -260.352082) (xy 3.234364 -260.344548)
			(xy 3.275679 -260.329691) (xy 3.313826 -260.307954) (xy 3.347668 -260.279984) (xy 3.376199 -260.246614)
			(xy 3.39857 -260.208836) (xy 3.414115 -260.167775) (xy 3.422371 -260.124653) (xy 3.423092 -260.080754)
			(xy 3.416257 -260.037384) (xy 3.402069 -259.995835) (xy 3.391916 -259.976366) (xy 3.375227 -259.945)
			(xy 3.348187 -259.879294) (xy 3.328646 -259.810982) (xy 3.316846 -259.740916) (xy 3.312936 -259.669971)
			(xy 3.316964 -259.599033) (xy 3.32888 -259.528987) (xy 3.348535 -259.460707) (xy 3.375685 -259.395046)
			(xy 3.409989 -259.332823) (xy 3.45102 -259.274816) (xy 3.498266 -259.221747) (xy 3.551136 -259.17428)
			(xy 3.608972 -259.133006) (xy 3.67105 -259.098442) (xy 3.736597 -259.071018) (xy 3.804794 -259.051078)
			(xy 3.87479 -259.038868) (xy 3.94571 -259.034544) (xy 4.016671 -259.038157) (xy 4.051808 -259.043424)
			(xy 4.066734 -259.045475) (xy 4.096773 -259.043239) (xy 4.125439 -259.033986) (xy 4.151116 -259.018237)
			(xy 4.162044 -259.007864) (xy 4.515104 -258.654804) (xy 4.515104 -258.50342) (xy 4.514613 -258.481132)
			(xy 4.506822 -258.437243) (xy 4.491492 -258.395387) (xy 4.469095 -258.356847) (xy 4.440317 -258.322806)
			(xy 4.406041 -258.294308) (xy 4.367318 -258.272228) (xy 4.325337 -258.257243) (xy 4.281385 -258.249812)
			(xy 4.236811 -258.250164) (xy 4.192983 -258.258288) (xy 4.17195 -258.265676) (xy 4.138892 -258.277557)
			(xy 4.070789 -258.294795) (xy 4.0012 -258.304416) (xy 3.930975 -258.306305) (xy 3.86097 -258.300437)
			(xy 3.792039 -258.286884) (xy 3.725023 -258.265812) (xy 3.66074 -258.237477) (xy 3.599974 -258.202226)
			(xy 3.543467 -258.160489) (xy 3.491907 -258.112773) (xy 3.445924 -258.059663) (xy 3.406078 -258.001806)
			(xy 3.372857 -257.939906) (xy 3.346665 -257.874721) (xy 3.327822 -257.807045) (xy 3.316557 -257.737703)
			(xy 3.313008 -257.667542) (xy 3.317219 -257.597418) (xy 3.329138 -257.528186) (xy 3.34862 -257.460691)
			(xy 3.375426 -257.395756) (xy 3.391916 -257.364738) (xy 3.402007 -257.345242) (xy 3.416178 -257.3037)
			(xy 3.423002 -257.260341) (xy 3.422275 -257.216455) (xy 3.414018 -257.173346) (xy 3.398477 -257.132296)
			(xy 3.376115 -257.094527) (xy 3.347597 -257.061162) (xy 3.31377 -257.033192) (xy 3.27564 -257.01145)
			(xy 3.234342 -256.996583) (xy 3.191104 -256.989032) (xy 3.169158 -256.988564) (xy 2.568448 -256.988564)
			(xy 2.553356 -256.988978) (xy 2.524002 -256.995999) (xy 2.497125 -257.009729) (xy 2.474231 -257.029397)
			(xy 2.46507 -257.041396) (xy 2.443911 -257.070004) (xy 2.396194 -257.122794) (xy 2.34288 -257.169923)
			(xy 2.284634 -257.210802) (xy 2.222187 -257.244919) (xy 2.15632 -257.271846) (xy 2.087857 -257.291248)
			(xy 2.017656 -257.302881) (xy 1.946594 -257.3066) (xy 1.875561 -257.302357) (xy 1.805447 -257.290206)
			(xy 1.73713 -257.2703) (xy 1.671463 -257.242887) (xy 1.609269 -257.20831) (xy 1.551327 -257.167003)
			(xy 1.498361 -257.119482) (xy 1.451036 -257.066342) (xy 1.409942 -257.008248) (xy 1.375595 -256.945927)
			(xy 1.348424 -256.88016) (xy 1.328769 -256.811769) (xy 1.316877 -256.741611) (xy 1.312896 -256.670563)
			(xy 0.509016 -256.670563) (xy 0.509016 -269.705429) (xy 1.31495 -269.705429) (xy 1.31495 -269.634107)
			(xy 1.322936 -269.563233) (xy 1.338806 -269.493698) (xy 1.362363 -269.426378) (xy 1.393308 -269.362119)
			(xy 1.431254 -269.301728) (xy 1.475723 -269.245966) (xy 1.526156 -269.195533) (xy 1.581918 -269.151064)
			(xy 1.642309 -269.113118) (xy 1.706568 -269.082173) (xy 1.773888 -269.058616) (xy 1.843423 -269.042746)
			(xy 1.914297 -269.03476) (xy 1.949958 -269.03426) (xy 1.985619 -269.03476) (xy 2.056493 -269.042746)
			(xy 2.126028 -269.058616) (xy 2.193348 -269.082173) (xy 2.257607 -269.113118) (xy 2.317998 -269.151064)
			(xy 2.37376 -269.195533) (xy 2.424193 -269.245966) (xy 2.468662 -269.301728) (xy 2.506608 -269.362119)
			(xy 2.537553 -269.426378) (xy 2.56111 -269.493698) (xy 2.57698 -269.563233) (xy 2.584966 -269.634107)
			(xy 2.584966 -269.705429) (xy 2.57698 -269.776303) (xy 2.56111 -269.845838) (xy 2.537553 -269.913158)
			(xy 2.506608 -269.977417) (xy 2.468662 -270.037808) (xy 2.424193 -270.09357) (xy 2.37376 -270.144003)
			(xy 2.317998 -270.188472) (xy 2.257607 -270.226418) (xy 2.193348 -270.257363) (xy 2.126028 -270.28092)
			(xy 2.056493 -270.29679) (xy 1.985619 -270.304776) (xy 1.914297 -270.304776) (xy 1.843423 -270.29679)
			(xy 1.773888 -270.28092) (xy 1.706568 -270.257363) (xy 1.642309 -270.226418) (xy 1.581918 -270.188472)
			(xy 1.526156 -270.144003) (xy 1.475723 -270.09357) (xy 1.431254 -270.037808) (xy 1.393308 -269.977417)
			(xy 1.362363 -269.913158) (xy 1.338806 -269.845838) (xy 1.322936 -269.776303) (xy 1.31495 -269.705429)
			(xy 0.509016 -269.705429) (xy 0.509016 -270.705427) (xy 3.314946 -270.705427) (xy 3.314946 -270.634105)
			(xy 3.322932 -270.563231) (xy 3.338802 -270.493696) (xy 3.362359 -270.426376) (xy 3.393304 -270.362117)
			(xy 3.43125 -270.301726) (xy 3.475719 -270.245964) (xy 3.526152 -270.195531) (xy 3.581914 -270.151062)
			(xy 3.642305 -270.113116) (xy 3.706564 -270.082171) (xy 3.773884 -270.058614) (xy 3.843419 -270.042744)
			(xy 3.914293 -270.034758) (xy 3.949954 -270.034258) (xy 3.985615 -270.034758) (xy 4.056489 -270.042744)
			(xy 4.126024 -270.058614) (xy 4.193344 -270.082171) (xy 4.257603 -270.113116) (xy 4.317994 -270.151062)
			(xy 4.373756 -270.195531) (xy 4.424189 -270.245964) (xy 4.468658 -270.301726) (xy 4.506604 -270.362117)
			(xy 4.537549 -270.426376) (xy 4.561106 -270.493696) (xy 4.576976 -270.563231) (xy 4.584962 -270.634105)
			(xy 4.584962 -270.705427) (xy 4.576976 -270.776301) (xy 4.561106 -270.845836) (xy 4.537549 -270.913156)
			(xy 4.506604 -270.977415) (xy 4.468658 -271.037806) (xy 4.424189 -271.093568) (xy 4.373756 -271.144001)
			(xy 4.317994 -271.18847) (xy 4.257603 -271.226416) (xy 4.193344 -271.257361) (xy 4.126024 -271.280918)
			(xy 4.056489 -271.296788) (xy 3.985615 -271.304774) (xy 3.914293 -271.304774) (xy 3.843419 -271.296788)
			(xy 3.773884 -271.280918) (xy 3.706564 -271.257361) (xy 3.642305 -271.226416) (xy 3.581914 -271.18847)
			(xy 3.526152 -271.144001) (xy 3.475719 -271.093568) (xy 3.43125 -271.037806) (xy 3.393304 -270.977415)
			(xy 3.362359 -270.913156) (xy 3.338802 -270.845836) (xy 3.322932 -270.776301) (xy 3.314946 -270.705427)
			(xy 0.509016 -270.705427) (xy 0.509016 -271.705425) (xy 7.81481 -271.705425) (xy 7.81481 -271.634103)
			(xy 7.822796 -271.563229) (xy 7.838666 -271.493694) (xy 7.862223 -271.426374) (xy 7.893168 -271.362115)
			(xy 7.931114 -271.301724) (xy 7.975583 -271.245962) (xy 8.026016 -271.195529) (xy 8.081778 -271.15106)
			(xy 8.142169 -271.113114) (xy 8.206428 -271.082169) (xy 8.273748 -271.058612) (xy 8.343283 -271.042742)
			(xy 8.414157 -271.034756) (xy 8.449818 -271.034256) (xy 8.485479 -271.034756) (xy 8.556353 -271.042742)
			(xy 8.625888 -271.058612) (xy 8.693208 -271.082169) (xy 8.757467 -271.113114) (xy 8.817858 -271.15106)
			(xy 8.87362 -271.195529) (xy 8.924053 -271.245962) (xy 8.968522 -271.301724) (xy 9.006468 -271.362115)
			(xy 9.037413 -271.426374) (xy 9.06097 -271.493694) (xy 9.07684 -271.563229) (xy 9.084826 -271.634103)
			(xy 9.084826 -271.705425) (xy 9.07684 -271.776299) (xy 9.06097 -271.845834) (xy 9.037413 -271.913154)
			(xy 9.006468 -271.977413) (xy 8.968522 -272.037804) (xy 8.924053 -272.093566) (xy 8.87362 -272.143999)
			(xy 8.817858 -272.188468) (xy 8.757467 -272.226414) (xy 8.693208 -272.257359) (xy 8.625888 -272.280916)
			(xy 8.556353 -272.296786) (xy 8.485479 -272.304772) (xy 8.414157 -272.304772) (xy 8.343283 -272.296786)
			(xy 8.273748 -272.280916) (xy 8.206428 -272.257359) (xy 8.142169 -272.226414) (xy 8.081778 -272.188468)
			(xy 8.026016 -272.143999) (xy 7.975583 -272.093566) (xy 7.931114 -272.037804) (xy 7.893168 -271.977413)
			(xy 7.862223 -271.913154) (xy 7.838666 -271.845834) (xy 7.822796 -271.776299) (xy 7.81481 -271.705425)
			(xy 0.509016 -271.705425) (xy 0.509016 -272.705423) (xy 3.314946 -272.705423) (xy 3.314946 -272.634101)
			(xy 3.322932 -272.563227) (xy 3.338802 -272.493692) (xy 3.362359 -272.426372) (xy 3.393304 -272.362113)
			(xy 3.43125 -272.301722) (xy 3.475719 -272.24596) (xy 3.526152 -272.195527) (xy 3.581914 -272.151058)
			(xy 3.642305 -272.113112) (xy 3.706564 -272.082167) (xy 3.773884 -272.05861) (xy 3.843419 -272.04274)
			(xy 3.914293 -272.034754) (xy 3.949954 -272.034254) (xy 3.985615 -272.034754) (xy 4.056489 -272.04274)
			(xy 4.126024 -272.05861) (xy 4.193344 -272.082167) (xy 4.257603 -272.113112) (xy 4.317994 -272.151058)
			(xy 4.373756 -272.195527) (xy 4.424189 -272.24596) (xy 4.468658 -272.301722) (xy 4.506604 -272.362113)
			(xy 4.537549 -272.426372) (xy 4.561106 -272.493692) (xy 4.576976 -272.563227) (xy 4.584962 -272.634101)
			(xy 4.584962 -272.705423) (xy 4.576976 -272.776297) (xy 4.561106 -272.845832) (xy 4.537549 -272.913152)
			(xy 4.506604 -272.977411) (xy 4.468658 -273.037802) (xy 4.424189 -273.093564) (xy 4.373756 -273.143997)
			(xy 4.317994 -273.188466) (xy 4.257603 -273.226412) (xy 4.193344 -273.257357) (xy 4.126024 -273.280914)
			(xy 4.056489 -273.296784) (xy 3.985615 -273.30477) (xy 3.914293 -273.30477) (xy 3.843419 -273.296784)
			(xy 3.773884 -273.280914) (xy 3.706564 -273.257357) (xy 3.642305 -273.226412) (xy 3.581914 -273.188466)
			(xy 3.526152 -273.143997) (xy 3.475719 -273.093564) (xy 3.43125 -273.037802) (xy 3.393304 -272.977411)
			(xy 3.362359 -272.913152) (xy 3.338802 -272.845832) (xy 3.322932 -272.776297) (xy 3.314946 -272.705423)
			(xy 0.509016 -272.705423) (xy 0.509016 -273.705421) (xy 1.31495 -273.705421) (xy 1.31495 -273.634099)
			(xy 1.322936 -273.563225) (xy 1.338806 -273.49369) (xy 1.362363 -273.42637) (xy 1.393308 -273.362111)
			(xy 1.431254 -273.30172) (xy 1.475723 -273.245958) (xy 1.526156 -273.195525) (xy 1.581918 -273.151056)
			(xy 1.642309 -273.11311) (xy 1.706568 -273.082165) (xy 1.773888 -273.058608) (xy 1.843423 -273.042738)
			(xy 1.914297 -273.034752) (xy 1.949958 -273.034252) (xy 1.985619 -273.034752) (xy 2.056493 -273.042738)
			(xy 2.126028 -273.058608) (xy 2.193348 -273.082165) (xy 2.257607 -273.11311) (xy 2.317998 -273.151056)
			(xy 2.37376 -273.195525) (xy 2.424193 -273.245958) (xy 2.468662 -273.30172) (xy 2.506608 -273.362111)
			(xy 2.537553 -273.42637) (xy 2.56111 -273.49369) (xy 2.57698 -273.563225) (xy 2.584966 -273.634099)
			(xy 2.584966 -273.705421) (xy 2.57698 -273.776295) (xy 2.56111 -273.84583) (xy 2.537553 -273.91315)
			(xy 2.506608 -273.977409) (xy 2.468662 -274.0378) (xy 2.424193 -274.093562) (xy 2.37376 -274.143995)
			(xy 2.317998 -274.188464) (xy 2.257607 -274.22641) (xy 2.193348 -274.257355) (xy 2.126028 -274.280912)
			(xy 2.056493 -274.296782) (xy 1.985619 -274.304768) (xy 1.914297 -274.304768) (xy 1.843423 -274.296782)
			(xy 1.773888 -274.280912) (xy 1.706568 -274.257355) (xy 1.642309 -274.22641) (xy 1.581918 -274.188464)
			(xy 1.526156 -274.143995) (xy 1.475723 -274.093562) (xy 1.431254 -274.0378) (xy 1.393308 -273.977409)
			(xy 1.362363 -273.91315) (xy 1.338806 -273.84583) (xy 1.322936 -273.776295) (xy 1.31495 -273.705421)
			(xy 0.509016 -273.705421) (xy 0.509016 -274.705419) (xy 3.314946 -274.705419) (xy 3.314946 -274.634097)
			(xy 3.322932 -274.563223) (xy 3.338802 -274.493688) (xy 3.362359 -274.426368) (xy 3.393304 -274.362109)
			(xy 3.43125 -274.301718) (xy 3.475719 -274.245956) (xy 3.526152 -274.195523) (xy 3.581914 -274.151054)
			(xy 3.642305 -274.113108) (xy 3.706564 -274.082163) (xy 3.773884 -274.058606) (xy 3.843419 -274.042736)
			(xy 3.914293 -274.03475) (xy 3.949954 -274.03425) (xy 3.985615 -274.03475) (xy 4.056489 -274.042736)
			(xy 4.126024 -274.058606) (xy 4.193344 -274.082163) (xy 4.257603 -274.113108) (xy 4.317994 -274.151054)
			(xy 4.373756 -274.195523) (xy 4.424189 -274.245956) (xy 4.468658 -274.301718) (xy 4.506604 -274.362109)
			(xy 4.537549 -274.426368) (xy 4.561106 -274.493688) (xy 4.576976 -274.563223) (xy 4.584962 -274.634097)
			(xy 4.584962 -274.705419) (xy 4.576976 -274.776293) (xy 4.561106 -274.845828) (xy 4.537549 -274.913148)
			(xy 4.506604 -274.977407) (xy 4.468658 -275.037798) (xy 4.424189 -275.09356) (xy 4.373756 -275.143993)
			(xy 4.317994 -275.188462) (xy 4.257603 -275.226408) (xy 4.193344 -275.257353) (xy 4.126024 -275.28091)
			(xy 4.056489 -275.29678) (xy 3.985615 -275.304766) (xy 3.914293 -275.304766) (xy 3.843419 -275.29678)
			(xy 3.773884 -275.28091) (xy 3.706564 -275.257353) (xy 3.642305 -275.226408) (xy 3.581914 -275.188462)
			(xy 3.526152 -275.143993) (xy 3.475719 -275.09356) (xy 3.43125 -275.037798) (xy 3.393304 -274.977407)
			(xy 3.362359 -274.913148) (xy 3.338802 -274.845828) (xy 3.322932 -274.776293) (xy 3.314946 -274.705419)
			(xy 0.509016 -274.705419) (xy 0.509016 -275.705417) (xy 1.31495 -275.705417) (xy 1.31495 -275.634095)
			(xy 1.322936 -275.563221) (xy 1.338806 -275.493686) (xy 1.362363 -275.426366) (xy 1.393308 -275.362107)
			(xy 1.431254 -275.301716) (xy 1.475723 -275.245954) (xy 1.526156 -275.195521) (xy 1.581918 -275.151052)
			(xy 1.642309 -275.113106) (xy 1.706568 -275.082161) (xy 1.773888 -275.058604) (xy 1.843423 -275.042734)
			(xy 1.914297 -275.034748) (xy 1.949958 -275.034248) (xy 1.985619 -275.034748) (xy 2.056493 -275.042734)
			(xy 2.126028 -275.058604) (xy 2.193348 -275.082161) (xy 2.257607 -275.113106) (xy 2.317998 -275.151052)
			(xy 2.37376 -275.195521) (xy 2.424193 -275.245954) (xy 2.468662 -275.301716) (xy 2.506608 -275.362107)
			(xy 2.537553 -275.426366) (xy 2.56111 -275.493686) (xy 2.57698 -275.563221) (xy 2.584966 -275.634095)
			(xy 2.584966 -275.705417) (xy 2.57698 -275.776291) (xy 2.56111 -275.845826) (xy 2.537553 -275.913146)
			(xy 2.506608 -275.977405) (xy 2.468662 -276.037796) (xy 2.424193 -276.093558) (xy 2.37376 -276.143991)
			(xy 2.317998 -276.18846) (xy 2.257607 -276.226406) (xy 2.193348 -276.257351) (xy 2.126028 -276.280908)
			(xy 2.056493 -276.296778) (xy 1.985619 -276.304764) (xy 1.914297 -276.304764) (xy 1.843423 -276.296778)
			(xy 1.773888 -276.280908) (xy 1.706568 -276.257351) (xy 1.642309 -276.226406) (xy 1.581918 -276.18846)
			(xy 1.526156 -276.143991) (xy 1.475723 -276.093558) (xy 1.431254 -276.037796) (xy 1.393308 -275.977405)
			(xy 1.362363 -275.913146) (xy 1.338806 -275.845826) (xy 1.322936 -275.776291) (xy 1.31495 -275.705417)
			(xy 0.509016 -275.705417) (xy 0.509016 -284.705653) (xy 3.314946 -284.705653) (xy 3.314946 -284.634331)
			(xy 3.322932 -284.563457) (xy 3.338802 -284.493922) (xy 3.362359 -284.426602) (xy 3.393304 -284.362343)
			(xy 3.43125 -284.301952) (xy 3.475719 -284.24619) (xy 3.526152 -284.195757) (xy 3.581914 -284.151288)
			(xy 3.642305 -284.113342) (xy 3.706564 -284.082397) (xy 3.773884 -284.05884) (xy 3.843419 -284.04297)
			(xy 3.914293 -284.034984) (xy 3.949954 -284.034484) (xy 3.985615 -284.034984) (xy 4.056489 -284.04297)
			(xy 4.126024 -284.05884) (xy 4.193344 -284.082397) (xy 4.257603 -284.113342) (xy 4.317994 -284.151288)
			(xy 4.373756 -284.195757) (xy 4.424189 -284.24619) (xy 4.468658 -284.301952) (xy 4.506604 -284.362343)
			(xy 4.537549 -284.426602) (xy 4.561106 -284.493922) (xy 4.576976 -284.563457) (xy 4.584962 -284.634331)
			(xy 4.584962 -284.705653) (xy 4.576976 -284.776527) (xy 4.561106 -284.846062) (xy 4.537549 -284.913382)
			(xy 4.506604 -284.977641) (xy 4.468658 -285.038032) (xy 4.424189 -285.093794) (xy 4.373756 -285.144227)
			(xy 4.317994 -285.188696) (xy 4.257603 -285.226642) (xy 4.193344 -285.257587) (xy 4.126024 -285.281144)
			(xy 4.056489 -285.297014) (xy 3.985615 -285.305) (xy 3.914293 -285.305) (xy 3.843419 -285.297014)
			(xy 3.773884 -285.281144) (xy 3.706564 -285.257587) (xy 3.642305 -285.226642) (xy 3.581914 -285.188696)
			(xy 3.526152 -285.144227) (xy 3.475719 -285.093794) (xy 3.43125 -285.038032) (xy 3.393304 -284.977641)
			(xy 3.362359 -284.913382) (xy 3.338802 -284.846062) (xy 3.322932 -284.776527) (xy 3.314946 -284.705653)
			(xy 0.509016 -284.705653) (xy 0.509016 -285.705397) (xy 1.31495 -285.705397) (xy 1.31495 -285.634075)
			(xy 1.322936 -285.563201) (xy 1.338806 -285.493666) (xy 1.362363 -285.426346) (xy 1.393308 -285.362087)
			(xy 1.431254 -285.301696) (xy 1.475723 -285.245934) (xy 1.526156 -285.195501) (xy 1.581918 -285.151032)
			(xy 1.642309 -285.113086) (xy 1.706568 -285.082141) (xy 1.773888 -285.058584) (xy 1.843423 -285.042714)
			(xy 1.914297 -285.034728) (xy 1.949958 -285.034228) (xy 1.985619 -285.034728) (xy 2.056493 -285.042714)
			(xy 2.126028 -285.058584) (xy 2.193348 -285.082141) (xy 2.257607 -285.113086) (xy 2.317998 -285.151032)
			(xy 2.37376 -285.195501) (xy 2.424193 -285.245934) (xy 2.468662 -285.301696) (xy 2.506608 -285.362087)
			(xy 2.537553 -285.426346) (xy 2.56111 -285.493666) (xy 2.57698 -285.563201) (xy 2.584966 -285.634075)
			(xy 2.584966 -285.705397) (xy 2.57698 -285.776271) (xy 2.56111 -285.845806) (xy 2.537553 -285.913126)
			(xy 2.506608 -285.977385) (xy 2.468662 -286.037776) (xy 2.424193 -286.093538) (xy 2.37376 -286.143971)
			(xy 2.317998 -286.18844) (xy 2.257607 -286.226386) (xy 2.193348 -286.257331) (xy 2.126028 -286.280888)
			(xy 2.056493 -286.296758) (xy 1.985619 -286.304744) (xy 1.914297 -286.304744) (xy 1.843423 -286.296758)
			(xy 1.773888 -286.280888) (xy 1.706568 -286.257331) (xy 1.642309 -286.226386) (xy 1.581918 -286.18844)
			(xy 1.526156 -286.143971) (xy 1.475723 -286.093538) (xy 1.431254 -286.037776) (xy 1.393308 -285.977385)
			(xy 1.362363 -285.913126) (xy 1.338806 -285.845806) (xy 1.322936 -285.776271) (xy 1.31495 -285.705397)
			(xy 0.509016 -285.705397) (xy 0.509016 -287.705393) (xy 1.31495 -287.705393) (xy 1.31495 -287.634071)
			(xy 1.322936 -287.563197) (xy 1.338806 -287.493662) (xy 1.362363 -287.426342) (xy 1.393308 -287.362083)
			(xy 1.431254 -287.301692) (xy 1.475723 -287.24593) (xy 1.526156 -287.195497) (xy 1.581918 -287.151028)
			(xy 1.642309 -287.113082) (xy 1.706568 -287.082137) (xy 1.773888 -287.05858) (xy 1.843423 -287.04271)
			(xy 1.914297 -287.034724) (xy 1.949958 -287.034224) (xy 1.985619 -287.034724) (xy 2.056493 -287.04271)
			(xy 2.126028 -287.05858) (xy 2.193348 -287.082137) (xy 2.257607 -287.113082) (xy 2.317998 -287.151028)
			(xy 2.37376 -287.195497) (xy 2.424193 -287.24593) (xy 2.468662 -287.301692) (xy 2.506608 -287.362083)
			(xy 2.537553 -287.426342) (xy 2.56111 -287.493662) (xy 2.57698 -287.563197) (xy 2.584966 -287.634071)
			(xy 2.584966 -287.705393) (xy 2.57698 -287.776267) (xy 2.56111 -287.845802) (xy 2.537553 -287.913122)
			(xy 2.506608 -287.977381) (xy 2.468662 -288.037772) (xy 2.424193 -288.093534) (xy 2.37376 -288.143967)
			(xy 2.317998 -288.188436) (xy 2.257607 -288.226382) (xy 2.193348 -288.257327) (xy 2.126028 -288.280884)
			(xy 2.056493 -288.296754) (xy 1.985619 -288.30474) (xy 1.914297 -288.30474) (xy 1.843423 -288.296754)
			(xy 1.773888 -288.280884) (xy 1.706568 -288.257327) (xy 1.642309 -288.226382) (xy 1.581918 -288.188436)
			(xy 1.526156 -288.143967) (xy 1.475723 -288.093534) (xy 1.431254 -288.037772) (xy 1.393308 -287.977381)
			(xy 1.362363 -287.913122) (xy 1.338806 -287.845802) (xy 1.322936 -287.776267) (xy 1.31495 -287.705393)
			(xy 0.509016 -287.705393) (xy 0.509016 -288.705645) (xy 3.314946 -288.705645) (xy 3.314946 -288.634323)
			(xy 3.322932 -288.563449) (xy 3.338802 -288.493914) (xy 3.362359 -288.426594) (xy 3.393304 -288.362335)
			(xy 3.43125 -288.301944) (xy 3.475719 -288.246182) (xy 3.526152 -288.195749) (xy 3.581914 -288.15128)
			(xy 3.642305 -288.113334) (xy 3.706564 -288.082389) (xy 3.773884 -288.058832) (xy 3.843419 -288.042962)
			(xy 3.914293 -288.034976) (xy 3.949954 -288.034476) (xy 3.985615 -288.034976) (xy 4.056489 -288.042962)
			(xy 4.126024 -288.058832) (xy 4.193344 -288.082389) (xy 4.257603 -288.113334) (xy 4.317994 -288.15128)
			(xy 4.373756 -288.195749) (xy 4.424189 -288.246182) (xy 4.468658 -288.301944) (xy 4.506604 -288.362335)
			(xy 4.537549 -288.426594) (xy 4.561106 -288.493914) (xy 4.576976 -288.563449) (xy 4.584962 -288.634323)
			(xy 4.584962 -288.705645) (xy 5.814814 -288.705645) (xy 5.814814 -288.634323) (xy 5.8228 -288.563449)
			(xy 5.83867 -288.493914) (xy 5.862227 -288.426594) (xy 5.893172 -288.362335) (xy 5.931118 -288.301944)
			(xy 5.975587 -288.246182) (xy 6.02602 -288.195749) (xy 6.081782 -288.15128) (xy 6.142173 -288.113334)
			(xy 6.206432 -288.082389) (xy 6.273752 -288.058832) (xy 6.343287 -288.042962) (xy 6.414161 -288.034976)
			(xy 6.449822 -288.034476) (xy 6.485483 -288.034976) (xy 6.556357 -288.042962) (xy 6.625892 -288.058832)
			(xy 6.693212 -288.082389) (xy 6.757471 -288.113334) (xy 6.817862 -288.15128) (xy 6.873624 -288.195749)
			(xy 6.924057 -288.246182) (xy 6.968526 -288.301944) (xy 7.006472 -288.362335) (xy 7.037417 -288.426594)
			(xy 7.060974 -288.493914) (xy 7.076844 -288.563449) (xy 7.08483 -288.634323) (xy 7.08483 -288.705645)
			(xy 7.076844 -288.776519) (xy 7.060974 -288.846054) (xy 7.037417 -288.913374) (xy 7.006472 -288.977633)
			(xy 6.968526 -289.038024) (xy 6.924057 -289.093786) (xy 6.873624 -289.144219) (xy 6.817862 -289.188688)
			(xy 6.757471 -289.226634) (xy 6.693212 -289.257579) (xy 6.625892 -289.281136) (xy 6.556357 -289.297006)
			(xy 6.485483 -289.304992) (xy 6.414161 -289.304992) (xy 6.343287 -289.297006) (xy 6.273752 -289.281136)
			(xy 6.206432 -289.257579) (xy 6.142173 -289.226634) (xy 6.081782 -289.188688) (xy 6.02602 -289.144219)
			(xy 5.975587 -289.093786) (xy 5.931118 -289.038024) (xy 5.893172 -288.977633) (xy 5.862227 -288.913374)
			(xy 5.83867 -288.846054) (xy 5.8228 -288.776519) (xy 5.814814 -288.705645) (xy 4.584962 -288.705645)
			(xy 4.576976 -288.776519) (xy 4.561106 -288.846054) (xy 4.537549 -288.913374) (xy 4.506604 -288.977633)
			(xy 4.468658 -289.038024) (xy 4.424189 -289.093786) (xy 4.373756 -289.144219) (xy 4.317994 -289.188688)
			(xy 4.257603 -289.226634) (xy 4.193344 -289.257579) (xy 4.126024 -289.281136) (xy 4.056489 -289.297006)
			(xy 3.985615 -289.304992) (xy 3.914293 -289.304992) (xy 3.843419 -289.297006) (xy 3.773884 -289.281136)
			(xy 3.706564 -289.257579) (xy 3.642305 -289.226634) (xy 3.581914 -289.188688) (xy 3.526152 -289.144219)
			(xy 3.475719 -289.093786) (xy 3.43125 -289.038024) (xy 3.393304 -288.977633) (xy 3.362359 -288.913374)
			(xy 3.338802 -288.846054) (xy 3.322932 -288.776519) (xy 3.314946 -288.705645) (xy 0.509016 -288.705645)
			(xy 0.509016 -289.705389) (xy 1.31495 -289.705389) (xy 1.31495 -289.634067) (xy 1.322936 -289.563193)
			(xy 1.338806 -289.493658) (xy 1.362363 -289.426338) (xy 1.393308 -289.362079) (xy 1.431254 -289.301688)
			(xy 1.475723 -289.245926) (xy 1.526156 -289.195493) (xy 1.581918 -289.151024) (xy 1.642309 -289.113078)
			(xy 1.706568 -289.082133) (xy 1.773888 -289.058576) (xy 1.843423 -289.042706) (xy 1.914297 -289.03472)
			(xy 1.949958 -289.03422) (xy 1.985619 -289.03472) (xy 2.056493 -289.042706) (xy 2.126028 -289.058576)
			(xy 2.193348 -289.082133) (xy 2.257607 -289.113078) (xy 2.317998 -289.151024) (xy 2.37376 -289.195493)
			(xy 2.424193 -289.245926) (xy 2.468662 -289.301688) (xy 2.506608 -289.362079) (xy 2.537553 -289.426338)
			(xy 2.56111 -289.493658) (xy 2.57698 -289.563193) (xy 2.584966 -289.634067) (xy 2.584966 -289.705389)
			(xy 2.57698 -289.776263) (xy 2.56111 -289.845798) (xy 2.537553 -289.913118) (xy 2.506608 -289.977377)
			(xy 2.468662 -290.037768) (xy 2.424193 -290.09353) (xy 2.37376 -290.143963) (xy 2.317998 -290.188432)
			(xy 2.257607 -290.226378) (xy 2.193348 -290.257323) (xy 2.126028 -290.28088) (xy 2.056493 -290.29675)
			(xy 1.985619 -290.304736) (xy 1.914297 -290.304736) (xy 1.843423 -290.29675) (xy 1.773888 -290.28088)
			(xy 1.706568 -290.257323) (xy 1.642309 -290.226378) (xy 1.581918 -290.188432) (xy 1.526156 -290.143963)
			(xy 1.475723 -290.09353) (xy 1.431254 -290.037768) (xy 1.393308 -289.977377) (xy 1.362363 -289.913118)
			(xy 1.338806 -289.845798) (xy 1.322936 -289.776263) (xy 1.31495 -289.705389) (xy 0.509016 -289.705389)
			(xy 0.509016 -299.705623) (xy 1.31495 -299.705623) (xy 1.31495 -299.634301) (xy 1.322936 -299.563427)
			(xy 1.338806 -299.493892) (xy 1.362363 -299.426572) (xy 1.393308 -299.362313) (xy 1.431254 -299.301922)
			(xy 1.475723 -299.24616) (xy 1.526156 -299.195727) (xy 1.581918 -299.151258) (xy 1.642309 -299.113312)
			(xy 1.706568 -299.082367) (xy 1.773888 -299.05881) (xy 1.843423 -299.04294) (xy 1.914297 -299.034954)
			(xy 1.949958 -299.034454) (xy 1.985619 -299.034954) (xy 2.056493 -299.04294) (xy 2.126028 -299.05881)
			(xy 2.193348 -299.082367) (xy 2.257607 -299.113312) (xy 2.317998 -299.151258) (xy 2.37376 -299.195727)
			(xy 2.424193 -299.24616) (xy 2.468662 -299.301922) (xy 2.506608 -299.362313) (xy 2.537553 -299.426572)
			(xy 2.56111 -299.493892) (xy 2.57698 -299.563427) (xy 2.584966 -299.634301) (xy 2.584966 -299.705623)
			(xy 2.57698 -299.776497) (xy 2.56111 -299.846032) (xy 2.537553 -299.913352) (xy 2.506608 -299.977611)
			(xy 2.468662 -300.038002) (xy 2.424193 -300.093764) (xy 2.37376 -300.144197) (xy 2.317998 -300.188666)
			(xy 2.257607 -300.226612) (xy 2.193348 -300.257557) (xy 2.126028 -300.281114) (xy 2.056493 -300.296984)
			(xy 1.985619 -300.30497) (xy 1.914297 -300.30497) (xy 1.843423 -300.296984) (xy 1.773888 -300.281114)
			(xy 1.706568 -300.257557) (xy 1.642309 -300.226612) (xy 1.581918 -300.188666) (xy 1.526156 -300.144197)
			(xy 1.475723 -300.093764) (xy 1.431254 -300.038002) (xy 1.393308 -299.977611) (xy 1.362363 -299.913352)
			(xy 1.338806 -299.846032) (xy 1.322936 -299.776497) (xy 1.31495 -299.705623) (xy 0.509016 -299.705623)
			(xy 0.509016 -300.705621) (xy 3.314946 -300.705621) (xy 3.314946 -300.634299) (xy 3.322932 -300.563425)
			(xy 3.338802 -300.49389) (xy 3.362359 -300.42657) (xy 3.393304 -300.362311) (xy 3.43125 -300.30192)
			(xy 3.475719 -300.246158) (xy 3.526152 -300.195725) (xy 3.581914 -300.151256) (xy 3.642305 -300.11331)
			(xy 3.706564 -300.082365) (xy 3.773884 -300.058808) (xy 3.843419 -300.042938) (xy 3.914293 -300.034952)
			(xy 3.949954 -300.034452) (xy 3.985615 -300.034952) (xy 4.056489 -300.042938) (xy 4.126024 -300.058808)
			(xy 4.193344 -300.082365) (xy 4.257603 -300.11331) (xy 4.317994 -300.151256) (xy 4.373756 -300.195725)
			(xy 4.424189 -300.246158) (xy 4.468658 -300.30192) (xy 4.506604 -300.362311) (xy 4.537549 -300.42657)
			(xy 4.561106 -300.49389) (xy 4.576976 -300.563425) (xy 4.584962 -300.634299) (xy 4.584962 -300.705621)
			(xy 4.576976 -300.776495) (xy 4.561106 -300.84603) (xy 4.537549 -300.91335) (xy 4.506604 -300.977609)
			(xy 4.468658 -301.038) (xy 4.424189 -301.093762) (xy 4.373756 -301.144195) (xy 4.317994 -301.188664)
			(xy 4.257603 -301.22661) (xy 4.193344 -301.257555) (xy 4.126024 -301.281112) (xy 4.056489 -301.296982)
			(xy 3.985615 -301.304968) (xy 3.914293 -301.304968) (xy 3.843419 -301.296982) (xy 3.773884 -301.281112)
			(xy 3.706564 -301.257555) (xy 3.642305 -301.22661) (xy 3.581914 -301.188664) (xy 3.526152 -301.144195)
			(xy 3.475719 -301.093762) (xy 3.43125 -301.038) (xy 3.393304 -300.977609) (xy 3.362359 -300.91335)
			(xy 3.338802 -300.84603) (xy 3.322932 -300.776495) (xy 3.314946 -300.705621) (xy 0.509016 -300.705621)
			(xy 0.509016 -302.705617) (xy 3.314946 -302.705617) (xy 3.314946 -302.634295) (xy 3.322932 -302.563421)
			(xy 3.338802 -302.493886) (xy 3.362359 -302.426566) (xy 3.393304 -302.362307) (xy 3.43125 -302.301916)
			(xy 3.475719 -302.246154) (xy 3.526152 -302.195721) (xy 3.581914 -302.151252) (xy 3.642305 -302.113306)
			(xy 3.706564 -302.082361) (xy 3.773884 -302.058804) (xy 3.843419 -302.042934) (xy 3.914293 -302.034948)
			(xy 3.949954 -302.034448) (xy 3.985615 -302.034948) (xy 4.056489 -302.042934) (xy 4.126024 -302.058804)
			(xy 4.193344 -302.082361) (xy 4.257603 -302.113306) (xy 4.317994 -302.151252) (xy 4.373756 -302.195721)
			(xy 4.424189 -302.246154) (xy 4.468658 -302.301916) (xy 4.506604 -302.362307) (xy 4.537549 -302.426566)
			(xy 4.561106 -302.493886) (xy 4.576976 -302.563421) (xy 4.584962 -302.634295) (xy 4.584962 -302.705617)
			(xy 4.576976 -302.776491) (xy 4.561106 -302.846026) (xy 4.537549 -302.913346) (xy 4.506604 -302.977605)
			(xy 4.468658 -303.037996) (xy 4.424189 -303.093758) (xy 4.373756 -303.144191) (xy 4.317994 -303.18866)
			(xy 4.257603 -303.226606) (xy 4.193344 -303.257551) (xy 4.126024 -303.281108) (xy 4.056489 -303.296978)
			(xy 3.985615 -303.304964) (xy 3.914293 -303.304964) (xy 3.843419 -303.296978) (xy 3.773884 -303.281108)
			(xy 3.706564 -303.257551) (xy 3.642305 -303.226606) (xy 3.581914 -303.18866) (xy 3.526152 -303.144191)
			(xy 3.475719 -303.093758) (xy 3.43125 -303.037996) (xy 3.393304 -302.977605) (xy 3.362359 -302.913346)
			(xy 3.338802 -302.846026) (xy 3.322932 -302.776491) (xy 3.314946 -302.705617) (xy 0.509016 -302.705617)
			(xy 0.509016 -303.705615) (xy 1.31495 -303.705615) (xy 1.31495 -303.634293) (xy 1.322936 -303.563419)
			(xy 1.338806 -303.493884) (xy 1.362363 -303.426564) (xy 1.393308 -303.362305) (xy 1.431254 -303.301914)
			(xy 1.475723 -303.246152) (xy 1.526156 -303.195719) (xy 1.581918 -303.15125) (xy 1.642309 -303.113304)
			(xy 1.706568 -303.082359) (xy 1.773888 -303.058802) (xy 1.843423 -303.042932) (xy 1.914297 -303.034946)
			(xy 1.949958 -303.034446) (xy 1.985619 -303.034946) (xy 2.056493 -303.042932) (xy 2.126028 -303.058802)
			(xy 2.193348 -303.082359) (xy 2.257607 -303.113304) (xy 2.317998 -303.15125) (xy 2.37376 -303.195719)
			(xy 2.424193 -303.246152) (xy 2.468662 -303.301914) (xy 2.506608 -303.362305) (xy 2.537553 -303.426564)
			(xy 2.56111 -303.493884) (xy 2.57698 -303.563419) (xy 2.584966 -303.634293) (xy 2.584966 -303.705615)
			(xy 7.81481 -303.705615) (xy 7.81481 -303.634293) (xy 7.822796 -303.563419) (xy 7.838666 -303.493884)
			(xy 7.862223 -303.426564) (xy 7.893168 -303.362305) (xy 7.931114 -303.301914) (xy 7.975583 -303.246152)
			(xy 8.026016 -303.195719) (xy 8.081778 -303.15125) (xy 8.142169 -303.113304) (xy 8.206428 -303.082359)
			(xy 8.273748 -303.058802) (xy 8.343283 -303.042932) (xy 8.414157 -303.034946) (xy 8.449818 -303.034446)
			(xy 8.485479 -303.034946) (xy 8.556353 -303.042932) (xy 8.625888 -303.058802) (xy 8.693208 -303.082359)
			(xy 8.757467 -303.113304) (xy 8.817858 -303.15125) (xy 8.87362 -303.195719) (xy 8.924053 -303.246152)
			(xy 8.968522 -303.301914) (xy 9.006468 -303.362305) (xy 9.037413 -303.426564) (xy 9.06097 -303.493884)
			(xy 9.07684 -303.563419) (xy 9.084826 -303.634293) (xy 9.084826 -303.705615) (xy 9.07684 -303.776489)
			(xy 9.06097 -303.846024) (xy 9.037413 -303.913344) (xy 9.006468 -303.977603) (xy 8.968522 -304.037994)
			(xy 8.924053 -304.093756) (xy 8.87362 -304.144189) (xy 8.817858 -304.188658) (xy 8.757467 -304.226604)
			(xy 8.693208 -304.257549) (xy 8.625888 -304.281106) (xy 8.556353 -304.296976) (xy 8.485479 -304.304962)
			(xy 8.414157 -304.304962) (xy 8.343283 -304.296976) (xy 8.273748 -304.281106) (xy 8.206428 -304.257549)
			(xy 8.142169 -304.226604) (xy 8.081778 -304.188658) (xy 8.026016 -304.144189) (xy 7.975583 -304.093756)
			(xy 7.931114 -304.037994) (xy 7.893168 -303.977603) (xy 7.862223 -303.913344) (xy 7.838666 -303.846024)
			(xy 7.822796 -303.776489) (xy 7.81481 -303.705615) (xy 2.584966 -303.705615) (xy 2.57698 -303.776489)
			(xy 2.56111 -303.846024) (xy 2.537553 -303.913344) (xy 2.506608 -303.977603) (xy 2.468662 -304.037994)
			(xy 2.424193 -304.093756) (xy 2.37376 -304.144189) (xy 2.317998 -304.188658) (xy 2.257607 -304.226604)
			(xy 2.193348 -304.257549) (xy 2.126028 -304.281106) (xy 2.056493 -304.296976) (xy 1.985619 -304.304962)
			(xy 1.914297 -304.304962) (xy 1.843423 -304.296976) (xy 1.773888 -304.281106) (xy 1.706568 -304.257549)
			(xy 1.642309 -304.226604) (xy 1.581918 -304.188658) (xy 1.526156 -304.144189) (xy 1.475723 -304.093756)
			(xy 1.431254 -304.037994) (xy 1.393308 -303.977603) (xy 1.362363 -303.913344) (xy 1.338806 -303.846024)
			(xy 1.322936 -303.776489) (xy 1.31495 -303.705615) (xy 0.509016 -303.705615) (xy 0.509016 -304.705613)
			(xy 3.314946 -304.705613) (xy 3.314946 -304.634291) (xy 3.322932 -304.563417) (xy 3.338802 -304.493882)
			(xy 3.362359 -304.426562) (xy 3.393304 -304.362303) (xy 3.43125 -304.301912) (xy 3.475719 -304.24615)
			(xy 3.526152 -304.195717) (xy 3.581914 -304.151248) (xy 3.642305 -304.113302) (xy 3.706564 -304.082357)
			(xy 3.773884 -304.0588) (xy 3.843419 -304.04293) (xy 3.914293 -304.034944) (xy 3.949954 -304.034444)
			(xy 3.985615 -304.034944) (xy 4.056489 -304.04293) (xy 4.126024 -304.0588) (xy 4.193344 -304.082357)
			(xy 4.257603 -304.113302) (xy 4.317994 -304.151248) (xy 4.373756 -304.195717) (xy 4.424189 -304.24615)
			(xy 4.468658 -304.301912) (xy 4.506604 -304.362303) (xy 4.537549 -304.426562) (xy 4.561106 -304.493882)
			(xy 4.576976 -304.563417) (xy 4.584962 -304.634291) (xy 4.584962 -304.705613) (xy 5.814814 -304.705613)
			(xy 5.814814 -304.634291) (xy 5.8228 -304.563417) (xy 5.83867 -304.493882) (xy 5.862227 -304.426562)
			(xy 5.893172 -304.362303) (xy 5.931118 -304.301912) (xy 5.975587 -304.24615) (xy 6.02602 -304.195717)
			(xy 6.081782 -304.151248) (xy 6.142173 -304.113302) (xy 6.206432 -304.082357) (xy 6.273752 -304.0588)
			(xy 6.343287 -304.04293) (xy 6.414161 -304.034944) (xy 6.449822 -304.034444) (xy 6.485483 -304.034944)
			(xy 6.556357 -304.04293) (xy 6.625892 -304.0588) (xy 6.693212 -304.082357) (xy 6.757471 -304.113302)
			(xy 6.817862 -304.151248) (xy 6.873624 -304.195717) (xy 6.924057 -304.24615) (xy 6.968526 -304.301912)
			(xy 7.006472 -304.362303) (xy 7.037417 -304.426562) (xy 7.060974 -304.493882) (xy 7.076844 -304.563417)
			(xy 7.08483 -304.634291) (xy 7.08483 -304.705613) (xy 7.076844 -304.776487) (xy 7.060974 -304.846022)
			(xy 7.037417 -304.913342) (xy 7.006472 -304.977601) (xy 6.968526 -305.037992) (xy 6.924057 -305.093754)
			(xy 6.873624 -305.144187) (xy 6.817862 -305.188656) (xy 6.757471 -305.226602) (xy 6.693212 -305.257547)
			(xy 6.625892 -305.281104) (xy 6.556357 -305.296974) (xy 6.485483 -305.30496) (xy 6.414161 -305.30496)
			(xy 6.343287 -305.296974) (xy 6.273752 -305.281104) (xy 6.206432 -305.257547) (xy 6.142173 -305.226602)
			(xy 6.081782 -305.188656) (xy 6.02602 -305.144187) (xy 5.975587 -305.093754) (xy 5.931118 -305.037992)
			(xy 5.893172 -304.977601) (xy 5.862227 -304.913342) (xy 5.83867 -304.846022) (xy 5.8228 -304.776487)
			(xy 5.814814 -304.705613) (xy 4.584962 -304.705613) (xy 4.576976 -304.776487) (xy 4.561106 -304.846022)
			(xy 4.537549 -304.913342) (xy 4.506604 -304.977601) (xy 4.468658 -305.037992) (xy 4.424189 -305.093754)
			(xy 4.373756 -305.144187) (xy 4.317994 -305.188656) (xy 4.257603 -305.226602) (xy 4.193344 -305.257547)
			(xy 4.126024 -305.281104) (xy 4.056489 -305.296974) (xy 3.985615 -305.30496) (xy 3.914293 -305.30496)
			(xy 3.843419 -305.296974) (xy 3.773884 -305.281104) (xy 3.706564 -305.257547) (xy 3.642305 -305.226602)
			(xy 3.581914 -305.188656) (xy 3.526152 -305.144187) (xy 3.475719 -305.093754) (xy 3.43125 -305.037992)
			(xy 3.393304 -304.977601) (xy 3.362359 -304.913342) (xy 3.338802 -304.846022) (xy 3.322932 -304.776487)
			(xy 3.314946 -304.705613) (xy 0.509016 -304.705613) (xy 0.509016 -305.705611) (xy 1.31495 -305.705611)
			(xy 1.31495 -305.634289) (xy 1.322936 -305.563415) (xy 1.338806 -305.49388) (xy 1.362363 -305.42656)
			(xy 1.393308 -305.362301) (xy 1.431254 -305.30191) (xy 1.475723 -305.246148) (xy 1.526156 -305.195715)
			(xy 1.581918 -305.151246) (xy 1.642309 -305.1133) (xy 1.706568 -305.082355) (xy 1.773888 -305.058798)
			(xy 1.843423 -305.042928) (xy 1.914297 -305.034942) (xy 1.949958 -305.034442) (xy 1.985619 -305.034942)
			(xy 2.056493 -305.042928) (xy 2.126028 -305.058798) (xy 2.193348 -305.082355) (xy 2.257607 -305.1133)
			(xy 2.317998 -305.151246) (xy 2.37376 -305.195715) (xy 2.424193 -305.246148) (xy 2.468662 -305.30191)
			(xy 2.506608 -305.362301) (xy 2.537553 -305.42656) (xy 2.56111 -305.49388) (xy 2.57698 -305.563415)
			(xy 2.584966 -305.634289) (xy 2.584966 -305.705611) (xy 7.81481 -305.705611) (xy 7.81481 -305.634289)
			(xy 7.822796 -305.563415) (xy 7.838666 -305.49388) (xy 7.862223 -305.42656) (xy 7.893168 -305.362301)
			(xy 7.931114 -305.30191) (xy 7.975583 -305.246148) (xy 8.026016 -305.195715) (xy 8.081778 -305.151246)
			(xy 8.142169 -305.1133) (xy 8.206428 -305.082355) (xy 8.273748 -305.058798) (xy 8.343283 -305.042928)
			(xy 8.414157 -305.034942) (xy 8.449818 -305.034442) (xy 8.485479 -305.034942) (xy 8.556353 -305.042928)
			(xy 8.625888 -305.058798) (xy 8.693208 -305.082355) (xy 8.757467 -305.1133) (xy 8.817858 -305.151246)
			(xy 8.87362 -305.195715) (xy 8.924053 -305.246148) (xy 8.968522 -305.30191) (xy 9.006468 -305.362301)
			(xy 9.037413 -305.42656) (xy 9.06097 -305.49388) (xy 9.07684 -305.563415) (xy 9.084826 -305.634289)
			(xy 9.084826 -305.705611) (xy 9.07684 -305.776485) (xy 9.06097 -305.84602) (xy 9.037413 -305.91334)
			(xy 9.006468 -305.977599) (xy 8.968522 -306.03799) (xy 8.924053 -306.093752) (xy 8.87362 -306.144185)
			(xy 8.817858 -306.188654) (xy 8.757467 -306.2266) (xy 8.693208 -306.257545) (xy 8.625888 -306.281102)
			(xy 8.556353 -306.296972) (xy 8.485479 -306.304958) (xy 8.414157 -306.304958) (xy 8.343283 -306.296972)
			(xy 8.273748 -306.281102) (xy 8.206428 -306.257545) (xy 8.142169 -306.2266) (xy 8.081778 -306.188654)
			(xy 8.026016 -306.144185) (xy 7.975583 -306.093752) (xy 7.931114 -306.03799) (xy 7.893168 -305.977599)
			(xy 7.862223 -305.91334) (xy 7.838666 -305.84602) (xy 7.822796 -305.776485) (xy 7.81481 -305.705611)
			(xy 2.584966 -305.705611) (xy 2.57698 -305.776485) (xy 2.56111 -305.84602) (xy 2.537553 -305.91334)
			(xy 2.506608 -305.977599) (xy 2.468662 -306.03799) (xy 2.424193 -306.093752) (xy 2.37376 -306.144185)
			(xy 2.317998 -306.188654) (xy 2.257607 -306.2266) (xy 2.193348 -306.257545) (xy 2.126028 -306.281102)
			(xy 2.056493 -306.296972) (xy 1.985619 -306.304958) (xy 1.914297 -306.304958) (xy 1.843423 -306.296972)
			(xy 1.773888 -306.281102) (xy 1.706568 -306.257545) (xy 1.642309 -306.2266) (xy 1.581918 -306.188654)
			(xy 1.526156 -306.144185) (xy 1.475723 -306.093752) (xy 1.431254 -306.03799) (xy 1.393308 -305.977599)
			(xy 1.362363 -305.91334) (xy 1.338806 -305.84602) (xy 1.322936 -305.776485) (xy 1.31495 -305.705611)
			(xy 0.509016 -305.705611) (xy 0.509016 -315.705591) (xy 1.31495 -315.705591) (xy 1.31495 -315.634269)
			(xy 1.322936 -315.563395) (xy 1.338806 -315.49386) (xy 1.362363 -315.42654) (xy 1.393308 -315.362281)
			(xy 1.431254 -315.30189) (xy 1.475723 -315.246128) (xy 1.526156 -315.195695) (xy 1.581918 -315.151226)
			(xy 1.642309 -315.11328) (xy 1.706568 -315.082335) (xy 1.773888 -315.058778) (xy 1.843423 -315.042908)
			(xy 1.914297 -315.034922) (xy 1.949958 -315.034422) (xy 1.985619 -315.034922) (xy 2.056493 -315.042908)
			(xy 2.126028 -315.058778) (xy 2.193348 -315.082335) (xy 2.257607 -315.11328) (xy 2.317998 -315.151226)
			(xy 2.37376 -315.195695) (xy 2.424193 -315.246128) (xy 2.468662 -315.30189) (xy 2.506608 -315.362281)
			(xy 2.537553 -315.42654) (xy 2.56111 -315.49386) (xy 2.57698 -315.563395) (xy 2.584966 -315.634269)
			(xy 2.584966 -315.705591) (xy 2.57698 -315.776465) (xy 2.56111 -315.846) (xy 2.537553 -315.91332)
			(xy 2.506608 -315.977579) (xy 2.468662 -316.03797) (xy 2.424193 -316.093732) (xy 2.37376 -316.144165)
			(xy 2.317998 -316.188634) (xy 2.257607 -316.22658) (xy 2.193348 -316.257525) (xy 2.126028 -316.281082)
			(xy 2.056493 -316.296952) (xy 1.985619 -316.304938) (xy 1.914297 -316.304938) (xy 1.843423 -316.296952)
			(xy 1.773888 -316.281082) (xy 1.706568 -316.257525) (xy 1.642309 -316.22658) (xy 1.581918 -316.188634)
			(xy 1.526156 -316.144165) (xy 1.475723 -316.093732) (xy 1.431254 -316.03797) (xy 1.393308 -315.977579)
			(xy 1.362363 -315.91332) (xy 1.338806 -315.846) (xy 1.322936 -315.776465) (xy 1.31495 -315.705591)
			(xy 0.509016 -315.705591) (xy 0.509016 -317.705587) (xy 1.31495 -317.705587) (xy 1.31495 -317.634265)
			(xy 1.322936 -317.563391) (xy 1.338806 -317.493856) (xy 1.362363 -317.426536) (xy 1.393308 -317.362277)
			(xy 1.431254 -317.301886) (xy 1.475723 -317.246124) (xy 1.526156 -317.195691) (xy 1.581918 -317.151222)
			(xy 1.642309 -317.113276) (xy 1.706568 -317.082331) (xy 1.773888 -317.058774) (xy 1.843423 -317.042904)
			(xy 1.914297 -317.034918) (xy 1.949958 -317.034418) (xy 1.985619 -317.034918) (xy 2.056493 -317.042904)
			(xy 2.126028 -317.058774) (xy 2.193348 -317.082331) (xy 2.257607 -317.113276) (xy 2.317998 -317.151222)
			(xy 2.37376 -317.195691) (xy 2.424193 -317.246124) (xy 2.468662 -317.301886) (xy 2.506608 -317.362277)
			(xy 2.537553 -317.426536) (xy 2.56111 -317.493856) (xy 2.57698 -317.563391) (xy 2.584966 -317.634265)
			(xy 2.584966 -317.705587) (xy 2.57698 -317.776461) (xy 2.56111 -317.845996) (xy 2.537553 -317.913316)
			(xy 2.506608 -317.977575) (xy 2.468662 -318.037966) (xy 2.424193 -318.093728) (xy 2.37376 -318.144161)
			(xy 2.317998 -318.18863) (xy 2.257607 -318.226576) (xy 2.193348 -318.257521) (xy 2.126028 -318.281078)
			(xy 2.056493 -318.296948) (xy 1.985619 -318.304934) (xy 1.914297 -318.304934) (xy 1.843423 -318.296948)
			(xy 1.773888 -318.281078) (xy 1.706568 -318.257521) (xy 1.642309 -318.226576) (xy 1.581918 -318.18863)
			(xy 1.526156 -318.144161) (xy 1.475723 -318.093728) (xy 1.431254 -318.037966) (xy 1.393308 -317.977575)
			(xy 1.362363 -317.913316) (xy 1.338806 -317.845996) (xy 1.322936 -317.776461) (xy 1.31495 -317.705587)
			(xy 0.509016 -317.705587) (xy 0.509016 -318.705585) (xy 3.314946 -318.705585) (xy 3.314946 -318.634263)
			(xy 3.322932 -318.563389) (xy 3.338802 -318.493854) (xy 3.362359 -318.426534) (xy 3.393304 -318.362275)
			(xy 3.43125 -318.301884) (xy 3.475719 -318.246122) (xy 3.526152 -318.195689) (xy 3.581914 -318.15122)
			(xy 3.642305 -318.113274) (xy 3.706564 -318.082329) (xy 3.773884 -318.058772) (xy 3.843419 -318.042902)
			(xy 3.914293 -318.034916) (xy 3.949954 -318.034416) (xy 3.985615 -318.034916) (xy 4.056489 -318.042902)
			(xy 4.126024 -318.058772) (xy 4.193344 -318.082329) (xy 4.257603 -318.113274) (xy 4.317994 -318.15122)
			(xy 4.373756 -318.195689) (xy 4.424189 -318.246122) (xy 4.468658 -318.301884) (xy 4.506604 -318.362275)
			(xy 4.537549 -318.426534) (xy 4.561106 -318.493854) (xy 4.576976 -318.563389) (xy 4.584962 -318.634263)
			(xy 4.584962 -318.705585) (xy 5.814814 -318.705585) (xy 5.814814 -318.634263) (xy 5.8228 -318.563389)
			(xy 5.83867 -318.493854) (xy 5.862227 -318.426534) (xy 5.893172 -318.362275) (xy 5.931118 -318.301884)
			(xy 5.975587 -318.246122) (xy 6.02602 -318.195689) (xy 6.081782 -318.15122) (xy 6.142173 -318.113274)
			(xy 6.206432 -318.082329) (xy 6.273752 -318.058772) (xy 6.343287 -318.042902) (xy 6.414161 -318.034916)
			(xy 6.449822 -318.034416) (xy 6.485483 -318.034916) (xy 6.556357 -318.042902) (xy 6.625892 -318.058772)
			(xy 6.693212 -318.082329) (xy 6.757471 -318.113274) (xy 6.817862 -318.15122) (xy 6.873624 -318.195689)
			(xy 6.924057 -318.246122) (xy 6.968526 -318.301884) (xy 7.006472 -318.362275) (xy 7.037417 -318.426534)
			(xy 7.060974 -318.493854) (xy 7.076844 -318.563389) (xy 7.08483 -318.634263) (xy 7.08483 -318.705585)
			(xy 7.076844 -318.776459) (xy 7.060974 -318.845994) (xy 7.037417 -318.913314) (xy 7.006472 -318.977573)
			(xy 6.968526 -319.037964) (xy 6.924057 -319.093726) (xy 6.873624 -319.144159) (xy 6.817862 -319.188628)
			(xy 6.757471 -319.226574) (xy 6.693212 -319.257519) (xy 6.625892 -319.281076) (xy 6.556357 -319.296946)
			(xy 6.485483 -319.304932) (xy 6.414161 -319.304932) (xy 6.343287 -319.296946) (xy 6.273752 -319.281076)
			(xy 6.206432 -319.257519) (xy 6.142173 -319.226574) (xy 6.081782 -319.188628) (xy 6.02602 -319.144159)
			(xy 5.975587 -319.093726) (xy 5.931118 -319.037964) (xy 5.893172 -318.977573) (xy 5.862227 -318.913314)
			(xy 5.83867 -318.845994) (xy 5.8228 -318.776459) (xy 5.814814 -318.705585) (xy 4.584962 -318.705585)
			(xy 4.576976 -318.776459) (xy 4.561106 -318.845994) (xy 4.537549 -318.913314) (xy 4.506604 -318.977573)
			(xy 4.468658 -319.037964) (xy 4.424189 -319.093726) (xy 4.373756 -319.144159) (xy 4.317994 -319.188628)
			(xy 4.257603 -319.226574) (xy 4.193344 -319.257519) (xy 4.126024 -319.281076) (xy 4.056489 -319.296946)
			(xy 3.985615 -319.304932) (xy 3.914293 -319.304932) (xy 3.843419 -319.296946) (xy 3.773884 -319.281076)
			(xy 3.706564 -319.257519) (xy 3.642305 -319.226574) (xy 3.581914 -319.188628) (xy 3.526152 -319.144159)
			(xy 3.475719 -319.093726) (xy 3.43125 -319.037964) (xy 3.393304 -318.977573) (xy 3.362359 -318.913314)
			(xy 3.338802 -318.845994) (xy 3.322932 -318.776459) (xy 3.314946 -318.705585) (xy 0.509016 -318.705585)
			(xy 0.509016 -319.705583) (xy 1.31495 -319.705583) (xy 1.31495 -319.634261) (xy 1.322936 -319.563387)
			(xy 1.338806 -319.493852) (xy 1.362363 -319.426532) (xy 1.393308 -319.362273) (xy 1.431254 -319.301882)
			(xy 1.475723 -319.24612) (xy 1.526156 -319.195687) (xy 1.581918 -319.151218) (xy 1.642309 -319.113272)
			(xy 1.706568 -319.082327) (xy 1.773888 -319.05877) (xy 1.843423 -319.0429) (xy 1.914297 -319.034914)
			(xy 1.949958 -319.034414) (xy 1.985619 -319.034914) (xy 2.056493 -319.0429) (xy 2.126028 -319.05877)
			(xy 2.193348 -319.082327) (xy 2.257607 -319.113272) (xy 2.317998 -319.151218) (xy 2.37376 -319.195687)
			(xy 2.424193 -319.24612) (xy 2.468662 -319.301882) (xy 2.506608 -319.362273) (xy 2.537553 -319.426532)
			(xy 2.56111 -319.493852) (xy 2.57698 -319.563387) (xy 2.584966 -319.634261) (xy 2.584966 -319.705583)
			(xy 7.81481 -319.705583) (xy 7.81481 -319.634261) (xy 7.822796 -319.563387) (xy 7.838666 -319.493852)
			(xy 7.862223 -319.426532) (xy 7.893168 -319.362273) (xy 7.931114 -319.301882) (xy 7.975583 -319.24612)
			(xy 8.026016 -319.195687) (xy 8.081778 -319.151218) (xy 8.142169 -319.113272) (xy 8.206428 -319.082327)
			(xy 8.273748 -319.05877) (xy 8.343283 -319.0429) (xy 8.414157 -319.034914) (xy 8.449818 -319.034414)
			(xy 8.485479 -319.034914) (xy 8.556353 -319.0429) (xy 8.625888 -319.05877) (xy 8.693208 -319.082327)
			(xy 8.757467 -319.113272) (xy 8.817858 -319.151218) (xy 8.87362 -319.195687) (xy 8.924053 -319.24612)
			(xy 8.968522 -319.301882) (xy 9.006468 -319.362273) (xy 9.037413 -319.426532) (xy 9.06097 -319.493852)
			(xy 9.07684 -319.563387) (xy 9.084826 -319.634261) (xy 9.084826 -319.705583) (xy 9.07684 -319.776457)
			(xy 9.06097 -319.845992) (xy 9.037413 -319.913312) (xy 9.006468 -319.977571) (xy 8.968522 -320.037962)
			(xy 8.924053 -320.093724) (xy 8.87362 -320.144157) (xy 8.817858 -320.188626) (xy 8.757467 -320.226572)
			(xy 8.693208 -320.257517) (xy 8.625888 -320.281074) (xy 8.556353 -320.296944) (xy 8.485479 -320.30493)
			(xy 8.414157 -320.30493) (xy 8.343283 -320.296944) (xy 8.273748 -320.281074) (xy 8.206428 -320.257517)
			(xy 8.142169 -320.226572) (xy 8.081778 -320.188626) (xy 8.026016 -320.144157) (xy 7.975583 -320.093724)
			(xy 7.931114 -320.037962) (xy 7.893168 -319.977571) (xy 7.862223 -319.913312) (xy 7.838666 -319.845992)
			(xy 7.822796 -319.776457) (xy 7.81481 -319.705583) (xy 2.584966 -319.705583) (xy 2.57698 -319.776457)
			(xy 2.56111 -319.845992) (xy 2.537553 -319.913312) (xy 2.506608 -319.977571) (xy 2.468662 -320.037962)
			(xy 2.424193 -320.093724) (xy 2.37376 -320.144157) (xy 2.317998 -320.188626) (xy 2.257607 -320.226572)
			(xy 2.193348 -320.257517) (xy 2.126028 -320.281074) (xy 2.056493 -320.296944) (xy 1.985619 -320.30493)
			(xy 1.914297 -320.30493) (xy 1.843423 -320.296944) (xy 1.773888 -320.281074) (xy 1.706568 -320.257517)
			(xy 1.642309 -320.226572) (xy 1.581918 -320.188626) (xy 1.526156 -320.144157) (xy 1.475723 -320.093724)
			(xy 1.431254 -320.037962) (xy 1.393308 -319.977571) (xy 1.362363 -319.913312) (xy 1.338806 -319.845992)
			(xy 1.322936 -319.776457) (xy 1.31495 -319.705583) (xy 0.509016 -319.705583) (xy 0.509016 -320.705581)
			(xy 3.314946 -320.705581) (xy 3.314946 -320.634259) (xy 3.322932 -320.563385) (xy 3.338802 -320.49385)
			(xy 3.362359 -320.42653) (xy 3.393304 -320.362271) (xy 3.43125 -320.30188) (xy 3.475719 -320.246118)
			(xy 3.526152 -320.195685) (xy 3.581914 -320.151216) (xy 3.642305 -320.11327) (xy 3.706564 -320.082325)
			(xy 3.773884 -320.058768) (xy 3.843419 -320.042898) (xy 3.914293 -320.034912) (xy 3.949954 -320.034412)
			(xy 3.985615 -320.034912) (xy 4.056489 -320.042898) (xy 4.126024 -320.058768) (xy 4.193344 -320.082325)
			(xy 4.257603 -320.11327) (xy 4.317994 -320.151216) (xy 4.373756 -320.195685) (xy 4.424189 -320.246118)
			(xy 4.468658 -320.30188) (xy 4.506604 -320.362271) (xy 4.537549 -320.42653) (xy 4.561106 -320.49385)
			(xy 4.576976 -320.563385) (xy 4.584962 -320.634259) (xy 4.584962 -320.705581) (xy 4.576976 -320.776455)
			(xy 4.561106 -320.84599) (xy 4.537549 -320.91331) (xy 4.506604 -320.977569) (xy 4.468658 -321.03796)
			(xy 4.424189 -321.093722) (xy 4.373756 -321.144155) (xy 4.317994 -321.188624) (xy 4.257603 -321.22657)
			(xy 4.193344 -321.257515) (xy 4.126024 -321.281072) (xy 4.056489 -321.296942) (xy 3.985615 -321.304928)
			(xy 3.914293 -321.304928) (xy 3.843419 -321.296942) (xy 3.773884 -321.281072) (xy 3.706564 -321.257515)
			(xy 3.642305 -321.22657) (xy 3.581914 -321.188624) (xy 3.526152 -321.144155) (xy 3.475719 -321.093722)
			(xy 3.43125 -321.03796) (xy 3.393304 -320.977569) (xy 3.362359 -320.91331) (xy 3.338802 -320.84599)
			(xy 3.322932 -320.776455) (xy 3.314946 -320.705581) (xy 0.509016 -320.705581) (xy 0.509016 -321.705579)
			(xy 7.81481 -321.705579) (xy 7.81481 -321.634257) (xy 7.822796 -321.563383) (xy 7.838666 -321.493848)
			(xy 7.862223 -321.426528) (xy 7.893168 -321.362269) (xy 7.931114 -321.301878) (xy 7.975583 -321.246116)
			(xy 8.026016 -321.195683) (xy 8.081778 -321.151214) (xy 8.142169 -321.113268) (xy 8.206428 -321.082323)
			(xy 8.273748 -321.058766) (xy 8.343283 -321.042896) (xy 8.414157 -321.03491) (xy 8.449818 -321.03441)
			(xy 8.485479 -321.03491) (xy 8.556353 -321.042896) (xy 8.625888 -321.058766) (xy 8.693208 -321.082323)
			(xy 8.757467 -321.113268) (xy 8.817858 -321.151214) (xy 8.87362 -321.195683) (xy 8.924053 -321.246116)
			(xy 8.968522 -321.301878) (xy 9.006468 -321.362269) (xy 9.037413 -321.426528) (xy 9.06097 -321.493848)
			(xy 9.07684 -321.563383) (xy 9.084826 -321.634257) (xy 9.084826 -321.705579) (xy 9.07684 -321.776453)
			(xy 9.06097 -321.845988) (xy 9.037413 -321.913308) (xy 9.006468 -321.977567) (xy 8.968522 -322.037958)
			(xy 8.924053 -322.09372) (xy 8.87362 -322.144153) (xy 8.817858 -322.188622) (xy 8.757467 -322.226568)
			(xy 8.693208 -322.257513) (xy 8.625888 -322.28107) (xy 8.556353 -322.29694) (xy 8.485479 -322.304926)
			(xy 8.414157 -322.304926) (xy 8.343283 -322.29694) (xy 8.273748 -322.28107) (xy 8.206428 -322.257513)
			(xy 8.142169 -322.226568) (xy 8.081778 -322.188622) (xy 8.026016 -322.144153) (xy 7.975583 -322.09372)
			(xy 7.931114 -322.037958) (xy 7.893168 -321.977567) (xy 7.862223 -321.913308) (xy 7.838666 -321.845988)
			(xy 7.822796 -321.776453) (xy 7.81481 -321.705579) (xy 0.509016 -321.705579) (xy 0.509016 -322.705577)
			(xy 3.314946 -322.705577) (xy 3.314946 -322.634255) (xy 3.322932 -322.563381) (xy 3.338802 -322.493846)
			(xy 3.362359 -322.426526) (xy 3.393304 -322.362267) (xy 3.43125 -322.301876) (xy 3.475719 -322.246114)
			(xy 3.526152 -322.195681) (xy 3.581914 -322.151212) (xy 3.642305 -322.113266) (xy 3.706564 -322.082321)
			(xy 3.773884 -322.058764) (xy 3.843419 -322.042894) (xy 3.914293 -322.034908) (xy 3.949954 -322.034408)
			(xy 3.985615 -322.034908) (xy 4.056489 -322.042894) (xy 4.126024 -322.058764) (xy 4.193344 -322.082321)
			(xy 4.257603 -322.113266) (xy 4.317994 -322.151212) (xy 4.373756 -322.195681) (xy 4.424189 -322.246114)
			(xy 4.468658 -322.301876) (xy 4.506604 -322.362267) (xy 4.537549 -322.426526) (xy 4.561106 -322.493846)
			(xy 4.576976 -322.563381) (xy 4.584962 -322.634255) (xy 4.584962 -322.705577) (xy 4.576976 -322.776451)
			(xy 4.561106 -322.845986) (xy 4.537549 -322.913306) (xy 4.506604 -322.977565) (xy 4.468658 -323.037956)
			(xy 4.424189 -323.093718) (xy 4.373756 -323.144151) (xy 4.317994 -323.18862) (xy 4.257603 -323.226566)
			(xy 4.193344 -323.257511) (xy 4.126024 -323.281068) (xy 4.056489 -323.296938) (xy 3.985615 -323.304924)
			(xy 3.914293 -323.304924) (xy 3.843419 -323.296938) (xy 3.773884 -323.281068) (xy 3.706564 -323.257511)
			(xy 3.642305 -323.226566) (xy 3.581914 -323.18862) (xy 3.526152 -323.144151) (xy 3.475719 -323.093718)
			(xy 3.43125 -323.037956) (xy 3.393304 -322.977565) (xy 3.362359 -322.913306) (xy 3.338802 -322.845986)
			(xy 3.322932 -322.776451) (xy 3.314946 -322.705577) (xy 0.509016 -322.705577) (xy 0.509016 -323.705575)
			(xy 1.31495 -323.705575) (xy 1.31495 -323.634253) (xy 1.322936 -323.563379) (xy 1.338806 -323.493844)
			(xy 1.362363 -323.426524) (xy 1.393308 -323.362265) (xy 1.431254 -323.301874) (xy 1.475723 -323.246112)
			(xy 1.526156 -323.195679) (xy 1.581918 -323.15121) (xy 1.642309 -323.113264) (xy 1.706568 -323.082319)
			(xy 1.773888 -323.058762) (xy 1.843423 -323.042892) (xy 1.914297 -323.034906) (xy 1.949958 -323.034406)
			(xy 1.985619 -323.034906) (xy 2.056493 -323.042892) (xy 2.126028 -323.058762) (xy 2.193348 -323.082319)
			(xy 2.257607 -323.113264) (xy 2.317998 -323.15121) (xy 2.37376 -323.195679) (xy 2.424193 -323.246112)
			(xy 2.468662 -323.301874) (xy 2.506608 -323.362265) (xy 2.537553 -323.426524) (xy 2.56111 -323.493844)
			(xy 2.57698 -323.563379) (xy 2.584966 -323.634253) (xy 2.584966 -323.705575) (xy 7.81481 -323.705575)
			(xy 7.81481 -323.634253) (xy 7.822796 -323.563379) (xy 7.838666 -323.493844) (xy 7.862223 -323.426524)
			(xy 7.893168 -323.362265) (xy 7.931114 -323.301874) (xy 7.975583 -323.246112) (xy 8.026016 -323.195679)
			(xy 8.081778 -323.15121) (xy 8.142169 -323.113264) (xy 8.206428 -323.082319) (xy 8.273748 -323.058762)
			(xy 8.343283 -323.042892) (xy 8.414157 -323.034906) (xy 8.449818 -323.034406) (xy 8.485479 -323.034906)
			(xy 8.556353 -323.042892) (xy 8.625888 -323.058762) (xy 8.693208 -323.082319) (xy 8.757467 -323.113264)
			(xy 8.817858 -323.15121) (xy 8.87362 -323.195679) (xy 8.924053 -323.246112) (xy 8.968522 -323.301874)
			(xy 9.006468 -323.362265) (xy 9.037413 -323.426524) (xy 9.06097 -323.493844) (xy 9.07684 -323.563379)
			(xy 9.084826 -323.634253) (xy 9.084826 -323.705575) (xy 9.07684 -323.776449) (xy 9.06097 -323.845984)
			(xy 9.037413 -323.913304) (xy 9.006468 -323.977563) (xy 8.968522 -324.037954) (xy 8.924053 -324.093716)
			(xy 8.87362 -324.144149) (xy 8.817858 -324.188618) (xy 8.757467 -324.226564) (xy 8.693208 -324.257509)
			(xy 8.625888 -324.281066) (xy 8.556353 -324.296936) (xy 8.485479 -324.304922) (xy 8.414157 -324.304922)
			(xy 8.343283 -324.296936) (xy 8.273748 -324.281066) (xy 8.206428 -324.257509) (xy 8.142169 -324.226564)
			(xy 8.081778 -324.188618) (xy 8.026016 -324.144149) (xy 7.975583 -324.093716) (xy 7.931114 -324.037954)
			(xy 7.893168 -323.977563) (xy 7.862223 -323.913304) (xy 7.838666 -323.845984) (xy 7.822796 -323.776449)
			(xy 7.81481 -323.705575) (xy 2.584966 -323.705575) (xy 2.57698 -323.776449) (xy 2.56111 -323.845984)
			(xy 2.537553 -323.913304) (xy 2.506608 -323.977563) (xy 2.468662 -324.037954) (xy 2.424193 -324.093716)
			(xy 2.37376 -324.144149) (xy 2.317998 -324.188618) (xy 2.257607 -324.226564) (xy 2.193348 -324.257509)
			(xy 2.126028 -324.281066) (xy 2.056493 -324.296936) (xy 1.985619 -324.304922) (xy 1.914297 -324.304922)
			(xy 1.843423 -324.296936) (xy 1.773888 -324.281066) (xy 1.706568 -324.257509) (xy 1.642309 -324.226564)
			(xy 1.581918 -324.188618) (xy 1.526156 -324.144149) (xy 1.475723 -324.093716) (xy 1.431254 -324.037954)
			(xy 1.393308 -323.977563) (xy 1.362363 -323.913304) (xy 1.338806 -323.845984) (xy 1.322936 -323.776449)
			(xy 1.31495 -323.705575) (xy 0.509016 -323.705575) (xy 0.509016 -324.705573) (xy 3.314946 -324.705573)
			(xy 3.314946 -324.634251) (xy 3.322932 -324.563377) (xy 3.338802 -324.493842) (xy 3.362359 -324.426522)
			(xy 3.393304 -324.362263) (xy 3.43125 -324.301872) (xy 3.475719 -324.24611) (xy 3.526152 -324.195677)
			(xy 3.581914 -324.151208) (xy 3.642305 -324.113262) (xy 3.706564 -324.082317) (xy 3.773884 -324.05876)
			(xy 3.843419 -324.04289) (xy 3.914293 -324.034904) (xy 3.949954 -324.034404) (xy 3.985615 -324.034904)
			(xy 4.056489 -324.04289) (xy 4.126024 -324.05876) (xy 4.193344 -324.082317) (xy 4.257603 -324.113262)
			(xy 4.317994 -324.151208) (xy 4.373756 -324.195677) (xy 4.424189 -324.24611) (xy 4.468658 -324.301872)
			(xy 4.506604 -324.362263) (xy 4.537549 -324.426522) (xy 4.561106 -324.493842) (xy 4.576976 -324.563377)
			(xy 4.584962 -324.634251) (xy 4.584962 -324.705573) (xy 5.814814 -324.705573) (xy 5.814814 -324.634251)
			(xy 5.8228 -324.563377) (xy 5.83867 -324.493842) (xy 5.862227 -324.426522) (xy 5.893172 -324.362263)
			(xy 5.931118 -324.301872) (xy 5.975587 -324.24611) (xy 6.02602 -324.195677) (xy 6.081782 -324.151208)
			(xy 6.142173 -324.113262) (xy 6.206432 -324.082317) (xy 6.273752 -324.05876) (xy 6.343287 -324.04289)
			(xy 6.414161 -324.034904) (xy 6.449822 -324.034404) (xy 6.485483 -324.034904) (xy 6.556357 -324.04289)
			(xy 6.625892 -324.05876) (xy 6.693212 -324.082317) (xy 6.757471 -324.113262) (xy 6.817862 -324.151208)
			(xy 6.873624 -324.195677) (xy 6.924057 -324.24611) (xy 6.968526 -324.301872) (xy 7.006472 -324.362263)
			(xy 7.037417 -324.426522) (xy 7.060974 -324.493842) (xy 7.076844 -324.563377) (xy 7.08483 -324.634251)
			(xy 7.08483 -324.705573) (xy 7.076844 -324.776447) (xy 7.060974 -324.845982) (xy 7.037417 -324.913302)
			(xy 7.006472 -324.977561) (xy 6.968526 -325.037952) (xy 6.924057 -325.093714) (xy 6.873624 -325.144147)
			(xy 6.817862 -325.188616) (xy 6.757471 -325.226562) (xy 6.693212 -325.257507) (xy 6.625892 -325.281064)
			(xy 6.556357 -325.296934) (xy 6.485483 -325.30492) (xy 6.414161 -325.30492) (xy 6.343287 -325.296934)
			(xy 6.273752 -325.281064) (xy 6.206432 -325.257507) (xy 6.142173 -325.226562) (xy 6.081782 -325.188616)
			(xy 6.02602 -325.144147) (xy 5.975587 -325.093714) (xy 5.931118 -325.037952) (xy 5.893172 -324.977561)
			(xy 5.862227 -324.913302) (xy 5.83867 -324.845982) (xy 5.8228 -324.776447) (xy 5.814814 -324.705573)
			(xy 4.584962 -324.705573) (xy 4.576976 -324.776447) (xy 4.561106 -324.845982) (xy 4.537549 -324.913302)
			(xy 4.506604 -324.977561) (xy 4.468658 -325.037952) (xy 4.424189 -325.093714) (xy 4.373756 -325.144147)
			(xy 4.317994 -325.188616) (xy 4.257603 -325.226562) (xy 4.193344 -325.257507) (xy 4.126024 -325.281064)
			(xy 4.056489 -325.296934) (xy 3.985615 -325.30492) (xy 3.914293 -325.30492) (xy 3.843419 -325.296934)
			(xy 3.773884 -325.281064) (xy 3.706564 -325.257507) (xy 3.642305 -325.226562) (xy 3.581914 -325.188616)
			(xy 3.526152 -325.144147) (xy 3.475719 -325.093714) (xy 3.43125 -325.037952) (xy 3.393304 -324.977561)
			(xy 3.362359 -324.913302) (xy 3.338802 -324.845982) (xy 3.322932 -324.776447) (xy 3.314946 -324.705573)
			(xy 0.509016 -324.705573) (xy 0.509016 -325.705571) (xy 7.81481 -325.705571) (xy 7.81481 -325.634249)
			(xy 7.822796 -325.563375) (xy 7.838666 -325.49384) (xy 7.862223 -325.42652) (xy 7.893168 -325.362261)
			(xy 7.931114 -325.30187) (xy 7.975583 -325.246108) (xy 8.026016 -325.195675) (xy 8.081778 -325.151206)
			(xy 8.142169 -325.11326) (xy 8.206428 -325.082315) (xy 8.273748 -325.058758) (xy 8.343283 -325.042888)
			(xy 8.414157 -325.034902) (xy 8.449818 -325.034402) (xy 8.485479 -325.034902) (xy 8.556353 -325.042888)
			(xy 8.625888 -325.058758) (xy 8.693208 -325.082315) (xy 8.757467 -325.11326) (xy 8.817858 -325.151206)
			(xy 8.87362 -325.195675) (xy 8.924053 -325.246108) (xy 8.968522 -325.30187) (xy 9.006468 -325.362261)
			(xy 9.037413 -325.42652) (xy 9.06097 -325.49384) (xy 9.07684 -325.563375) (xy 9.084826 -325.634249)
			(xy 9.084826 -325.705571) (xy 9.07684 -325.776445) (xy 9.06097 -325.84598) (xy 9.037413 -325.9133)
			(xy 9.006468 -325.977559) (xy 8.968522 -326.03795) (xy 8.924053 -326.093712) (xy 8.87362 -326.144145)
			(xy 8.817858 -326.188614) (xy 8.757467 -326.22656) (xy 8.693208 -326.257505) (xy 8.625888 -326.281062)
			(xy 8.556353 -326.296932) (xy 8.485479 -326.304918) (xy 8.414157 -326.304918) (xy 8.343283 -326.296932)
			(xy 8.273748 -326.281062) (xy 8.206428 -326.257505) (xy 8.142169 -326.22656) (xy 8.081778 -326.188614)
			(xy 8.026016 -326.144145) (xy 7.975583 -326.093712) (xy 7.931114 -326.03795) (xy 7.893168 -325.977559)
			(xy 7.862223 -325.9133) (xy 7.838666 -325.84598) (xy 7.822796 -325.776445) (xy 7.81481 -325.705571)
			(xy 0.509016 -325.705571) (xy 0.509016 -337.705547) (xy 1.31495 -337.705547) (xy 1.31495 -337.634225)
			(xy 1.322936 -337.563351) (xy 1.338806 -337.493816) (xy 1.362363 -337.426496) (xy 1.393308 -337.362237)
			(xy 1.431254 -337.301846) (xy 1.475723 -337.246084) (xy 1.526156 -337.195651) (xy 1.581918 -337.151182)
			(xy 1.642309 -337.113236) (xy 1.706568 -337.082291) (xy 1.773888 -337.058734) (xy 1.843423 -337.042864)
			(xy 1.914297 -337.034878) (xy 1.949958 -337.034378) (xy 1.985619 -337.034878) (xy 2.056493 -337.042864)
			(xy 2.126028 -337.058734) (xy 2.193348 -337.082291) (xy 2.257607 -337.113236) (xy 2.317998 -337.151182)
			(xy 2.37376 -337.195651) (xy 2.424193 -337.246084) (xy 2.468662 -337.301846) (xy 2.506608 -337.362237)
			(xy 2.537553 -337.426496) (xy 2.56111 -337.493816) (xy 2.57698 -337.563351) (xy 2.584966 -337.634225)
			(xy 2.584966 -337.705547) (xy 2.57698 -337.776421) (xy 2.56111 -337.845956) (xy 2.537553 -337.913276)
			(xy 2.506608 -337.977535) (xy 2.468662 -338.037926) (xy 2.424193 -338.093688) (xy 2.37376 -338.144121)
			(xy 2.317998 -338.18859) (xy 2.257607 -338.226536) (xy 2.193348 -338.257481) (xy 2.126028 -338.281038)
			(xy 2.056493 -338.296908) (xy 1.985619 -338.304894) (xy 1.914297 -338.304894) (xy 1.843423 -338.296908)
			(xy 1.773888 -338.281038) (xy 1.706568 -338.257481) (xy 1.642309 -338.226536) (xy 1.581918 -338.18859)
			(xy 1.526156 -338.144121) (xy 1.475723 -338.093688) (xy 1.431254 -338.037926) (xy 1.393308 -337.977535)
			(xy 1.362363 -337.913276) (xy 1.338806 -337.845956) (xy 1.322936 -337.776421) (xy 1.31495 -337.705547)
			(xy 0.509016 -337.705547) (xy 0.509016 -339.705543) (xy 1.31495 -339.705543) (xy 1.31495 -339.634221)
			(xy 1.322936 -339.563347) (xy 1.338806 -339.493812) (xy 1.362363 -339.426492) (xy 1.393308 -339.362233)
			(xy 1.431254 -339.301842) (xy 1.475723 -339.24608) (xy 1.526156 -339.195647) (xy 1.581918 -339.151178)
			(xy 1.642309 -339.113232) (xy 1.706568 -339.082287) (xy 1.773888 -339.05873) (xy 1.843423 -339.04286)
			(xy 1.914297 -339.034874) (xy 1.949958 -339.034374) (xy 1.985619 -339.034874) (xy 2.056493 -339.04286)
			(xy 2.126028 -339.05873) (xy 2.193348 -339.082287) (xy 2.257607 -339.113232) (xy 2.317998 -339.151178)
			(xy 2.37376 -339.195647) (xy 2.424193 -339.24608) (xy 2.468662 -339.301842) (xy 2.506608 -339.362233)
			(xy 2.537553 -339.426492) (xy 2.56111 -339.493812) (xy 2.57698 -339.563347) (xy 2.584966 -339.634221)
			(xy 2.584966 -339.705543) (xy 2.57698 -339.776417) (xy 2.56111 -339.845952) (xy 2.537553 -339.913272)
			(xy 2.506608 -339.977531) (xy 2.468662 -340.037922) (xy 2.424193 -340.093684) (xy 2.37376 -340.144117)
			(xy 2.317998 -340.188586) (xy 2.257607 -340.226532) (xy 2.193348 -340.257477) (xy 2.126028 -340.281034)
			(xy 2.056493 -340.296904) (xy 1.985619 -340.30489) (xy 1.914297 -340.30489) (xy 1.843423 -340.296904)
			(xy 1.773888 -340.281034) (xy 1.706568 -340.257477) (xy 1.642309 -340.226532) (xy 1.581918 -340.188586)
			(xy 1.526156 -340.144117) (xy 1.475723 -340.093684) (xy 1.431254 -340.037922) (xy 1.393308 -339.977531)
			(xy 1.362363 -339.913272) (xy 1.338806 -339.845952) (xy 1.322936 -339.776417) (xy 1.31495 -339.705543)
			(xy 0.509016 -339.705543) (xy 0.509016 -343.705535) (xy 1.31495 -343.705535) (xy 1.31495 -343.634213)
			(xy 1.322936 -343.563339) (xy 1.338806 -343.493804) (xy 1.362363 -343.426484) (xy 1.393308 -343.362225)
			(xy 1.431254 -343.301834) (xy 1.475723 -343.246072) (xy 1.526156 -343.195639) (xy 1.581918 -343.15117)
			(xy 1.642309 -343.113224) (xy 1.706568 -343.082279) (xy 1.773888 -343.058722) (xy 1.843423 -343.042852)
			(xy 1.914297 -343.034866) (xy 1.949958 -343.034366) (xy 1.985619 -343.034866) (xy 2.056493 -343.042852)
			(xy 2.126028 -343.058722) (xy 2.193348 -343.082279) (xy 2.257607 -343.113224) (xy 2.317998 -343.15117)
			(xy 2.37376 -343.195639) (xy 2.424193 -343.246072) (xy 2.468662 -343.301834) (xy 2.506608 -343.362225)
			(xy 2.537553 -343.426484) (xy 2.56111 -343.493804) (xy 2.57698 -343.563339) (xy 2.584966 -343.634213)
			(xy 2.584966 -343.705535) (xy 2.57698 -343.776409) (xy 2.56111 -343.845944) (xy 2.537553 -343.913264)
			(xy 2.506608 -343.977523) (xy 2.468662 -344.037914) (xy 2.424193 -344.093676) (xy 2.37376 -344.144109)
			(xy 2.317998 -344.188578) (xy 2.257607 -344.226524) (xy 2.193348 -344.257469) (xy 2.126028 -344.281026)
			(xy 2.056493 -344.296896) (xy 1.985619 -344.304882) (xy 1.914297 -344.304882) (xy 1.843423 -344.296896)
			(xy 1.773888 -344.281026) (xy 1.706568 -344.257469) (xy 1.642309 -344.226524) (xy 1.581918 -344.188578)
			(xy 1.526156 -344.144109) (xy 1.475723 -344.093676) (xy 1.431254 -344.037914) (xy 1.393308 -343.977523)
			(xy 1.362363 -343.913264) (xy 1.338806 -343.845944) (xy 1.322936 -343.776409) (xy 1.31495 -343.705535)
			(xy 0.509016 -343.705535) (xy 0.509016 -344.705533) (xy 5.814814 -344.705533) (xy 5.814814 -344.634211)
			(xy 5.8228 -344.563337) (xy 5.83867 -344.493802) (xy 5.862227 -344.426482) (xy 5.893172 -344.362223)
			(xy 5.931118 -344.301832) (xy 5.975587 -344.24607) (xy 6.02602 -344.195637) (xy 6.081782 -344.151168)
			(xy 6.142173 -344.113222) (xy 6.206432 -344.082277) (xy 6.273752 -344.05872) (xy 6.343287 -344.04285)
			(xy 6.414161 -344.034864) (xy 6.449822 -344.034364) (xy 6.485483 -344.034864) (xy 6.556357 -344.04285)
			(xy 6.625892 -344.05872) (xy 6.693212 -344.082277) (xy 6.757471 -344.113222) (xy 6.817862 -344.151168)
			(xy 6.873624 -344.195637) (xy 6.924057 -344.24607) (xy 6.968526 -344.301832) (xy 7.006472 -344.362223)
			(xy 7.037417 -344.426482) (xy 7.060974 -344.493802) (xy 7.076844 -344.563337) (xy 7.08483 -344.634211)
			(xy 7.08483 -344.705533) (xy 7.076844 -344.776407) (xy 7.060974 -344.845942) (xy 7.037417 -344.913262)
			(xy 7.006472 -344.977521) (xy 6.968526 -345.037912) (xy 6.924057 -345.093674) (xy 6.873624 -345.144107)
			(xy 6.817862 -345.188576) (xy 6.757471 -345.226522) (xy 6.693212 -345.257467) (xy 6.625892 -345.281024)
			(xy 6.556357 -345.296894) (xy 6.485483 -345.30488) (xy 6.414161 -345.30488) (xy 6.343287 -345.296894)
			(xy 6.273752 -345.281024) (xy 6.206432 -345.257467) (xy 6.142173 -345.226522) (xy 6.081782 -345.188576)
			(xy 6.02602 -345.144107) (xy 5.975587 -345.093674) (xy 5.931118 -345.037912) (xy 5.893172 -344.977521)
			(xy 5.862227 -344.913262) (xy 5.83867 -344.845942) (xy 5.8228 -344.776407) (xy 5.814814 -344.705533)
			(xy 0.509016 -344.705533) (xy 0.509016 -346.705529) (xy 5.814814 -346.705529) (xy 5.814814 -346.634207)
			(xy 5.8228 -346.563333) (xy 5.83867 -346.493798) (xy 5.862227 -346.426478) (xy 5.893172 -346.362219)
			(xy 5.931118 -346.301828) (xy 5.975587 -346.246066) (xy 6.02602 -346.195633) (xy 6.081782 -346.151164)
			(xy 6.142173 -346.113218) (xy 6.206432 -346.082273) (xy 6.273752 -346.058716) (xy 6.343287 -346.042846)
			(xy 6.414161 -346.03486) (xy 6.449822 -346.03436) (xy 6.485483 -346.03486) (xy 6.556357 -346.042846)
			(xy 6.625892 -346.058716) (xy 6.693212 -346.082273) (xy 6.757471 -346.113218) (xy 6.817862 -346.151164)
			(xy 6.873624 -346.195633) (xy 6.924057 -346.246066) (xy 6.968526 -346.301828) (xy 7.006472 -346.362219)
			(xy 7.037417 -346.426478) (xy 7.060974 -346.493798) (xy 7.076844 -346.563333) (xy 7.08483 -346.634207)
			(xy 7.08483 -346.705529) (xy 7.076844 -346.776403) (xy 7.060974 -346.845938) (xy 7.037417 -346.913258)
			(xy 7.006472 -346.977517) (xy 6.968526 -347.037908) (xy 6.924057 -347.09367) (xy 6.873624 -347.144103)
			(xy 6.817862 -347.188572) (xy 6.757471 -347.226518) (xy 6.693212 -347.257463) (xy 6.625892 -347.28102)
			(xy 6.556357 -347.29689) (xy 6.485483 -347.304876) (xy 6.414161 -347.304876) (xy 6.343287 -347.29689)
			(xy 6.273752 -347.28102) (xy 6.206432 -347.257463) (xy 6.142173 -347.226518) (xy 6.081782 -347.188572)
			(xy 6.02602 -347.144103) (xy 5.975587 -347.09367) (xy 5.931118 -347.037908) (xy 5.893172 -346.977517)
			(xy 5.862227 -346.913258) (xy 5.83867 -346.845938) (xy 5.8228 -346.776403) (xy 5.814814 -346.705529)
			(xy 0.509016 -346.705529) (xy 0.509016 -347.705527) (xy 1.31495 -347.705527) (xy 1.31495 -347.634205)
			(xy 1.322936 -347.563331) (xy 1.338806 -347.493796) (xy 1.362363 -347.426476) (xy 1.393308 -347.362217)
			(xy 1.431254 -347.301826) (xy 1.475723 -347.246064) (xy 1.526156 -347.195631) (xy 1.581918 -347.151162)
			(xy 1.642309 -347.113216) (xy 1.706568 -347.082271) (xy 1.773888 -347.058714) (xy 1.843423 -347.042844)
			(xy 1.914297 -347.034858) (xy 1.949958 -347.034358) (xy 1.985619 -347.034858) (xy 2.056493 -347.042844)
			(xy 2.126028 -347.058714) (xy 2.193348 -347.082271) (xy 2.257607 -347.113216) (xy 2.317998 -347.151162)
			(xy 2.37376 -347.195631) (xy 2.424193 -347.246064) (xy 2.468662 -347.301826) (xy 2.506608 -347.362217)
			(xy 2.537553 -347.426476) (xy 2.56111 -347.493796) (xy 2.57698 -347.563331) (xy 2.584966 -347.634205)
			(xy 2.584966 -347.705527) (xy 2.57698 -347.776401) (xy 2.56111 -347.845936) (xy 2.537553 -347.913256)
			(xy 2.506608 -347.977515) (xy 2.468662 -348.037906) (xy 2.424193 -348.093668) (xy 2.37376 -348.144101)
			(xy 2.317998 -348.18857) (xy 2.257607 -348.226516) (xy 2.193348 -348.257461) (xy 2.126028 -348.281018)
			(xy 2.056493 -348.296888) (xy 1.985619 -348.304874) (xy 1.914297 -348.304874) (xy 1.843423 -348.296888)
			(xy 1.773888 -348.281018) (xy 1.706568 -348.257461) (xy 1.642309 -348.226516) (xy 1.581918 -348.18857)
			(xy 1.526156 -348.144101) (xy 1.475723 -348.093668) (xy 1.431254 -348.037906) (xy 1.393308 -347.977515)
			(xy 1.362363 -347.913256) (xy 1.338806 -347.845936) (xy 1.322936 -347.776401) (xy 1.31495 -347.705527)
			(xy 0.509016 -347.705527) (xy 0.509016 -348.705525) (xy 3.314946 -348.705525) (xy 3.314946 -348.634203)
			(xy 3.322932 -348.563329) (xy 3.338802 -348.493794) (xy 3.362359 -348.426474) (xy 3.393304 -348.362215)
			(xy 3.43125 -348.301824) (xy 3.475719 -348.246062) (xy 3.526152 -348.195629) (xy 3.581914 -348.15116)
			(xy 3.642305 -348.113214) (xy 3.706564 -348.082269) (xy 3.773884 -348.058712) (xy 3.843419 -348.042842)
			(xy 3.914293 -348.034856) (xy 3.949954 -348.034356) (xy 3.985615 -348.034856) (xy 4.056489 -348.042842)
			(xy 4.126024 -348.058712) (xy 4.193344 -348.082269) (xy 4.257603 -348.113214) (xy 4.317994 -348.15116)
			(xy 4.373756 -348.195629) (xy 4.424189 -348.246062) (xy 4.468658 -348.301824) (xy 4.506604 -348.362215)
			(xy 4.537549 -348.426474) (xy 4.561106 -348.493794) (xy 4.576976 -348.563329) (xy 4.584962 -348.634203)
			(xy 4.584962 -348.705525) (xy 4.576976 -348.776399) (xy 4.561106 -348.845934) (xy 4.537549 -348.913254)
			(xy 4.506604 -348.977513) (xy 4.468658 -349.037904) (xy 4.424189 -349.093666) (xy 4.373756 -349.144099)
			(xy 4.317994 -349.188568) (xy 4.257603 -349.226514) (xy 4.193344 -349.257459) (xy 4.126024 -349.281016)
			(xy 4.056489 -349.296886) (xy 3.985615 -349.304872) (xy 3.914293 -349.304872) (xy 3.843419 -349.296886)
			(xy 3.773884 -349.281016) (xy 3.706564 -349.257459) (xy 3.642305 -349.226514) (xy 3.581914 -349.188568)
			(xy 3.526152 -349.144099) (xy 3.475719 -349.093666) (xy 3.43125 -349.037904) (xy 3.393304 -348.977513)
			(xy 3.362359 -348.913254) (xy 3.338802 -348.845934) (xy 3.322932 -348.776399) (xy 3.314946 -348.705525)
			(xy 0.509016 -348.705525) (xy 0.509016 -350.705521) (xy 3.314946 -350.705521) (xy 3.314946 -350.634199)
			(xy 3.322932 -350.563325) (xy 3.338802 -350.49379) (xy 3.362359 -350.42647) (xy 3.393304 -350.362211)
			(xy 3.43125 -350.30182) (xy 3.475719 -350.246058) (xy 3.526152 -350.195625) (xy 3.581914 -350.151156)
			(xy 3.642305 -350.11321) (xy 3.706564 -350.082265) (xy 3.773884 -350.058708) (xy 3.843419 -350.042838)
			(xy 3.914293 -350.034852) (xy 3.949954 -350.034352) (xy 3.985615 -350.034852) (xy 4.056489 -350.042838)
			(xy 4.126024 -350.058708) (xy 4.193344 -350.082265) (xy 4.257603 -350.11321) (xy 4.317994 -350.151156)
			(xy 4.373756 -350.195625) (xy 4.424189 -350.246058) (xy 4.468658 -350.30182) (xy 4.506604 -350.362211)
			(xy 4.537549 -350.42647) (xy 4.561106 -350.49379) (xy 4.576976 -350.563325) (xy 4.584962 -350.634199)
			(xy 4.584962 -350.705521) (xy 5.814814 -350.705521) (xy 5.814814 -350.634199) (xy 5.8228 -350.563325)
			(xy 5.83867 -350.49379) (xy 5.862227 -350.42647) (xy 5.893172 -350.362211) (xy 5.931118 -350.30182)
			(xy 5.975587 -350.246058) (xy 6.02602 -350.195625) (xy 6.081782 -350.151156) (xy 6.142173 -350.11321)
			(xy 6.206432 -350.082265) (xy 6.273752 -350.058708) (xy 6.343287 -350.042838) (xy 6.414161 -350.034852)
			(xy 6.449822 -350.034352) (xy 6.485483 -350.034852) (xy 6.556357 -350.042838) (xy 6.625892 -350.058708)
			(xy 6.693212 -350.082265) (xy 6.757471 -350.11321) (xy 6.817862 -350.151156) (xy 6.873624 -350.195625)
			(xy 6.924057 -350.246058) (xy 6.968526 -350.30182) (xy 7.006472 -350.362211) (xy 7.037417 -350.42647)
			(xy 7.060974 -350.49379) (xy 7.076844 -350.563325) (xy 7.08483 -350.634199) (xy 7.08483 -350.705521)
			(xy 7.076844 -350.776395) (xy 7.060974 -350.84593) (xy 7.037417 -350.91325) (xy 7.006472 -350.977509)
			(xy 6.968526 -351.0379) (xy 6.924057 -351.093662) (xy 6.873624 -351.144095) (xy 6.817862 -351.188564)
			(xy 6.757471 -351.22651) (xy 6.693212 -351.257455) (xy 6.625892 -351.281012) (xy 6.556357 -351.296882)
			(xy 6.485483 -351.304868) (xy 6.414161 -351.304868) (xy 6.343287 -351.296882) (xy 6.273752 -351.281012)
			(xy 6.206432 -351.257455) (xy 6.142173 -351.22651) (xy 6.081782 -351.188564) (xy 6.02602 -351.144095)
			(xy 5.975587 -351.093662) (xy 5.931118 -351.0379) (xy 5.893172 -350.977509) (xy 5.862227 -350.91325)
			(xy 5.83867 -350.84593) (xy 5.8228 -350.776395) (xy 5.814814 -350.705521) (xy 4.584962 -350.705521)
			(xy 4.576976 -350.776395) (xy 4.561106 -350.84593) (xy 4.537549 -350.91325) (xy 4.506604 -350.977509)
			(xy 4.468658 -351.0379) (xy 4.424189 -351.093662) (xy 4.373756 -351.144095) (xy 4.317994 -351.188564)
			(xy 4.257603 -351.22651) (xy 4.193344 -351.257455) (xy 4.126024 -351.281012) (xy 4.056489 -351.296882)
			(xy 3.985615 -351.304868) (xy 3.914293 -351.304868) (xy 3.843419 -351.296882) (xy 3.773884 -351.281012)
			(xy 3.706564 -351.257455) (xy 3.642305 -351.22651) (xy 3.581914 -351.188564) (xy 3.526152 -351.144095)
			(xy 3.475719 -351.093662) (xy 3.43125 -351.0379) (xy 3.393304 -350.977509) (xy 3.362359 -350.91325)
			(xy 3.338802 -350.84593) (xy 3.322932 -350.776395) (xy 3.314946 -350.705521) (xy 0.509016 -350.705521)
			(xy 0.509016 -351.705519) (xy 1.31495 -351.705519) (xy 1.31495 -351.634197) (xy 1.322936 -351.563323)
			(xy 1.338806 -351.493788) (xy 1.362363 -351.426468) (xy 1.393308 -351.362209) (xy 1.431254 -351.301818)
			(xy 1.475723 -351.246056) (xy 1.526156 -351.195623) (xy 1.581918 -351.151154) (xy 1.642309 -351.113208)
			(xy 1.706568 -351.082263) (xy 1.773888 -351.058706) (xy 1.843423 -351.042836) (xy 1.914297 -351.03485)
			(xy 1.949958 -351.03435) (xy 1.985619 -351.03485) (xy 2.056493 -351.042836) (xy 2.126028 -351.058706)
			(xy 2.193348 -351.082263) (xy 2.257607 -351.113208) (xy 2.317998 -351.151154) (xy 2.37376 -351.195623)
			(xy 2.424193 -351.246056) (xy 2.468662 -351.301818) (xy 2.506608 -351.362209) (xy 2.537553 -351.426468)
			(xy 2.56111 -351.493788) (xy 2.57698 -351.563323) (xy 2.584966 -351.634197) (xy 2.584966 -351.705519)
			(xy 2.57698 -351.776393) (xy 2.56111 -351.845928) (xy 2.537553 -351.913248) (xy 2.506608 -351.977507)
			(xy 2.468662 -352.037898) (xy 2.424193 -352.09366) (xy 2.37376 -352.144093) (xy 2.317998 -352.188562)
			(xy 2.257607 -352.226508) (xy 2.193348 -352.257453) (xy 2.126028 -352.28101) (xy 2.056493 -352.29688)
			(xy 1.985619 -352.304866) (xy 1.914297 -352.304866) (xy 1.843423 -352.29688) (xy 1.773888 -352.28101)
			(xy 1.706568 -352.257453) (xy 1.642309 -352.226508) (xy 1.581918 -352.188562) (xy 1.526156 -352.144093)
			(xy 1.475723 -352.09366) (xy 1.431254 -352.037898) (xy 1.393308 -351.977507) (xy 1.362363 -351.913248)
			(xy 1.338806 -351.845928) (xy 1.322936 -351.776393) (xy 1.31495 -351.705519) (xy 0.509016 -351.705519)
			(xy 0.509016 -352.705517) (xy 5.814814 -352.705517) (xy 5.814814 -352.634195) (xy 5.8228 -352.563321)
			(xy 5.83867 -352.493786) (xy 5.862227 -352.426466) (xy 5.893172 -352.362207) (xy 5.931118 -352.301816)
			(xy 5.975587 -352.246054) (xy 6.02602 -352.195621) (xy 6.081782 -352.151152) (xy 6.142173 -352.113206)
			(xy 6.206432 -352.082261) (xy 6.273752 -352.058704) (xy 6.343287 -352.042834) (xy 6.414161 -352.034848)
			(xy 6.449822 -352.034348) (xy 6.485483 -352.034848) (xy 6.556357 -352.042834) (xy 6.625892 -352.058704)
			(xy 6.693212 -352.082261) (xy 6.757471 -352.113206) (xy 6.817862 -352.151152) (xy 6.873624 -352.195621)
			(xy 6.924057 -352.246054) (xy 6.968526 -352.301816) (xy 7.006472 -352.362207) (xy 7.037417 -352.426466)
			(xy 7.060974 -352.493786) (xy 7.076844 -352.563321) (xy 7.08483 -352.634195) (xy 7.08483 -352.705517)
			(xy 7.076844 -352.776391) (xy 7.060974 -352.845926) (xy 7.037417 -352.913246) (xy 7.006472 -352.977505)
			(xy 6.968526 -353.037896) (xy 6.924057 -353.093658) (xy 6.873624 -353.144091) (xy 6.817862 -353.18856)
			(xy 6.757471 -353.226506) (xy 6.693212 -353.257451) (xy 6.625892 -353.281008) (xy 6.556357 -353.296878)
			(xy 6.485483 -353.304864) (xy 6.414161 -353.304864) (xy 6.343287 -353.296878) (xy 6.273752 -353.281008)
			(xy 6.206432 -353.257451) (xy 6.142173 -353.226506) (xy 6.081782 -353.18856) (xy 6.02602 -353.144091)
			(xy 5.975587 -353.093658) (xy 5.931118 -353.037896) (xy 5.893172 -352.977505) (xy 5.862227 -352.913246)
			(xy 5.83867 -352.845926) (xy 5.8228 -352.776391) (xy 5.814814 -352.705517) (xy 0.509016 -352.705517)
			(xy 0.509016 -373.875046) (xy 1.29566 -373.875046) (xy 1.299673 -373.779296) (xy 1.311684 -373.684219)
			(xy 1.331609 -373.590479) (xy 1.359308 -373.498736) (xy 1.394587 -373.409632) (xy 1.437198 -373.323793)
			(xy 1.486842 -373.24182) (xy 1.543172 -373.164289) (xy 1.605791 -373.091743) (xy 1.674262 -373.024692)
			(xy 1.748103 -372.963605) (xy 1.826797 -372.908912) (xy 1.909791 -372.860995) (xy 1.996504 -372.820191)
			(xy 2.086327 -372.786786) (xy 2.17863 -372.761015) (xy 2.272766 -372.743057) (xy 2.368075 -372.73304)
			(xy 2.463888 -372.731033) (xy 2.559532 -372.73705) (xy 2.654338 -372.75105) (xy 2.747639 -372.772934)
			(xy 2.838782 -372.802548) (xy 2.927128 -372.839685) (xy 3.012056 -372.884084) (xy 3.092971 -372.935435)
			(xy 3.169305 -372.993375) (xy 3.240524 -373.057501) (xy 3.306126 -373.12736) (xy 3.365653 -373.202464)
			(xy 3.418687 -373.282286) (xy 3.464855 -373.366266) (xy 3.503834 -373.453814) (xy 3.53535 -373.544317)
			(xy 3.559183 -373.63714) (xy 3.575165 -373.731632) (xy 3.583184 -373.827129) (xy 3.583686 -373.875046)
			(xy 3.583184 -373.922963) (xy 3.575165 -374.01846) (xy 3.559183 -374.112952) (xy 3.53535 -374.205775)
			(xy 3.503834 -374.296278) (xy 3.464855 -374.383826) (xy 3.418687 -374.467806) (xy 3.365653 -374.547628)
			(xy 3.306126 -374.622732) (xy 3.240524 -374.692591) (xy 3.169305 -374.756717) (xy 3.092971 -374.814657)
			(xy 3.012056 -374.866008) (xy 2.927128 -374.910407) (xy 2.838782 -374.947544) (xy 2.747639 -374.977158)
			(xy 2.654338 -374.999042) (xy 2.559532 -375.013042) (xy 2.463888 -375.019059) (xy 2.368075 -375.017052)
			(xy 2.272766 -375.007035) (xy 2.17863 -374.989077) (xy 2.086327 -374.963306) (xy 1.996504 -374.929901)
			(xy 1.909791 -374.889097) (xy 1.826797 -374.84118) (xy 1.748103 -374.786487) (xy 1.674262 -374.7254)
			(xy 1.605791 -374.658349) (xy 1.543172 -374.585803) (xy 1.486842 -374.508272) (xy 1.437198 -374.426299)
			(xy 1.394587 -374.34046) (xy 1.359308 -374.251356) (xy 1.331609 -374.159613) (xy 1.311684 -374.065873)
			(xy 1.299673 -373.970796) (xy 1.29566 -373.875046) (xy 0.509016 -373.875046) (xy 0.509016 -380.824994)
			(xy 1.29566 -380.824994) (xy 1.299673 -380.729244) (xy 1.311684 -380.634167) (xy 1.331609 -380.540427)
			(xy 1.359308 -380.448684) (xy 1.394587 -380.35958) (xy 1.437198 -380.273741) (xy 1.486842 -380.191768)
			(xy 1.543172 -380.114237) (xy 1.605791 -380.041691) (xy 1.674262 -379.97464) (xy 1.748103 -379.913553)
			(xy 1.826797 -379.85886) (xy 1.909791 -379.810943) (xy 1.996504 -379.770139) (xy 2.086327 -379.736734)
			(xy 2.17863 -379.710963) (xy 2.272766 -379.693005) (xy 2.368075 -379.682988) (xy 2.463888 -379.680981)
			(xy 2.559532 -379.686998) (xy 2.654338 -379.700998) (xy 2.747639 -379.722882) (xy 2.838782 -379.752496)
			(xy 2.927128 -379.789633) (xy 3.012056 -379.834032) (xy 3.092971 -379.885383) (xy 3.169305 -379.943323)
			(xy 3.240524 -380.007449) (xy 3.306126 -380.077308) (xy 3.365653 -380.152412) (xy 3.418687 -380.232234)
			(xy 3.464855 -380.316214) (xy 3.503834 -380.403762) (xy 3.53535 -380.494265) (xy 3.559183 -380.587088)
			(xy 3.575165 -380.68158) (xy 3.583184 -380.777077) (xy 3.583686 -380.824994) (xy 3.583184 -380.872911)
			(xy 3.575165 -380.968408) (xy 3.559183 -381.0629) (xy 3.53535 -381.155723) (xy 3.503834 -381.246226)
			(xy 3.464855 -381.333774) (xy 3.418687 -381.417754) (xy 3.365653 -381.497576) (xy 3.306126 -381.57268)
			(xy 3.240524 -381.642539) (xy 3.169305 -381.706665) (xy 3.092971 -381.764605) (xy 3.012056 -381.815956)
			(xy 2.927128 -381.860355) (xy 2.838782 -381.897492) (xy 2.747639 -381.927106) (xy 2.654338 -381.94899)
			(xy 2.559532 -381.96299) (xy 2.463888 -381.969007) (xy 2.368075 -381.967) (xy 2.272766 -381.956983)
			(xy 2.17863 -381.939025) (xy 2.086327 -381.913254) (xy 1.996504 -381.879849) (xy 1.909791 -381.839045)
			(xy 1.826797 -381.791128) (xy 1.748103 -381.736435) (xy 1.674262 -381.675348) (xy 1.605791 -381.608297)
			(xy 1.543172 -381.535751) (xy 1.486842 -381.45822) (xy 1.437198 -381.376247) (xy 1.394587 -381.290408)
			(xy 1.359308 -381.201304) (xy 1.331609 -381.109561) (xy 1.311684 -381.015821) (xy 1.299673 -380.920744)
			(xy 1.29566 -380.824994) (xy 0.509016 -380.824994) (xy 0.509016 -399.239994) (xy 2.181354 -399.239994)
			(xy 2.185399 -399.160231) (xy 2.197492 -399.081287) (xy 2.217511 -399.003972) (xy 2.245248 -398.929078)
			(xy 2.28042 -398.857375) (xy 2.322666 -398.789598) (xy 2.371552 -398.726442) (xy 2.426576 -398.668557)
			(xy 2.487175 -398.616535) (xy 2.552725 -398.570911) (xy 2.622555 -398.532152) (xy 2.695948 -398.500657)
			(xy 2.77215 -398.476748) (xy 2.85038 -398.460671) (xy 2.929835 -398.452591) (xy 2.969768 -398.452086)
			(xy 3.009701 -398.452591) (xy 3.089156 -398.460671) (xy 3.167386 -398.476748) (xy 3.243588 -398.500657)
			(xy 3.316981 -398.532152) (xy 3.386811 -398.570911) (xy 3.452361 -398.616535) (xy 3.51296 -398.668557)
			(xy 3.567984 -398.726442) (xy 3.61687 -398.789598) (xy 3.659116 -398.857375) (xy 3.694288 -398.929078)
			(xy 3.722025 -399.003972) (xy 3.742044 -399.081287) (xy 3.754137 -399.160231) (xy 3.758183 -399.239994)
			(xy 4.671316 -399.239994) (xy 4.675361 -399.160231) (xy 4.687454 -399.081287) (xy 4.707473 -399.003972)
			(xy 4.73521 -398.929078) (xy 4.770382 -398.857375) (xy 4.812628 -398.789598) (xy 4.861514 -398.726442)
			(xy 4.916538 -398.668557) (xy 4.977137 -398.616535) (xy 5.042687 -398.570911) (xy 5.112517 -398.532152)
			(xy 5.18591 -398.500657) (xy 5.262112 -398.476748) (xy 5.340342 -398.460671) (xy 5.419797 -398.452591)
			(xy 5.45973 -398.452086) (xy 5.499663 -398.452591) (xy 5.579118 -398.460671) (xy 5.657348 -398.476748)
			(xy 5.73355 -398.500657) (xy 5.806943 -398.532152) (xy 5.876773 -398.570911) (xy 5.942323 -398.616535)
			(xy 6.002922 -398.668557) (xy 6.057946 -398.726442) (xy 6.106832 -398.789598) (xy 6.149078 -398.857375)
			(xy 6.18425 -398.929078) (xy 6.211987 -399.003972) (xy 6.232006 -399.081287) (xy 6.244099 -399.160231)
			(xy 6.248145 -399.239994) (xy 6.244099 -399.319757) (xy 6.232006 -399.398701) (xy 6.211987 -399.476016)
			(xy 6.18425 -399.55091) (xy 6.149078 -399.622613) (xy 6.106832 -399.69039) (xy 6.057946 -399.753546)
			(xy 6.002922 -399.811431) (xy 5.942323 -399.863453) (xy 5.876773 -399.909077) (xy 5.806943 -399.947836)
			(xy 5.73355 -399.979331) (xy 5.657348 -400.00324) (xy 5.579118 -400.019317) (xy 5.499663 -400.027397)
			(xy 5.419797 -400.027397) (xy 5.340342 -400.019317) (xy 5.262112 -400.00324) (xy 5.18591 -399.979331)
			(xy 5.112517 -399.947836) (xy 5.042687 -399.909077) (xy 4.977137 -399.863453) (xy 4.916538 -399.811431)
			(xy 4.861514 -399.753546) (xy 4.812628 -399.69039) (xy 4.770382 -399.622613) (xy 4.73521 -399.55091)
			(xy 4.707473 -399.476016) (xy 4.687454 -399.398701) (xy 4.675361 -399.319757) (xy 4.671316 -399.239994)
			(xy 3.758183 -399.239994) (xy 3.754137 -399.319757) (xy 3.742044 -399.398701) (xy 3.722025 -399.476016)
			(xy 3.694288 -399.55091) (xy 3.659116 -399.622613) (xy 3.61687 -399.69039) (xy 3.567984 -399.753546)
			(xy 3.51296 -399.811431) (xy 3.452361 -399.863453) (xy 3.386811 -399.909077) (xy 3.316981 -399.947836)
			(xy 3.243588 -399.979331) (xy 3.167386 -400.00324) (xy 3.089156 -400.019317) (xy 3.009701 -400.027397)
			(xy 2.929835 -400.027397) (xy 2.85038 -400.019317) (xy 2.77215 -400.00324) (xy 2.695948 -399.979331)
			(xy 2.622555 -399.947836) (xy 2.552725 -399.909077) (xy 2.487175 -399.863453) (xy 2.426576 -399.811431)
			(xy 2.371552 -399.753546) (xy 2.322666 -399.69039) (xy 2.28042 -399.622613) (xy 2.245248 -399.55091)
			(xy 2.217511 -399.476016) (xy 2.197492 -399.398701) (xy 2.185399 -399.319757) (xy 2.181354 -399.239994)
			(xy 0.509016 -399.239994) (xy 0.509016 -403.413036) (xy 1.547863 -403.413036) (xy 1.547863 -403.2869)
			(xy 1.555783 -403.161012) (xy 1.571593 -403.03587) (xy 1.595228 -402.911967) (xy 1.626597 -402.789794)
			(xy 1.665575 -402.669831) (xy 1.712009 -402.552552) (xy 1.765716 -402.43842) (xy 1.826483 -402.327885)
			(xy 1.89407 -402.221385) (xy 1.968211 -402.119338) (xy 2.048614 -402.022148) (xy 2.13496 -401.930198)
			(xy 2.22691 -401.843852) (xy 2.3241 -401.763449) (xy 2.426147 -401.689308) (xy 2.532647 -401.621721)
			(xy 2.643182 -401.560954) (xy 2.757314 -401.507247) (xy 2.874593 -401.460813) (xy 2.994556 -401.421835)
			(xy 3.116729 -401.390466) (xy 3.240632 -401.366831) (xy 3.365774 -401.351021) (xy 3.491662 -401.343101)
			(xy 3.55473 -401.342606) (xy 3.617798 -401.343101) (xy 3.743686 -401.351021) (xy 3.868828 -401.366831)
			(xy 3.992731 -401.390466) (xy 4.114904 -401.421835) (xy 4.234867 -401.460813) (xy 4.352146 -401.507247)
			(xy 4.466278 -401.560954) (xy 4.576813 -401.621721) (xy 4.683313 -401.689308) (xy 4.78536 -401.763449)
			(xy 4.88255 -401.843852) (xy 4.9745 -401.930198) (xy 5.060846 -402.022148) (xy 5.141249 -402.119338)
			(xy 5.21539 -402.221385) (xy 5.282977 -402.327885) (xy 5.343744 -402.43842) (xy 5.397451 -402.552552)
			(xy 5.443885 -402.669831) (xy 5.482863 -402.789794) (xy 5.514232 -402.911967) (xy 5.537867 -403.03587)
			(xy 5.553677 -403.161012) (xy 5.561597 -403.2869) (xy 5.561597 -403.413036) (xy 5.553677 -403.538924)
			(xy 5.537867 -403.664066) (xy 5.514232 -403.787969) (xy 5.482863 -403.910142) (xy 5.443885 -404.030105)
			(xy 5.397451 -404.147384) (xy 5.343744 -404.261516) (xy 5.282977 -404.372051) (xy 5.21539 -404.478551)
			(xy 5.141249 -404.580598) (xy 5.060846 -404.677788) (xy 4.9745 -404.769738) (xy 4.88255 -404.856084)
			(xy 4.78536 -404.936487) (xy 4.683313 -405.010628) (xy 4.576813 -405.078215) (xy 4.466278 -405.138982)
			(xy 4.352146 -405.192689) (xy 4.234867 -405.239123) (xy 4.114904 -405.278101) (xy 3.992731 -405.30947)
			(xy 3.868828 -405.333105) (xy 3.743686 -405.348915) (xy 3.617798 -405.356835) (xy 3.491662 -405.356835)
			(xy 3.365774 -405.348915) (xy 3.240632 -405.333105) (xy 3.116729 -405.30947) (xy 2.994556 -405.278101)
			(xy 2.874593 -405.239123) (xy 2.757314 -405.192689) (xy 2.643182 -405.138982) (xy 2.532647 -405.078215)
			(xy 2.426147 -405.010628) (xy 2.3241 -404.936487) (xy 2.22691 -404.856084) (xy 2.13496 -404.769738)
			(xy 2.048614 -404.677788) (xy 1.968211 -404.580598) (xy 1.89407 -404.478551) (xy 1.826483 -404.372051)
			(xy 1.765716 -404.261516) (xy 1.712009 -404.147384) (xy 1.665575 -404.030105) (xy 1.626597 -403.910142)
			(xy 1.595228 -403.787969) (xy 1.571593 -403.664066) (xy 1.555783 -403.538924) (xy 1.547863 -403.413036)
			(xy 0.509016 -403.413036) (xy 0.509016 -409.699968) (xy 4.036316 -409.699968) (xy 4.040361 -409.620205)
			(xy 4.052454 -409.541261) (xy 4.072473 -409.463946) (xy 4.10021 -409.389052) (xy 4.135382 -409.317349)
			(xy 4.177628 -409.249572) (xy 4.226514 -409.186416) (xy 4.281538 -409.128531) (xy 4.342137 -409.076509)
			(xy 4.407687 -409.030885) (xy 4.477517 -408.992126) (xy 4.55091 -408.960631) (xy 4.627112 -408.936722)
			(xy 4.705342 -408.920645) (xy 4.784797 -408.912565) (xy 4.82473 -408.91206) (xy 4.864663 -408.912565)
			(xy 4.944118 -408.920645) (xy 5.022348 -408.936722) (xy 5.09855 -408.960631) (xy 5.171943 -408.992126)
			(xy 5.241773 -409.030885) (xy 5.307323 -409.076509) (xy 5.367922 -409.128531) (xy 5.422946 -409.186416)
			(xy 5.471832 -409.249572) (xy 5.514078 -409.317349) (xy 5.54925 -409.389052) (xy 5.576987 -409.463946)
			(xy 5.597006 -409.541261) (xy 5.609099 -409.620205) (xy 5.613145 -409.699968) (xy 6.576316 -409.699968)
			(xy 6.580361 -409.620205) (xy 6.592454 -409.541261) (xy 6.612473 -409.463946) (xy 6.64021 -409.389052)
			(xy 6.675382 -409.317349) (xy 6.717628 -409.249572) (xy 6.766514 -409.186416) (xy 6.821538 -409.128531)
			(xy 6.882137 -409.076509) (xy 6.947687 -409.030885) (xy 7.017517 -408.992126) (xy 7.09091 -408.960631)
			(xy 7.167112 -408.936722) (xy 7.245342 -408.920645) (xy 7.324797 -408.912565) (xy 7.36473 -408.91206)
			(xy 7.404663 -408.912565) (xy 7.484118 -408.920645) (xy 7.562348 -408.936722) (xy 7.63855 -408.960631)
			(xy 7.711943 -408.992126) (xy 7.781773 -409.030885) (xy 7.847323 -409.076509) (xy 7.907922 -409.128531)
			(xy 7.962946 -409.186416) (xy 8.011832 -409.249572) (xy 8.054078 -409.317349) (xy 8.08925 -409.389052)
			(xy 8.116987 -409.463946) (xy 8.137006 -409.541261) (xy 8.149099 -409.620205) (xy 8.153145 -409.699968)
			(xy 9.116316 -409.699968) (xy 9.120361 -409.620205) (xy 9.132454 -409.541261) (xy 9.152473 -409.463946)
			(xy 9.18021 -409.389052) (xy 9.215382 -409.317349) (xy 9.257628 -409.249572) (xy 9.306514 -409.186416)
			(xy 9.361538 -409.128531) (xy 9.422137 -409.076509) (xy 9.487687 -409.030885) (xy 9.557517 -408.992126)
			(xy 9.63091 -408.960631) (xy 9.707112 -408.936722) (xy 9.785342 -408.920645) (xy 9.864797 -408.912565)
			(xy 9.90473 -408.91206) (xy 9.944663 -408.912565) (xy 10.024118 -408.920645) (xy 10.102348 -408.936722)
			(xy 10.17855 -408.960631) (xy 10.251943 -408.992126) (xy 10.321773 -409.030885) (xy 10.387323 -409.076509)
			(xy 10.447922 -409.128531) (xy 10.502946 -409.186416) (xy 10.551832 -409.249572) (xy 10.594078 -409.317349)
			(xy 10.62925 -409.389052) (xy 10.656987 -409.463946) (xy 10.677006 -409.541261) (xy 10.689099 -409.620205)
			(xy 10.693145 -409.699968) (xy 10.689099 -409.779731) (xy 10.677006 -409.858675) (xy 10.656987 -409.93599)
			(xy 10.62925 -410.010884) (xy 10.594078 -410.082587) (xy 10.551832 -410.150364) (xy 10.502946 -410.21352)
			(xy 10.447922 -410.271405) (xy 10.387323 -410.323427) (xy 10.321773 -410.369051) (xy 10.251943 -410.40781)
			(xy 10.17855 -410.439305) (xy 10.102348 -410.463214) (xy 10.024118 -410.479291) (xy 9.944663 -410.487371)
			(xy 9.864797 -410.487371) (xy 9.785342 -410.479291) (xy 9.707112 -410.463214) (xy 9.63091 -410.439305)
			(xy 9.557517 -410.40781) (xy 9.487687 -410.369051) (xy 9.422137 -410.323427) (xy 9.361538 -410.271405)
			(xy 9.306514 -410.21352) (xy 9.257628 -410.150364) (xy 9.215382 -410.082587) (xy 9.18021 -410.010884)
			(xy 9.152473 -409.93599) (xy 9.132454 -409.858675) (xy 9.120361 -409.779731) (xy 9.116316 -409.699968)
			(xy 8.153145 -409.699968) (xy 8.149099 -409.779731) (xy 8.137006 -409.858675) (xy 8.116987 -409.93599)
			(xy 8.08925 -410.010884) (xy 8.054078 -410.082587) (xy 8.011832 -410.150364) (xy 7.962946 -410.21352)
			(xy 7.907922 -410.271405) (xy 7.847323 -410.323427) (xy 7.781773 -410.369051) (xy 7.711943 -410.40781)
			(xy 7.63855 -410.439305) (xy 7.562348 -410.463214) (xy 7.484118 -410.479291) (xy 7.404663 -410.487371)
			(xy 7.324797 -410.487371) (xy 7.245342 -410.479291) (xy 7.167112 -410.463214) (xy 7.09091 -410.439305)
			(xy 7.017517 -410.40781) (xy 6.947687 -410.369051) (xy 6.882137 -410.323427) (xy 6.821538 -410.271405)
			(xy 6.766514 -410.21352) (xy 6.717628 -410.150364) (xy 6.675382 -410.082587) (xy 6.64021 -410.010884)
			(xy 6.612473 -409.93599) (xy 6.592454 -409.858675) (xy 6.580361 -409.779731) (xy 6.576316 -409.699968)
			(xy 5.613145 -409.699968) (xy 5.609099 -409.779731) (xy 5.597006 -409.858675) (xy 5.576987 -409.93599)
			(xy 5.54925 -410.010884) (xy 5.514078 -410.082587) (xy 5.471832 -410.150364) (xy 5.422946 -410.21352)
			(xy 5.367922 -410.271405) (xy 5.307323 -410.323427) (xy 5.241773 -410.369051) (xy 5.171943 -410.40781)
			(xy 5.09855 -410.439305) (xy 5.022348 -410.463214) (xy 4.944118 -410.479291) (xy 4.864663 -410.487371)
			(xy 4.784797 -410.487371) (xy 4.705342 -410.479291) (xy 4.627112 -410.463214) (xy 4.55091 -410.439305)
			(xy 4.477517 -410.40781) (xy 4.407687 -410.369051) (xy 4.342137 -410.323427) (xy 4.281538 -410.271405)
			(xy 4.226514 -410.21352) (xy 4.177628 -410.150364) (xy 4.135382 -410.082587) (xy 4.10021 -410.010884)
			(xy 4.072473 -409.93599) (xy 4.052454 -409.858675) (xy 4.040361 -409.779731) (xy 4.036316 -409.699968)
			(xy 0.509016 -409.699968) (xy 0.509016 -412.239968) (xy 5.306316 -412.239968) (xy 5.310361 -412.160205)
			(xy 5.322454 -412.081261) (xy 5.342473 -412.003946) (xy 5.37021 -411.929052) (xy 5.405382 -411.857349)
			(xy 5.447628 -411.789572) (xy 5.496514 -411.726416) (xy 5.551538 -411.668531) (xy 5.612137 -411.616509)
			(xy 5.677687 -411.570885) (xy 5.747517 -411.532126) (xy 5.82091 -411.500631) (xy 5.897112 -411.476722)
			(xy 5.975342 -411.460645) (xy 6.054797 -411.452565) (xy 6.09473 -411.45206) (xy 6.134663 -411.452565)
			(xy 6.214118 -411.460645) (xy 6.292348 -411.476722) (xy 6.36855 -411.500631) (xy 6.441943 -411.532126)
			(xy 6.511773 -411.570885) (xy 6.577323 -411.616509) (xy 6.637922 -411.668531) (xy 6.692946 -411.726416)
			(xy 6.741832 -411.789572) (xy 6.784078 -411.857349) (xy 6.81925 -411.929052) (xy 6.846987 -412.003946)
			(xy 6.867006 -412.081261) (xy 6.879099 -412.160205) (xy 6.883145 -412.239968) (xy 7.846316 -412.239968)
			(xy 7.850361 -412.160205) (xy 7.862454 -412.081261) (xy 7.882473 -412.003946) (xy 7.91021 -411.929052)
			(xy 7.945382 -411.857349) (xy 7.987628 -411.789572) (xy 8.036514 -411.726416) (xy 8.091538 -411.668531)
			(xy 8.152137 -411.616509) (xy 8.217687 -411.570885) (xy 8.287517 -411.532126) (xy 8.36091 -411.500631)
			(xy 8.437112 -411.476722) (xy 8.515342 -411.460645) (xy 8.594797 -411.452565) (xy 8.63473 -411.45206)
			(xy 8.674663 -411.452565) (xy 8.754118 -411.460645) (xy 8.832348 -411.476722) (xy 8.90855 -411.500631)
			(xy 8.981943 -411.532126) (xy 9.051773 -411.570885) (xy 9.117323 -411.616509) (xy 9.177922 -411.668531)
			(xy 9.232946 -411.726416) (xy 9.281832 -411.789572) (xy 9.324078 -411.857349) (xy 9.35925 -411.929052)
			(xy 9.386987 -412.003946) (xy 9.407006 -412.081261) (xy 9.419099 -412.160205) (xy 9.423145 -412.239968)
			(xy 10.386316 -412.239968) (xy 10.390361 -412.160205) (xy 10.402454 -412.081261) (xy 10.422473 -412.003946)
			(xy 10.45021 -411.929052) (xy 10.485382 -411.857349) (xy 10.527628 -411.789572) (xy 10.576514 -411.726416)
			(xy 10.631538 -411.668531) (xy 10.692137 -411.616509) (xy 10.757687 -411.570885) (xy 10.827517 -411.532126)
			(xy 10.90091 -411.500631) (xy 10.977112 -411.476722) (xy 11.055342 -411.460645) (xy 11.134797 -411.452565)
			(xy 11.17473 -411.45206) (xy 11.214663 -411.452565) (xy 11.294118 -411.460645) (xy 11.372348 -411.476722)
			(xy 11.44855 -411.500631) (xy 11.521943 -411.532126) (xy 11.591773 -411.570885) (xy 11.657323 -411.616509)
			(xy 11.717922 -411.668531) (xy 11.772946 -411.726416) (xy 11.821832 -411.789572) (xy 11.864078 -411.857349)
			(xy 11.89925 -411.929052) (xy 11.926987 -412.003946) (xy 11.947006 -412.081261) (xy 11.959099 -412.160205)
			(xy 11.963145 -412.239968) (xy 11.959099 -412.319731) (xy 11.947006 -412.398675) (xy 11.926987 -412.47599)
			(xy 11.89925 -412.550884) (xy 11.864078 -412.622587) (xy 11.821832 -412.690364) (xy 11.772946 -412.75352)
			(xy 11.717922 -412.811405) (xy 11.657323 -412.863427) (xy 11.591773 -412.909051) (xy 11.521943 -412.94781)
			(xy 11.44855 -412.979305) (xy 11.372348 -413.003214) (xy 11.294118 -413.019291) (xy 11.214663 -413.027371)
			(xy 11.134797 -413.027371) (xy 11.055342 -413.019291) (xy 10.977112 -413.003214) (xy 10.90091 -412.979305)
			(xy 10.827517 -412.94781) (xy 10.757687 -412.909051) (xy 10.692137 -412.863427) (xy 10.631538 -412.811405)
			(xy 10.576514 -412.75352) (xy 10.527628 -412.690364) (xy 10.485382 -412.622587) (xy 10.45021 -412.550884)
			(xy 10.422473 -412.47599) (xy 10.402454 -412.398675) (xy 10.390361 -412.319731) (xy 10.386316 -412.239968)
			(xy 9.423145 -412.239968) (xy 9.419099 -412.319731) (xy 9.407006 -412.398675) (xy 9.386987 -412.47599)
			(xy 9.35925 -412.550884) (xy 9.324078 -412.622587) (xy 9.281832 -412.690364) (xy 9.232946 -412.75352)
			(xy 9.177922 -412.811405) (xy 9.117323 -412.863427) (xy 9.051773 -412.909051) (xy 8.981943 -412.94781)
			(xy 8.90855 -412.979305) (xy 8.832348 -413.003214) (xy 8.754118 -413.019291) (xy 8.674663 -413.027371)
			(xy 8.594797 -413.027371) (xy 8.515342 -413.019291) (xy 8.437112 -413.003214) (xy 8.36091 -412.979305)
			(xy 8.287517 -412.94781) (xy 8.217687 -412.909051) (xy 8.152137 -412.863427) (xy 8.091538 -412.811405)
			(xy 8.036514 -412.75352) (xy 7.987628 -412.690364) (xy 7.945382 -412.622587) (xy 7.91021 -412.550884)
			(xy 7.882473 -412.47599) (xy 7.862454 -412.398675) (xy 7.850361 -412.319731) (xy 7.846316 -412.239968)
			(xy 6.883145 -412.239968) (xy 6.879099 -412.319731) (xy 6.867006 -412.398675) (xy 6.846987 -412.47599)
			(xy 6.81925 -412.550884) (xy 6.784078 -412.622587) (xy 6.741832 -412.690364) (xy 6.692946 -412.75352)
			(xy 6.637922 -412.811405) (xy 6.577323 -412.863427) (xy 6.511773 -412.909051) (xy 6.441943 -412.94781)
			(xy 6.36855 -412.979305) (xy 6.292348 -413.003214) (xy 6.214118 -413.019291) (xy 6.134663 -413.027371)
			(xy 6.054797 -413.027371) (xy 5.975342 -413.019291) (xy 5.897112 -413.003214) (xy 5.82091 -412.979305)
			(xy 5.747517 -412.94781) (xy 5.677687 -412.909051) (xy 5.612137 -412.863427) (xy 5.551538 -412.811405)
			(xy 5.496514 -412.75352) (xy 5.447628 -412.690364) (xy 5.405382 -412.622587) (xy 5.37021 -412.550884)
			(xy 5.342473 -412.47599) (xy 5.322454 -412.398675) (xy 5.310361 -412.319731) (xy 5.306316 -412.239968)
			(xy 0.509016 -412.239968) (xy 0.509016 -423.893996) (xy 4.838202 -423.893996) (xy 4.842186 -423.800209)
			(xy 4.854109 -423.707097) (xy 4.873886 -423.615332) (xy 4.901374 -423.525575) (xy 4.936374 -423.438472)
			(xy 4.978636 -423.354651) (xy 5.027854 -423.274716) (xy 5.083673 -423.199243) (xy 5.145692 -423.128776)
			(xy 5.213464 -423.063823) (xy 5.286499 -423.00485) (xy 5.364273 -422.952284) (xy 5.446225 -422.906503)
			(xy 5.531764 -422.867837) (xy 5.620273 -422.836565) (xy 5.711116 -422.812911) (xy 5.803638 -422.797047)
			(xy 5.897172 -422.789086) (xy 5.944108 -422.788588) (xy 5.991044 -422.789086) (xy 6.084578 -422.797047)
			(xy 6.1771 -422.812911) (xy 6.267943 -422.836565) (xy 6.356452 -422.867837) (xy 6.441991 -422.906503)
			(xy 6.523943 -422.952284) (xy 6.601717 -423.00485) (xy 6.674752 -423.063823) (xy 6.742524 -423.128776)
			(xy 6.804543 -423.199243) (xy 6.860362 -423.274716) (xy 6.90958 -423.354651) (xy 6.951842 -423.438472)
			(xy 6.986842 -423.525575) (xy 7.01433 -423.615332) (xy 7.034107 -423.707097) (xy 7.04603 -423.800209)
			(xy 7.050015 -423.893996) (xy 10.338318 -423.893996) (xy 10.342302 -423.800209) (xy 10.354225 -423.707097)
			(xy 10.374002 -423.615332) (xy 10.40149 -423.525575) (xy 10.43649 -423.438472) (xy 10.478752 -423.354651)
			(xy 10.52797 -423.274716) (xy 10.583789 -423.199243) (xy 10.645808 -423.128776) (xy 10.71358 -423.063823)
			(xy 10.786615 -423.00485) (xy 10.864389 -422.952284) (xy 10.946341 -422.906503) (xy 11.03188 -422.867837)
			(xy 11.120389 -422.836565) (xy 11.211232 -422.812911) (xy 11.303754 -422.797047) (xy 11.397288 -422.789086)
			(xy 11.444224 -422.788588) (xy 11.49116 -422.789086) (xy 11.584694 -422.797047) (xy 11.677216 -422.812911)
			(xy 11.768059 -422.836565) (xy 11.856568 -422.867837) (xy 11.942107 -422.906503) (xy 12.024059 -422.952284)
			(xy 12.101833 -423.00485) (xy 12.174868 -423.063823) (xy 12.24264 -423.128776) (xy 12.304659 -423.199243)
			(xy 12.360478 -423.274716) (xy 12.409696 -423.354651) (xy 12.451958 -423.438472) (xy 12.486958 -423.525575)
			(xy 12.514446 -423.615332) (xy 12.534223 -423.707097) (xy 12.546146 -423.800209) (xy 12.550131 -423.893996)
			(xy 12.546146 -423.987783) (xy 12.534223 -424.080895) (xy 12.514446 -424.17266) (xy 12.486958 -424.262417)
			(xy 12.451958 -424.34952) (xy 12.409696 -424.433341) (xy 12.360478 -424.513276) (xy 12.304659 -424.588749)
			(xy 12.24264 -424.659216) (xy 12.174868 -424.724169) (xy 12.101833 -424.783142) (xy 12.024059 -424.835708)
			(xy 11.942107 -424.881489) (xy 11.856568 -424.920155) (xy 11.768059 -424.951427) (xy 11.677216 -424.975081)
			(xy 11.584694 -424.990945) (xy 11.49116 -424.998906) (xy 11.397288 -424.998906) (xy 11.303754 -424.990945)
			(xy 11.211232 -424.975081) (xy 11.120389 -424.951427) (xy 11.03188 -424.920155) (xy 10.946341 -424.881489)
			(xy 10.864389 -424.835708) (xy 10.786615 -424.783142) (xy 10.71358 -424.724169) (xy 10.645808 -424.659216)
			(xy 10.583789 -424.588749) (xy 10.52797 -424.513276) (xy 10.478752 -424.433341) (xy 10.43649 -424.34952)
			(xy 10.40149 -424.262417) (xy 10.374002 -424.17266) (xy 10.354225 -424.080895) (xy 10.342302 -423.987783)
			(xy 10.338318 -423.893996) (xy 7.050015 -423.893996) (xy 7.04603 -423.987783) (xy 7.034107 -424.080895)
			(xy 7.01433 -424.17266) (xy 6.986842 -424.262417) (xy 6.951842 -424.34952) (xy 6.90958 -424.433341)
			(xy 6.860362 -424.513276) (xy 6.804543 -424.588749) (xy 6.742524 -424.659216) (xy 6.674752 -424.724169)
			(xy 6.601717 -424.783142) (xy 6.523943 -424.835708) (xy 6.441991 -424.881489) (xy 6.356452 -424.920155)
			(xy 6.267943 -424.951427) (xy 6.1771 -424.975081) (xy 6.084578 -424.990945) (xy 5.991044 -424.998906)
			(xy 5.897172 -424.998906) (xy 5.803638 -424.990945) (xy 5.711116 -424.975081) (xy 5.620273 -424.951427)
			(xy 5.531764 -424.920155) (xy 5.446225 -424.881489) (xy 5.364273 -424.835708) (xy 5.286499 -424.783142)
			(xy 5.213464 -424.724169) (xy 5.145692 -424.659216) (xy 5.083673 -424.588749) (xy 5.027854 -424.513276)
			(xy 4.978636 -424.433341) (xy 4.936374 -424.34952) (xy 4.901374 -424.262417) (xy 4.873886 -424.17266)
			(xy 4.854109 -424.080895) (xy 4.842186 -423.987783) (xy 4.838202 -423.893996) (xy 0.509016 -423.893996)
			(xy 0.509016 -428.09414) (xy 10.338318 -428.09414) (xy 10.342302 -428.000353) (xy 10.354225 -427.907241)
			(xy 10.374002 -427.815476) (xy 10.40149 -427.725719) (xy 10.43649 -427.638616) (xy 10.478752 -427.554795)
			(xy 10.52797 -427.47486) (xy 10.583789 -427.399387) (xy 10.645808 -427.32892) (xy 10.71358 -427.263967)
			(xy 10.786615 -427.204994) (xy 10.864389 -427.152428) (xy 10.946341 -427.106647) (xy 11.03188 -427.067981)
			(xy 11.120389 -427.036709) (xy 11.211232 -427.013055) (xy 11.303754 -426.997191) (xy 11.397288 -426.98923)
			(xy 11.444224 -426.988732) (xy 11.49116 -426.98923) (xy 11.584694 -426.997191) (xy 11.677216 -427.013055)
			(xy 11.768059 -427.036709) (xy 11.856568 -427.067981) (xy 11.942107 -427.106647) (xy 12.024059 -427.152428)
			(xy 12.101833 -427.204994) (xy 12.174868 -427.263967) (xy 12.24264 -427.32892) (xy 12.304659 -427.399387)
			(xy 12.360478 -427.47486) (xy 12.409696 -427.554795) (xy 12.451958 -427.638616) (xy 12.486958 -427.725719)
			(xy 12.514446 -427.815476) (xy 12.534223 -427.907241) (xy 12.546146 -428.000353) (xy 12.550131 -428.09414)
			(xy 12.546146 -428.187927) (xy 12.534223 -428.281039) (xy 12.514446 -428.372804) (xy 12.486958 -428.462561)
			(xy 12.451958 -428.549664) (xy 12.409696 -428.633485) (xy 12.360478 -428.71342) (xy 12.304659 -428.788893)
			(xy 12.24264 -428.85936) (xy 12.174868 -428.924313) (xy 12.101833 -428.983286) (xy 12.024059 -429.035852)
			(xy 11.942107 -429.081633) (xy 11.856568 -429.120299) (xy 11.768059 -429.151571) (xy 11.677216 -429.175225)
			(xy 11.584694 -429.191089) (xy 11.49116 -429.19905) (xy 11.397288 -429.19905) (xy 11.303754 -429.191089)
			(xy 11.211232 -429.175225) (xy 11.120389 -429.151571) (xy 11.03188 -429.120299) (xy 10.946341 -429.081633)
			(xy 10.864389 -429.035852) (xy 10.786615 -428.983286) (xy 10.71358 -428.924313) (xy 10.645808 -428.85936)
			(xy 10.583789 -428.788893) (xy 10.52797 -428.71342) (xy 10.478752 -428.633485) (xy 10.43649 -428.549664)
			(xy 10.40149 -428.462561) (xy 10.374002 -428.372804) (xy 10.354225 -428.281039) (xy 10.342302 -428.187927)
			(xy 10.338318 -428.09414) (xy 0.509016 -428.09414) (xy 0.509016 -432.29403) (xy 10.338318 -432.29403)
			(xy 10.342302 -432.200243) (xy 10.354225 -432.107131) (xy 10.374002 -432.015366) (xy 10.40149 -431.925609)
			(xy 10.43649 -431.838506) (xy 10.478752 -431.754685) (xy 10.52797 -431.67475) (xy 10.583789 -431.599277)
			(xy 10.645808 -431.52881) (xy 10.71358 -431.463857) (xy 10.786615 -431.404884) (xy 10.864389 -431.352318)
			(xy 10.946341 -431.306537) (xy 11.03188 -431.267871) (xy 11.120389 -431.236599) (xy 11.211232 -431.212945)
			(xy 11.303754 -431.197081) (xy 11.397288 -431.18912) (xy 11.444224 -431.188622) (xy 11.49116 -431.18912)
			(xy 11.584694 -431.197081) (xy 11.677216 -431.212945) (xy 11.768059 -431.236599) (xy 11.856568 -431.267871)
			(xy 11.942107 -431.306537) (xy 12.024059 -431.352318) (xy 12.101833 -431.404884) (xy 12.174868 -431.463857)
			(xy 12.24264 -431.52881) (xy 12.304659 -431.599277) (xy 12.360478 -431.67475) (xy 12.409696 -431.754685)
			(xy 12.451958 -431.838506) (xy 12.486958 -431.925609) (xy 12.514446 -432.015366) (xy 12.534223 -432.107131)
			(xy 12.546146 -432.200243) (xy 12.550131 -432.29403) (xy 12.546146 -432.387817) (xy 12.534223 -432.480929)
			(xy 12.514446 -432.572694) (xy 12.486958 -432.662451) (xy 12.451958 -432.749554) (xy 12.409696 -432.833375)
			(xy 12.360478 -432.91331) (xy 12.304659 -432.988783) (xy 12.24264 -433.05925) (xy 12.174868 -433.124203)
			(xy 12.101833 -433.183176) (xy 12.024059 -433.235742) (xy 11.942107 -433.281523) (xy 11.856568 -433.320189)
			(xy 11.768059 -433.351461) (xy 11.677216 -433.375115) (xy 11.584694 -433.390979) (xy 11.49116 -433.39894)
			(xy 11.397288 -433.39894) (xy 11.303754 -433.390979) (xy 11.211232 -433.375115) (xy 11.120389 -433.351461)
			(xy 11.03188 -433.320189) (xy 10.946341 -433.281523) (xy 10.864389 -433.235742) (xy 10.786615 -433.183176)
			(xy 10.71358 -433.124203) (xy 10.645808 -433.05925) (xy 10.583789 -432.988783) (xy 10.52797 -432.91331)
			(xy 10.478752 -432.833375) (xy 10.43649 -432.749554) (xy 10.40149 -432.662451) (xy 10.374002 -432.572694)
			(xy 10.354225 -432.480929) (xy 10.342302 -432.387817) (xy 10.338318 -432.29403) (xy 0.509016 -432.29403)
			(xy 0.509016 -436.49392) (xy 4.838202 -436.49392) (xy 4.842186 -436.400133) (xy 4.854109 -436.307021)
			(xy 4.873886 -436.215256) (xy 4.901374 -436.125499) (xy 4.936374 -436.038396) (xy 4.978636 -435.954575)
			(xy 5.027854 -435.87464) (xy 5.083673 -435.799167) (xy 5.145692 -435.7287) (xy 5.213464 -435.663747)
			(xy 5.286499 -435.604774) (xy 5.364273 -435.552208) (xy 5.446225 -435.506427) (xy 5.531764 -435.467761)
			(xy 5.620273 -435.436489) (xy 5.711116 -435.412835) (xy 5.803638 -435.396971) (xy 5.897172 -435.38901)
			(xy 5.944108 -435.388512) (xy 5.991044 -435.38901) (xy 6.084578 -435.396971) (xy 6.1771 -435.412835)
			(xy 6.267943 -435.436489) (xy 6.356452 -435.467761) (xy 6.441991 -435.506427) (xy 6.523943 -435.552208)
			(xy 6.601717 -435.604774) (xy 6.674752 -435.663747) (xy 6.742524 -435.7287) (xy 6.804543 -435.799167)
			(xy 6.860362 -435.87464) (xy 6.90958 -435.954575) (xy 6.951842 -436.038396) (xy 6.986842 -436.125499)
			(xy 7.01433 -436.215256) (xy 7.034107 -436.307021) (xy 7.04603 -436.400133) (xy 7.050015 -436.49392)
			(xy 10.338318 -436.49392) (xy 10.342302 -436.400133) (xy 10.354225 -436.307021) (xy 10.374002 -436.215256)
			(xy 10.40149 -436.125499) (xy 10.43649 -436.038396) (xy 10.478752 -435.954575) (xy 10.52797 -435.87464)
			(xy 10.583789 -435.799167) (xy 10.645808 -435.7287) (xy 10.71358 -435.663747) (xy 10.786615 -435.604774)
			(xy 10.864389 -435.552208) (xy 10.946341 -435.506427) (xy 11.03188 -435.467761) (xy 11.120389 -435.436489)
			(xy 11.211232 -435.412835) (xy 11.303754 -435.396971) (xy 11.397288 -435.38901) (xy 11.444224 -435.388512)
			(xy 11.49116 -435.38901) (xy 11.584694 -435.396971) (xy 11.677216 -435.412835) (xy 11.768059 -435.436489)
			(xy 11.856568 -435.467761) (xy 11.942107 -435.506427) (xy 12.024059 -435.552208) (xy 12.101833 -435.604774)
			(xy 12.174868 -435.663747) (xy 12.24264 -435.7287) (xy 12.304659 -435.799167) (xy 12.360478 -435.87464)
			(xy 12.409696 -435.954575) (xy 12.451958 -436.038396) (xy 12.486958 -436.125499) (xy 12.514446 -436.215256)
			(xy 12.534223 -436.307021) (xy 12.546146 -436.400133) (xy 12.550131 -436.49392) (xy 12.546146 -436.587707)
			(xy 12.534223 -436.680819) (xy 12.514446 -436.772584) (xy 12.486958 -436.862341) (xy 12.451958 -436.949444)
			(xy 12.409696 -437.033265) (xy 12.360478 -437.1132) (xy 12.304659 -437.188673) (xy 12.24264 -437.25914)
			(xy 12.174868 -437.324093) (xy 12.101833 -437.383066) (xy 12.024059 -437.435632) (xy 11.942107 -437.481413)
			(xy 11.856568 -437.520079) (xy 11.768059 -437.551351) (xy 11.677216 -437.575005) (xy 11.584694 -437.590869)
			(xy 11.49116 -437.59883) (xy 11.397288 -437.59883) (xy 11.303754 -437.590869) (xy 11.211232 -437.575005)
			(xy 11.120389 -437.551351) (xy 11.03188 -437.520079) (xy 10.946341 -437.481413) (xy 10.864389 -437.435632)
			(xy 10.786615 -437.383066) (xy 10.71358 -437.324093) (xy 10.645808 -437.25914) (xy 10.583789 -437.188673)
			(xy 10.52797 -437.1132) (xy 10.478752 -437.033265) (xy 10.43649 -436.949444) (xy 10.40149 -436.862341)
			(xy 10.374002 -436.772584) (xy 10.354225 -436.680819) (xy 10.342302 -436.587707) (xy 10.338318 -436.49392)
			(xy 7.050015 -436.49392) (xy 7.04603 -436.587707) (xy 7.034107 -436.680819) (xy 7.01433 -436.772584)
			(xy 6.986842 -436.862341) (xy 6.951842 -436.949444) (xy 6.90958 -437.033265) (xy 6.860362 -437.1132)
			(xy 6.804543 -437.188673) (xy 6.742524 -437.25914) (xy 6.674752 -437.324093) (xy 6.601717 -437.383066)
			(xy 6.523943 -437.435632) (xy 6.441991 -437.481413) (xy 6.356452 -437.520079) (xy 6.267943 -437.551351)
			(xy 6.1771 -437.575005) (xy 6.084578 -437.590869) (xy 5.991044 -437.59883) (xy 5.897172 -437.59883)
			(xy 5.803638 -437.590869) (xy 5.711116 -437.575005) (xy 5.620273 -437.551351) (xy 5.531764 -437.520079)
			(xy 5.446225 -437.481413) (xy 5.364273 -437.435632) (xy 5.286499 -437.383066) (xy 5.213464 -437.324093)
			(xy 5.145692 -437.25914) (xy 5.083673 -437.188673) (xy 5.027854 -437.1132) (xy 4.978636 -437.033265)
			(xy 4.936374 -436.949444) (xy 4.901374 -436.862341) (xy 4.873886 -436.772584) (xy 4.854109 -436.680819)
			(xy 4.842186 -436.587707) (xy 4.838202 -436.49392) (xy 0.509016 -436.49392) (xy 0.509016 -440.694064)
			(xy 10.338318 -440.694064) (xy 10.342302 -440.600277) (xy 10.354225 -440.507165) (xy 10.374002 -440.4154)
			(xy 10.40149 -440.325643) (xy 10.43649 -440.23854) (xy 10.478752 -440.154719) (xy 10.52797 -440.074784)
			(xy 10.583789 -439.999311) (xy 10.645808 -439.928844) (xy 10.71358 -439.863891) (xy 10.786615 -439.804918)
			(xy 10.864389 -439.752352) (xy 10.946341 -439.706571) (xy 11.03188 -439.667905) (xy 11.120389 -439.636633)
			(xy 11.211232 -439.612979) (xy 11.303754 -439.597115) (xy 11.397288 -439.589154) (xy 11.444224 -439.588656)
			(xy 11.49116 -439.589154) (xy 11.584694 -439.597115) (xy 11.677216 -439.612979) (xy 11.768059 -439.636633)
			(xy 11.856568 -439.667905) (xy 11.942107 -439.706571) (xy 12.024059 -439.752352) (xy 12.101833 -439.804918)
			(xy 12.174868 -439.863891) (xy 12.24264 -439.928844) (xy 12.304659 -439.999311) (xy 12.360478 -440.074784)
			(xy 12.409696 -440.154719) (xy 12.451958 -440.23854) (xy 12.486958 -440.325643) (xy 12.514446 -440.4154)
			(xy 12.534223 -440.507165) (xy 12.546146 -440.600277) (xy 12.550131 -440.694064) (xy 12.546146 -440.787851)
			(xy 12.534223 -440.880963) (xy 12.514446 -440.972728) (xy 12.486958 -441.062485) (xy 12.451958 -441.149588)
			(xy 12.409696 -441.233409) (xy 12.360478 -441.313344) (xy 12.304659 -441.388817) (xy 12.24264 -441.459284)
			(xy 12.174868 -441.524237) (xy 12.101833 -441.58321) (xy 12.024059 -441.635776) (xy 11.942107 -441.681557)
			(xy 11.856568 -441.720223) (xy 11.768059 -441.751495) (xy 11.677216 -441.775149) (xy 11.584694 -441.791013)
			(xy 11.49116 -441.798974) (xy 11.397288 -441.798974) (xy 11.303754 -441.791013) (xy 11.211232 -441.775149)
			(xy 11.120389 -441.751495) (xy 11.03188 -441.720223) (xy 10.946341 -441.681557) (xy 10.864389 -441.635776)
			(xy 10.786615 -441.58321) (xy 10.71358 -441.524237) (xy 10.645808 -441.459284) (xy 10.583789 -441.388817)
			(xy 10.52797 -441.313344) (xy 10.478752 -441.233409) (xy 10.43649 -441.149588) (xy 10.40149 -441.062485)
			(xy 10.374002 -440.972728) (xy 10.354225 -440.880963) (xy 10.342302 -440.787851) (xy 10.338318 -440.694064)
			(xy 0.509016 -440.694064) (xy 0.509016 -444.893954) (xy 10.338318 -444.893954) (xy 10.342302 -444.800167)
			(xy 10.354225 -444.707055) (xy 10.374002 -444.61529) (xy 10.40149 -444.525533) (xy 10.43649 -444.43843)
			(xy 10.478752 -444.354609) (xy 10.52797 -444.274674) (xy 10.583789 -444.199201) (xy 10.645808 -444.128734)
			(xy 10.71358 -444.063781) (xy 10.786615 -444.004808) (xy 10.864389 -443.952242) (xy 10.946341 -443.906461)
			(xy 11.03188 -443.867795) (xy 11.120389 -443.836523) (xy 11.211232 -443.812869) (xy 11.303754 -443.797005)
			(xy 11.397288 -443.789044) (xy 11.444224 -443.788546) (xy 11.49116 -443.789044) (xy 11.584694 -443.797005)
			(xy 11.677216 -443.812869) (xy 11.768059 -443.836523) (xy 11.856568 -443.867795) (xy 11.942107 -443.906461)
			(xy 12.024059 -443.952242) (xy 12.101833 -444.004808) (xy 12.174868 -444.063781) (xy 12.24264 -444.128734)
			(xy 12.304659 -444.199201) (xy 12.360478 -444.274674) (xy 12.409696 -444.354609) (xy 12.451958 -444.43843)
			(xy 12.486958 -444.525533) (xy 12.514446 -444.61529) (xy 12.534223 -444.707055) (xy 12.546146 -444.800167)
			(xy 12.550131 -444.893954) (xy 12.546146 -444.987741) (xy 12.534223 -445.080853) (xy 12.514446 -445.172618)
			(xy 12.486958 -445.262375) (xy 12.451958 -445.349478) (xy 12.409696 -445.433299) (xy 12.360478 -445.513234)
			(xy 12.304659 -445.588707) (xy 12.24264 -445.659174) (xy 12.174868 -445.724127) (xy 12.101833 -445.7831)
			(xy 12.024059 -445.835666) (xy 11.942107 -445.881447) (xy 11.856568 -445.920113) (xy 11.768059 -445.951385)
			(xy 11.677216 -445.975039) (xy 11.584694 -445.990903) (xy 11.49116 -445.998864) (xy 11.397288 -445.998864)
			(xy 11.303754 -445.990903) (xy 11.211232 -445.975039) (xy 11.120389 -445.951385) (xy 11.03188 -445.920113)
			(xy 10.946341 -445.881447) (xy 10.864389 -445.835666) (xy 10.786615 -445.7831) (xy 10.71358 -445.724127)
			(xy 10.645808 -445.659174) (xy 10.583789 -445.588707) (xy 10.52797 -445.513234) (xy 10.478752 -445.433299)
			(xy 10.43649 -445.349478) (xy 10.40149 -445.262375) (xy 10.374002 -445.172618) (xy 10.354225 -445.080853)
			(xy 10.342302 -444.987741) (xy 10.338318 -444.893954) (xy 0.509016 -444.893954) (xy 0.509016 -449.094098)
			(xy 4.838202 -449.094098) (xy 4.842186 -449.000311) (xy 4.854109 -448.907199) (xy 4.873886 -448.815434)
			(xy 4.901374 -448.725677) (xy 4.936374 -448.638574) (xy 4.978636 -448.554753) (xy 5.027854 -448.474818)
			(xy 5.083673 -448.399345) (xy 5.145692 -448.328878) (xy 5.213464 -448.263925) (xy 5.286499 -448.204952)
			(xy 5.364273 -448.152386) (xy 5.446225 -448.106605) (xy 5.531764 -448.067939) (xy 5.620273 -448.036667)
			(xy 5.711116 -448.013013) (xy 5.803638 -447.997149) (xy 5.897172 -447.989188) (xy 5.944108 -447.98869)
			(xy 5.991044 -447.989188) (xy 6.084578 -447.997149) (xy 6.1771 -448.013013) (xy 6.267943 -448.036667)
			(xy 6.356452 -448.067939) (xy 6.441991 -448.106605) (xy 6.523943 -448.152386) (xy 6.601717 -448.204952)
			(xy 6.674752 -448.263925) (xy 6.742524 -448.328878) (xy 6.804543 -448.399345) (xy 6.860362 -448.474818)
			(xy 6.90958 -448.554753) (xy 6.951842 -448.638574) (xy 6.986842 -448.725677) (xy 7.01433 -448.815434)
			(xy 7.034107 -448.907199) (xy 7.04603 -449.000311) (xy 7.050015 -449.094098) (xy 10.338318 -449.094098)
			(xy 10.342302 -449.000311) (xy 10.354225 -448.907199) (xy 10.374002 -448.815434) (xy 10.40149 -448.725677)
			(xy 10.43649 -448.638574) (xy 10.478752 -448.554753) (xy 10.52797 -448.474818) (xy 10.583789 -448.399345)
			(xy 10.645808 -448.328878) (xy 10.71358 -448.263925) (xy 10.786615 -448.204952) (xy 10.864389 -448.152386)
			(xy 10.946341 -448.106605) (xy 11.03188 -448.067939) (xy 11.120389 -448.036667) (xy 11.211232 -448.013013)
			(xy 11.303754 -447.997149) (xy 11.397288 -447.989188) (xy 11.444224 -447.98869) (xy 11.49116 -447.989188)
			(xy 11.584694 -447.997149) (xy 11.677216 -448.013013) (xy 11.768059 -448.036667) (xy 11.856568 -448.067939)
			(xy 11.942107 -448.106605) (xy 12.024059 -448.152386) (xy 12.101833 -448.204952) (xy 12.174868 -448.263925)
			(xy 12.24264 -448.328878) (xy 12.304659 -448.399345) (xy 12.360478 -448.474818) (xy 12.409696 -448.554753)
			(xy 12.451958 -448.638574) (xy 12.486958 -448.725677) (xy 12.514446 -448.815434) (xy 12.534223 -448.907199)
			(xy 12.546146 -449.000311) (xy 12.550131 -449.094098) (xy 12.546146 -449.187885) (xy 12.534223 -449.280997)
			(xy 12.514446 -449.372762) (xy 12.486958 -449.462519) (xy 12.451958 -449.549622) (xy 12.409696 -449.633443)
			(xy 12.360478 -449.713378) (xy 12.304659 -449.788851) (xy 12.24264 -449.859318) (xy 12.174868 -449.924271)
			(xy 12.101833 -449.983244) (xy 12.024059 -450.03581) (xy 11.942107 -450.081591) (xy 11.856568 -450.120257)
			(xy 11.768059 -450.151529) (xy 11.677216 -450.175183) (xy 11.584694 -450.191047) (xy 11.49116 -450.199008)
			(xy 11.397288 -450.199008) (xy 11.303754 -450.191047) (xy 11.211232 -450.175183) (xy 11.120389 -450.151529)
			(xy 11.03188 -450.120257) (xy 10.946341 -450.081591) (xy 10.864389 -450.03581) (xy 10.786615 -449.983244)
			(xy 10.71358 -449.924271) (xy 10.645808 -449.859318) (xy 10.583789 -449.788851) (xy 10.52797 -449.713378)
			(xy 10.478752 -449.633443) (xy 10.43649 -449.549622) (xy 10.40149 -449.462519) (xy 10.374002 -449.372762)
			(xy 10.354225 -449.280997) (xy 10.342302 -449.187885) (xy 10.338318 -449.094098) (xy 7.050015 -449.094098)
			(xy 7.04603 -449.187885) (xy 7.034107 -449.280997) (xy 7.01433 -449.372762) (xy 6.986842 -449.462519)
			(xy 6.951842 -449.549622) (xy 6.90958 -449.633443) (xy 6.860362 -449.713378) (xy 6.804543 -449.788851)
			(xy 6.742524 -449.859318) (xy 6.674752 -449.924271) (xy 6.601717 -449.983244) (xy 6.523943 -450.03581)
			(xy 6.441991 -450.081591) (xy 6.356452 -450.120257) (xy 6.267943 -450.151529) (xy 6.1771 -450.175183)
			(xy 6.084578 -450.191047) (xy 5.991044 -450.199008) (xy 5.897172 -450.199008) (xy 5.803638 -450.191047)
			(xy 5.711116 -450.175183) (xy 5.620273 -450.151529) (xy 5.531764 -450.120257) (xy 5.446225 -450.081591)
			(xy 5.364273 -450.03581) (xy 5.286499 -449.983244) (xy 5.213464 -449.924271) (xy 5.145692 -449.859318)
			(xy 5.083673 -449.788851) (xy 5.027854 -449.713378) (xy 4.978636 -449.633443) (xy 4.936374 -449.549622)
			(xy 4.901374 -449.462519) (xy 4.873886 -449.372762) (xy 4.854109 -449.280997) (xy 4.842186 -449.187885)
			(xy 4.838202 -449.094098) (xy 0.509016 -449.094098) (xy 0.509016 -453.293988) (xy 10.338318 -453.293988)
			(xy 10.342302 -453.200201) (xy 10.354225 -453.107089) (xy 10.374002 -453.015324) (xy 10.40149 -452.925567)
			(xy 10.43649 -452.838464) (xy 10.478752 -452.754643) (xy 10.52797 -452.674708) (xy 10.583789 -452.599235)
			(xy 10.645808 -452.528768) (xy 10.71358 -452.463815) (xy 10.786615 -452.404842) (xy 10.864389 -452.352276)
			(xy 10.946341 -452.306495) (xy 11.03188 -452.267829) (xy 11.120389 -452.236557) (xy 11.211232 -452.212903)
			(xy 11.303754 -452.197039) (xy 11.397288 -452.189078) (xy 11.444224 -452.18858) (xy 11.49116 -452.189078)
			(xy 11.584694 -452.197039) (xy 11.677216 -452.212903) (xy 11.768059 -452.236557) (xy 11.856568 -452.267829)
			(xy 11.942107 -452.306495) (xy 12.024059 -452.352276) (xy 12.101833 -452.404842) (xy 12.174868 -452.463815)
			(xy 12.24264 -452.528768) (xy 12.304659 -452.599235) (xy 12.360478 -452.674708) (xy 12.409696 -452.754643)
			(xy 12.451958 -452.838464) (xy 12.486958 -452.925567) (xy 12.514446 -453.015324) (xy 12.534223 -453.107089)
			(xy 12.546146 -453.200201) (xy 12.550131 -453.293988) (xy 12.546146 -453.387775) (xy 12.534223 -453.480887)
			(xy 12.514446 -453.572652) (xy 12.486958 -453.662409) (xy 12.451958 -453.749512) (xy 12.409696 -453.833333)
			(xy 12.360478 -453.913268) (xy 12.304659 -453.988741) (xy 12.24264 -454.059208) (xy 12.174868 -454.124161)
			(xy 12.101833 -454.183134) (xy 12.024059 -454.2357) (xy 11.942107 -454.281481) (xy 11.856568 -454.320147)
			(xy 11.768059 -454.351419) (xy 11.677216 -454.375073) (xy 11.584694 -454.390937) (xy 11.49116 -454.398898)
			(xy 11.397288 -454.398898) (xy 11.303754 -454.390937) (xy 11.211232 -454.375073) (xy 11.120389 -454.351419)
			(xy 11.03188 -454.320147) (xy 10.946341 -454.281481) (xy 10.864389 -454.2357) (xy 10.786615 -454.183134)
			(xy 10.71358 -454.124161) (xy 10.645808 -454.059208) (xy 10.583789 -453.988741) (xy 10.52797 -453.913268)
			(xy 10.478752 -453.833333) (xy 10.43649 -453.749512) (xy 10.40149 -453.662409) (xy 10.374002 -453.572652)
			(xy 10.354225 -453.480887) (xy 10.342302 -453.387775) (xy 10.338318 -453.293988) (xy 0.509016 -453.293988)
			(xy 0.509016 -457.494132) (xy 10.338318 -457.494132) (xy 10.342302 -457.400345) (xy 10.354225 -457.307233)
			(xy 10.374002 -457.215468) (xy 10.40149 -457.125711) (xy 10.43649 -457.038608) (xy 10.478752 -456.954787)
			(xy 10.52797 -456.874852) (xy 10.583789 -456.799379) (xy 10.645808 -456.728912) (xy 10.71358 -456.663959)
			(xy 10.786615 -456.604986) (xy 10.864389 -456.55242) (xy 10.946341 -456.506639) (xy 11.03188 -456.467973)
			(xy 11.120389 -456.436701) (xy 11.211232 -456.413047) (xy 11.303754 -456.397183) (xy 11.397288 -456.389222)
			(xy 11.444224 -456.388724) (xy 11.49116 -456.389222) (xy 11.584694 -456.397183) (xy 11.677216 -456.413047)
			(xy 11.768059 -456.436701) (xy 11.856568 -456.467973) (xy 11.942107 -456.506639) (xy 12.024059 -456.55242)
			(xy 12.101833 -456.604986) (xy 12.174868 -456.663959) (xy 12.24264 -456.728912) (xy 12.304659 -456.799379)
			(xy 12.360478 -456.874852) (xy 12.409696 -456.954787) (xy 12.451958 -457.038608) (xy 12.486958 -457.125711)
			(xy 12.514446 -457.215468) (xy 12.534223 -457.307233) (xy 12.546146 -457.400345) (xy 12.550131 -457.494132)
			(xy 12.546146 -457.587919) (xy 12.534223 -457.681031) (xy 12.514446 -457.772796) (xy 12.486958 -457.862553)
			(xy 12.451958 -457.949656) (xy 12.409696 -458.033477) (xy 12.360478 -458.113412) (xy 12.304659 -458.188885)
			(xy 12.24264 -458.259352) (xy 12.174868 -458.324305) (xy 12.101833 -458.383278) (xy 12.024059 -458.435844)
			(xy 11.942107 -458.481625) (xy 11.856568 -458.520291) (xy 11.768059 -458.551563) (xy 11.677216 -458.575217)
			(xy 11.584694 -458.591081) (xy 11.49116 -458.599042) (xy 11.397288 -458.599042) (xy 11.303754 -458.591081)
			(xy 11.211232 -458.575217) (xy 11.120389 -458.551563) (xy 11.03188 -458.520291) (xy 10.946341 -458.481625)
			(xy 10.864389 -458.435844) (xy 10.786615 -458.383278) (xy 10.71358 -458.324305) (xy 10.645808 -458.259352)
			(xy 10.583789 -458.188885) (xy 10.52797 -458.113412) (xy 10.478752 -458.033477) (xy 10.43649 -457.949656)
			(xy 10.40149 -457.862553) (xy 10.374002 -457.772796) (xy 10.354225 -457.681031) (xy 10.342302 -457.587919)
			(xy 10.338318 -457.494132) (xy 0.509016 -457.494132) (xy 0.509016 -461.694022) (xy 4.838202 -461.694022)
			(xy 4.842186 -461.600235) (xy 4.854109 -461.507123) (xy 4.873886 -461.415358) (xy 4.901374 -461.325601)
			(xy 4.936374 -461.238498) (xy 4.978636 -461.154677) (xy 5.027854 -461.074742) (xy 5.083673 -460.999269)
			(xy 5.145692 -460.928802) (xy 5.213464 -460.863849) (xy 5.286499 -460.804876) (xy 5.364273 -460.75231)
			(xy 5.446225 -460.706529) (xy 5.531764 -460.667863) (xy 5.620273 -460.636591) (xy 5.711116 -460.612937)
			(xy 5.803638 -460.597073) (xy 5.897172 -460.589112) (xy 5.944108 -460.588614) (xy 5.991044 -460.589112)
			(xy 6.084578 -460.597073) (xy 6.1771 -460.612937) (xy 6.267943 -460.636591) (xy 6.356452 -460.667863)
			(xy 6.441991 -460.706529) (xy 6.523943 -460.75231) (xy 6.601717 -460.804876) (xy 6.674752 -460.863849)
			(xy 6.742524 -460.928802) (xy 6.804543 -460.999269) (xy 6.860362 -461.074742) (xy 6.90958 -461.154677)
			(xy 6.951842 -461.238498) (xy 6.986842 -461.325601) (xy 7.01433 -461.415358) (xy 7.034107 -461.507123)
			(xy 7.04603 -461.600235) (xy 7.050015 -461.694022) (xy 10.338318 -461.694022) (xy 10.342302 -461.600235)
			(xy 10.354225 -461.507123) (xy 10.374002 -461.415358) (xy 10.40149 -461.325601) (xy 10.43649 -461.238498)
			(xy 10.478752 -461.154677) (xy 10.52797 -461.074742) (xy 10.583789 -460.999269) (xy 10.645808 -460.928802)
			(xy 10.71358 -460.863849) (xy 10.786615 -460.804876) (xy 10.864389 -460.75231) (xy 10.946341 -460.706529)
			(xy 11.03188 -460.667863) (xy 11.120389 -460.636591) (xy 11.211232 -460.612937) (xy 11.303754 -460.597073)
			(xy 11.397288 -460.589112) (xy 11.444224 -460.588614) (xy 11.49116 -460.589112) (xy 11.584694 -460.597073)
			(xy 11.677216 -460.612937) (xy 11.768059 -460.636591) (xy 11.856568 -460.667863) (xy 11.942107 -460.706529)
			(xy 12.024059 -460.75231) (xy 12.101833 -460.804876) (xy 12.174868 -460.863849) (xy 12.24264 -460.928802)
			(xy 12.304659 -460.999269) (xy 12.360478 -461.074742) (xy 12.409696 -461.154677) (xy 12.451958 -461.238498)
			(xy 12.486958 -461.325601) (xy 12.514446 -461.415358) (xy 12.534223 -461.507123) (xy 12.546146 -461.600235)
			(xy 12.550131 -461.694022) (xy 12.546146 -461.787809) (xy 12.534223 -461.880921) (xy 12.514446 -461.972686)
			(xy 12.486958 -462.062443) (xy 12.451958 -462.149546) (xy 12.409696 -462.233367) (xy 12.360478 -462.313302)
			(xy 12.304659 -462.388775) (xy 12.24264 -462.459242) (xy 12.174868 -462.524195) (xy 12.101833 -462.583168)
			(xy 12.024059 -462.635734) (xy 11.942107 -462.681515) (xy 11.856568 -462.720181) (xy 11.768059 -462.751453)
			(xy 11.677216 -462.775107) (xy 11.584694 -462.790971) (xy 11.49116 -462.798932) (xy 11.397288 -462.798932)
			(xy 11.303754 -462.790971) (xy 11.211232 -462.775107) (xy 11.120389 -462.751453) (xy 11.03188 -462.720181)
			(xy 10.946341 -462.681515) (xy 10.864389 -462.635734) (xy 10.786615 -462.583168) (xy 10.71358 -462.524195)
			(xy 10.645808 -462.459242) (xy 10.583789 -462.388775) (xy 10.52797 -462.313302) (xy 10.478752 -462.233367)
			(xy 10.43649 -462.149546) (xy 10.40149 -462.062443) (xy 10.374002 -461.972686) (xy 10.354225 -461.880921)
			(xy 10.342302 -461.787809) (xy 10.338318 -461.694022) (xy 7.050015 -461.694022) (xy 7.04603 -461.787809)
			(xy 7.034107 -461.880921) (xy 7.01433 -461.972686) (xy 6.986842 -462.062443) (xy 6.951842 -462.149546)
			(xy 6.90958 -462.233367) (xy 6.860362 -462.313302) (xy 6.804543 -462.388775) (xy 6.742524 -462.459242)
			(xy 6.674752 -462.524195) (xy 6.601717 -462.583168) (xy 6.523943 -462.635734) (xy 6.441991 -462.681515)
			(xy 6.356452 -462.720181) (xy 6.267943 -462.751453) (xy 6.1771 -462.775107) (xy 6.084578 -462.790971)
			(xy 5.991044 -462.798932) (xy 5.897172 -462.798932) (xy 5.803638 -462.790971) (xy 5.711116 -462.775107)
			(xy 5.620273 -462.751453) (xy 5.531764 -462.720181) (xy 5.446225 -462.681515) (xy 5.364273 -462.635734)
			(xy 5.286499 -462.583168) (xy 5.213464 -462.524195) (xy 5.145692 -462.459242) (xy 5.083673 -462.388775)
			(xy 5.027854 -462.313302) (xy 4.978636 -462.233367) (xy 4.936374 -462.149546) (xy 4.901374 -462.062443)
			(xy 4.873886 -461.972686) (xy 4.854109 -461.880921) (xy 4.842186 -461.787809) (xy 4.838202 -461.694022)
			(xy 0.509016 -461.694022) (xy 0.509016 -488.294325) (xy 1.150876 -488.294325) (xy 1.152892 -488.164712)
			(xy 1.162962 -488.035476) (xy 1.181047 -487.907115) (xy 1.207077 -487.780127) (xy 1.240952 -487.655003)
			(xy 1.28254 -487.532227) (xy 1.331681 -487.412274) (xy 1.388184 -487.295609) (xy 1.451831 -487.182681)
			(xy 1.522375 -487.073929) (xy 1.599544 -486.969773) (xy 1.683039 -486.870616) (xy 1.772537 -486.776842)
			(xy 1.867692 -486.688813) (xy 1.968135 -486.60687) (xy 2.073478 -486.531331) (xy 2.183314 -486.462486)
			(xy 2.297218 -486.400603) (xy 2.414748 -486.345922) (xy 2.535451 -486.298652) (xy 2.658859 -486.258979)
			(xy 2.784495 -486.227054) (xy 2.911872 -486.203002) (xy 3.040498 -486.186915) (xy 3.169876 -486.178856)
			(xy 3.23469 -486.178352) (xy 3.299504 -486.178856) (xy 3.428882 -486.186915) (xy 3.557508 -486.203002)
			(xy 3.684885 -486.227054) (xy 3.810521 -486.258979) (xy 3.933929 -486.298652) (xy 4.054632 -486.345922)
			(xy 4.172162 -486.400603) (xy 4.286066 -486.462486) (xy 4.395902 -486.531331) (xy 4.501245 -486.60687)
			(xy 4.601688 -486.688813) (xy 4.696843 -486.776842) (xy 4.786341 -486.870616) (xy 4.869836 -486.969773)
			(xy 4.947005 -487.073929) (xy 5.017549 -487.182681) (xy 5.081196 -487.295609) (xy 5.137699 -487.412274)
			(xy 5.18684 -487.532227) (xy 5.228428 -487.655003) (xy 5.262303 -487.780127) (xy 5.288333 -487.907115)
			(xy 5.306418 -488.035476) (xy 5.316488 -488.164712) (xy 5.318504 -488.294325) (xy 5.312458 -488.423812)
			(xy 5.298374 -488.552673) (xy 5.276305 -488.680409) (xy 5.246338 -488.806526) (xy 5.208589 -488.930536)
			(xy 5.163202 -489.051959) (xy 5.110355 -489.170326) (xy 5.050251 -489.285178) (xy 4.983123 -489.396071)
			(xy 4.909231 -489.502577) (xy 4.82886 -489.604283) (xy 4.742322 -489.700795) (xy 4.64995 -489.79174)
			(xy 4.552104 -489.876767) (xy 4.449161 -489.955547) (xy 4.341519 -490.027774) (xy 4.229595 -490.093169)
			(xy 4.113822 -490.15148) (xy 3.994648 -490.20248) (xy 3.872534 -490.245972) (xy 3.747951 -490.281789)
			(xy 3.621384 -490.309791) (xy 3.49332 -490.32987) (xy 3.364256 -490.341949) (xy 3.23469 -490.34598)
			(xy 3.105124 -490.341949) (xy 2.97606 -490.32987) (xy 2.847996 -490.309791) (xy 2.721429 -490.281789)
			(xy 2.596846 -490.245972) (xy 2.474732 -490.20248) (xy 2.355558 -490.15148) (xy 2.239785 -490.093169)
			(xy 2.127861 -490.027774) (xy 2.020219 -489.955547) (xy 1.917276 -489.876767) (xy 1.81943 -489.79174)
			(xy 1.727058 -489.700795) (xy 1.64052 -489.604283) (xy 1.560149 -489.502577) (xy 1.486257 -489.396071)
			(xy 1.419129 -489.285178) (xy 1.359025 -489.170326) (xy 1.306178 -489.051959) (xy 1.260791 -488.930536)
			(xy 1.223042 -488.806526) (xy 1.193075 -488.680409) (xy 1.171006 -488.552673) (xy 1.156922 -488.423812)
			(xy 1.150876 -488.294325) (xy 0.509016 -488.294325) (xy 0.509016 -514.804305) (xy 1.150876 -514.804305)
			(xy 1.152892 -514.674692) (xy 1.162962 -514.545456) (xy 1.181047 -514.417095) (xy 1.207077 -514.290107)
			(xy 1.240952 -514.164983) (xy 1.28254 -514.042207) (xy 1.331681 -513.922254) (xy 1.388184 -513.805589)
			(xy 1.451831 -513.692661) (xy 1.522375 -513.583909) (xy 1.599544 -513.479753) (xy 1.683039 -513.380596)
			(xy 1.772537 -513.286822) (xy 1.867692 -513.198793) (xy 1.968135 -513.11685) (xy 2.073478 -513.041311)
			(xy 2.183314 -512.972466) (xy 2.297218 -512.910583) (xy 2.414748 -512.855902) (xy 2.535451 -512.808632)
			(xy 2.658859 -512.768959) (xy 2.784495 -512.737034) (xy 2.911872 -512.712982) (xy 3.040498 -512.696895)
			(xy 3.169876 -512.688836) (xy 3.23469 -512.688332) (xy 3.299504 -512.688836) (xy 3.428882 -512.696895)
			(xy 3.557508 -512.712982) (xy 3.684885 -512.737034) (xy 3.810521 -512.768959) (xy 3.933929 -512.808632)
			(xy 4.054632 -512.855902) (xy 4.172162 -512.910583) (xy 4.286066 -512.972466) (xy 4.395902 -513.041311)
			(xy 4.501245 -513.11685) (xy 4.601688 -513.198793) (xy 4.696843 -513.286822) (xy 4.786341 -513.380596)
			(xy 4.869836 -513.479753) (xy 4.947005 -513.583909) (xy 5.017549 -513.692661) (xy 5.081196 -513.805589)
			(xy 5.137699 -513.922254) (xy 5.18684 -514.042207) (xy 5.228428 -514.164983) (xy 5.262303 -514.290107)
			(xy 5.288333 -514.417095) (xy 5.306418 -514.545456) (xy 5.316488 -514.674692) (xy 5.318504 -514.804305)
			(xy 5.312458 -514.933792) (xy 5.298374 -515.062653) (xy 5.276305 -515.190389) (xy 5.246338 -515.316506)
			(xy 5.208589 -515.440516) (xy 5.163202 -515.561939) (xy 5.110355 -515.680306) (xy 5.050251 -515.795158)
			(xy 4.983123 -515.906051) (xy 4.909231 -516.012557) (xy 4.82886 -516.114263) (xy 4.742322 -516.210775)
			(xy 4.64995 -516.30172) (xy 4.552104 -516.386747) (xy 4.449161 -516.465527) (xy 4.341519 -516.537754)
			(xy 4.229595 -516.603149) (xy 4.113822 -516.66146) (xy 3.994648 -516.71246) (xy 3.872534 -516.755952)
			(xy 3.747951 -516.791769) (xy 3.621384 -516.819771) (xy 3.49332 -516.83985) (xy 3.364256 -516.851929)
			(xy 3.23469 -516.85596) (xy 3.105124 -516.851929) (xy 2.97606 -516.83985) (xy 2.847996 -516.819771)
			(xy 2.721429 -516.791769) (xy 2.596846 -516.755952) (xy 2.474732 -516.71246) (xy 2.355558 -516.66146)
			(xy 2.239785 -516.603149) (xy 2.127861 -516.537754) (xy 2.020219 -516.465527) (xy 1.917276 -516.386747)
			(xy 1.81943 -516.30172) (xy 1.727058 -516.210775) (xy 1.64052 -516.114263) (xy 1.560149 -516.012557)
			(xy 1.486257 -515.906051) (xy 1.419129 -515.795158) (xy 1.359025 -515.680306) (xy 1.306178 -515.561939)
			(xy 1.260791 -515.440516) (xy 1.223042 -515.316506) (xy 1.193075 -515.190389) (xy 1.171006 -515.062653)
			(xy 1.156922 -514.933792) (xy 1.150876 -514.804305) (xy 0.509016 -514.804305) (xy 0.509016 -524.500094)
			(xy 0.509529 -524.54588) (xy 0.517978 -524.637062) (xy 0.534804 -524.727075) (xy 0.559864 -524.815152)
			(xy 0.592944 -524.900541) (xy 0.633761 -524.982513) (xy 0.681968 -525.06037) (xy 0.737153 -525.133446)
			(xy 0.798845 -525.201119) (xy 0.866518 -525.262811) (xy 0.939594 -525.317996) (xy 1.017451 -525.366203)
			(xy 1.031828 -525.373362) (xy 29.519874 -525.373362) (xy 29.519874 -525.286462) (xy 29.527892 -525.199933)
			(xy 29.54386 -525.114513) (xy 29.567641 -525.030931) (xy 29.599033 -524.949899) (xy 29.637767 -524.87211)
			(xy 29.683514 -524.798226) (xy 29.735883 -524.728879) (xy 29.794427 -524.664659) (xy 29.858647 -524.606115)
			(xy 29.927994 -524.553746) (xy 30.001878 -524.507999) (xy 30.079667 -524.469265) (xy 30.160699 -524.437873)
			(xy 30.244281 -524.414092) (xy 30.329701 -524.398124) (xy 30.41623 -524.390106) (xy 30.45968 -524.389604)
			(xy 30.50313 -524.390106) (xy 30.589659 -524.398124) (xy 30.675079 -524.414092) (xy 30.758661 -524.437873)
			(xy 30.839693 -524.469265) (xy 30.917482 -524.507999) (xy 30.991366 -524.553746) (xy 31.060713 -524.606115)
			(xy 31.124933 -524.664659) (xy 31.183477 -524.728879) (xy 31.235846 -524.798226) (xy 31.281593 -524.87211)
			(xy 31.320327 -524.949899) (xy 31.351719 -525.030931) (xy 31.3755 -525.114513) (xy 31.391468 -525.199933)
			(xy 31.399486 -525.286462) (xy 31.399486 -525.373362) (xy 34.599874 -525.373362) (xy 34.599874 -525.286462)
			(xy 34.607892 -525.199933) (xy 34.62386 -525.114513) (xy 34.647641 -525.030931) (xy 34.679033 -524.949899)
			(xy 34.717767 -524.87211) (xy 34.763514 -524.798226) (xy 34.815883 -524.728879) (xy 34.874427 -524.664659)
			(xy 34.938647 -524.606115) (xy 35.007994 -524.553746) (xy 35.081878 -524.507999) (xy 35.159667 -524.469265)
			(xy 35.240699 -524.437873) (xy 35.324281 -524.414092) (xy 35.409701 -524.398124) (xy 35.49623 -524.390106)
			(xy 35.53968 -524.389604) (xy 35.58313 -524.390106) (xy 35.669659 -524.398124) (xy 35.755079 -524.414092)
			(xy 35.838661 -524.437873) (xy 35.919693 -524.469265) (xy 35.997482 -524.507999) (xy 36.071366 -524.553746)
			(xy 36.140713 -524.606115) (xy 36.204933 -524.664659) (xy 36.263477 -524.728879) (xy 36.315846 -524.798226)
			(xy 36.361593 -524.87211) (xy 36.400327 -524.949899) (xy 36.431719 -525.030931) (xy 36.4555 -525.114513)
			(xy 36.467343 -525.177867) (xy 56.406534 -525.177867) (xy 56.406534 -525.106545) (xy 56.41452 -525.035671)
			(xy 56.43039 -524.966136) (xy 56.453947 -524.898816) (xy 56.484892 -524.834557) (xy 56.522838 -524.774166)
			(xy 56.567307 -524.718404) (xy 56.61774 -524.667971) (xy 56.673502 -524.623502) (xy 56.733893 -524.585556)
			(xy 56.798152 -524.554611) (xy 56.865472 -524.531054) (xy 56.935007 -524.515184) (xy 57.005881 -524.507198)
			(xy 57.041542 -524.506698) (xy 57.077203 -524.507198) (xy 57.148077 -524.515184) (xy 57.217612 -524.531054)
			(xy 57.284932 -524.554611) (xy 57.349191 -524.585556) (xy 57.409582 -524.623502) (xy 57.465344 -524.667971)
			(xy 57.515777 -524.718404) (xy 57.560246 -524.774166) (xy 57.598192 -524.834557) (xy 57.629137 -524.898816)
			(xy 57.652694 -524.966136) (xy 57.668564 -525.035671) (xy 57.67655 -525.106545) (xy 57.67655 -525.177867)
			(xy 58.938406 -525.177867) (xy 58.938406 -525.106545) (xy 58.946392 -525.035671) (xy 58.962262 -524.966136)
			(xy 58.985819 -524.898816) (xy 59.016764 -524.834557) (xy 59.05471 -524.774166) (xy 59.099179 -524.718404)
			(xy 59.149612 -524.667971) (xy 59.205374 -524.623502) (xy 59.265765 -524.585556) (xy 59.330024 -524.554611)
			(xy 59.397344 -524.531054) (xy 59.466879 -524.515184) (xy 59.537753 -524.507198) (xy 59.573414 -524.506698)
			(xy 59.609075 -524.507198) (xy 59.679949 -524.515184) (xy 59.749484 -524.531054) (xy 59.816804 -524.554611)
			(xy 59.881063 -524.585556) (xy 59.941454 -524.623502) (xy 59.997216 -524.667971) (xy 60.047649 -524.718404)
			(xy 60.092118 -524.774166) (xy 60.130064 -524.834557) (xy 60.161009 -524.898816) (xy 60.184566 -524.966136)
			(xy 60.200436 -525.035671) (xy 60.208422 -525.106545) (xy 60.208422 -525.177867) (xy 61.74282 -525.177867)
			(xy 61.74282 -525.106545) (xy 61.750806 -525.035671) (xy 61.766676 -524.966136) (xy 61.790233 -524.898816)
			(xy 61.821178 -524.834557) (xy 61.859124 -524.774166) (xy 61.903593 -524.718404) (xy 61.954026 -524.667971)
			(xy 62.009788 -524.623502) (xy 62.070179 -524.585556) (xy 62.134438 -524.554611) (xy 62.201758 -524.531054)
			(xy 62.271293 -524.515184) (xy 62.342167 -524.507198) (xy 62.377828 -524.506698) (xy 62.413489 -524.507198)
			(xy 62.484363 -524.515184) (xy 62.553898 -524.531054) (xy 62.621218 -524.554611) (xy 62.685477 -524.585556)
			(xy 62.745868 -524.623502) (xy 62.80163 -524.667971) (xy 62.852063 -524.718404) (xy 62.896532 -524.774166)
			(xy 62.934478 -524.834557) (xy 62.965423 -524.898816) (xy 62.98898 -524.966136) (xy 63.00485 -525.035671)
			(xy 63.012836 -525.106545) (xy 63.012836 -525.177867) (xy 64.98259 -525.177867) (xy 64.98259 -525.106545)
			(xy 64.990576 -525.035671) (xy 65.006446 -524.966136) (xy 65.030003 -524.898816) (xy 65.060948 -524.834557)
			(xy 65.098894 -524.774166) (xy 65.143363 -524.718404) (xy 65.193796 -524.667971) (xy 65.249558 -524.623502)
			(xy 65.309949 -524.585556) (xy 65.374208 -524.554611) (xy 65.441528 -524.531054) (xy 65.511063 -524.515184)
			(xy 65.581937 -524.507198) (xy 65.617598 -524.506698) (xy 65.653259 -524.507198) (xy 65.724133 -524.515184)
			(xy 65.793668 -524.531054) (xy 65.860988 -524.554611) (xy 65.925247 -524.585556) (xy 65.985638 -524.623502)
			(xy 66.0414 -524.667971) (xy 66.091833 -524.718404) (xy 66.136302 -524.774166) (xy 66.174248 -524.834557)
			(xy 66.205193 -524.898816) (xy 66.22875 -524.966136) (xy 66.24462 -525.035671) (xy 66.252606 -525.106545)
			(xy 66.252606 -525.177867) (xy 67.974202 -525.177867) (xy 67.974202 -525.106545) (xy 67.982188 -525.035671)
			(xy 67.998058 -524.966136) (xy 68.021615 -524.898816) (xy 68.05256 -524.834557) (xy 68.090506 -524.774166)
			(xy 68.134975 -524.718404) (xy 68.185408 -524.667971) (xy 68.24117 -524.623502) (xy 68.301561 -524.585556)
			(xy 68.36582 -524.554611) (xy 68.43314 -524.531054) (xy 68.502675 -524.515184) (xy 68.573549 -524.507198)
			(xy 68.60921 -524.506698) (xy 68.644871 -524.507198) (xy 68.715745 -524.515184) (xy 68.78528 -524.531054)
			(xy 68.8526 -524.554611) (xy 68.916859 -524.585556) (xy 68.97725 -524.623502) (xy 69.033012 -524.667971)
			(xy 69.083445 -524.718404) (xy 69.127914 -524.774166) (xy 69.16586 -524.834557) (xy 69.196805 -524.898816)
			(xy 69.220362 -524.966136) (xy 69.236232 -525.035671) (xy 69.244218 -525.106545) (xy 69.244218 -525.177867)
			(xy 69.236232 -525.248741) (xy 69.220362 -525.318276) (xy 69.196805 -525.385596) (xy 69.16586 -525.449855)
			(xy 69.127914 -525.510246) (xy 69.083445 -525.566008) (xy 69.033012 -525.616441) (xy 68.97725 -525.66091)
			(xy 68.916859 -525.698856) (xy 68.8526 -525.729801) (xy 68.78528 -525.753358) (xy 68.715745 -525.769228)
			(xy 68.644871 -525.777214) (xy 68.573549 -525.777214) (xy 68.502675 -525.769228) (xy 68.43314 -525.753358)
			(xy 68.36582 -525.729801) (xy 68.301561 -525.698856) (xy 68.24117 -525.66091) (xy 68.185408 -525.616441)
			(xy 68.134975 -525.566008) (xy 68.090506 -525.510246) (xy 68.05256 -525.449855) (xy 68.021615 -525.385596)
			(xy 67.998058 -525.318276) (xy 67.982188 -525.248741) (xy 67.974202 -525.177867) (xy 66.252606 -525.177867)
			(xy 66.24462 -525.248741) (xy 66.22875 -525.318276) (xy 66.205193 -525.385596) (xy 66.174248 -525.449855)
			(xy 66.136302 -525.510246) (xy 66.091833 -525.566008) (xy 66.0414 -525.616441) (xy 65.985638 -525.66091)
			(xy 65.925247 -525.698856) (xy 65.860988 -525.729801) (xy 65.793668 -525.753358) (xy 65.724133 -525.769228)
			(xy 65.653259 -525.777214) (xy 65.581937 -525.777214) (xy 65.511063 -525.769228) (xy 65.441528 -525.753358)
			(xy 65.374208 -525.729801) (xy 65.309949 -525.698856) (xy 65.249558 -525.66091) (xy 65.193796 -525.616441)
			(xy 65.143363 -525.566008) (xy 65.098894 -525.510246) (xy 65.060948 -525.449855) (xy 65.030003 -525.385596)
			(xy 65.006446 -525.318276) (xy 64.990576 -525.248741) (xy 64.98259 -525.177867) (xy 63.012836 -525.177867)
			(xy 63.00485 -525.248741) (xy 62.98898 -525.318276) (xy 62.965423 -525.385596) (xy 62.934478 -525.449855)
			(xy 62.896532 -525.510246) (xy 62.852063 -525.566008) (xy 62.80163 -525.616441) (xy 62.745868 -525.66091)
			(xy 62.685477 -525.698856) (xy 62.621218 -525.729801) (xy 62.553898 -525.753358) (xy 62.484363 -525.769228)
			(xy 62.413489 -525.777214) (xy 62.342167 -525.777214) (xy 62.271293 -525.769228) (xy 62.201758 -525.753358)
			(xy 62.134438 -525.729801) (xy 62.070179 -525.698856) (xy 62.009788 -525.66091) (xy 61.954026 -525.616441)
			(xy 61.903593 -525.566008) (xy 61.859124 -525.510246) (xy 61.821178 -525.449855) (xy 61.790233 -525.385596)
			(xy 61.766676 -525.318276) (xy 61.750806 -525.248741) (xy 61.74282 -525.177867) (xy 60.208422 -525.177867)
			(xy 60.200436 -525.248741) (xy 60.184566 -525.318276) (xy 60.161009 -525.385596) (xy 60.130064 -525.449855)
			(xy 60.092118 -525.510246) (xy 60.047649 -525.566008) (xy 59.997216 -525.616441) (xy 59.941454 -525.66091)
			(xy 59.881063 -525.698856) (xy 59.816804 -525.729801) (xy 59.749484 -525.753358) (xy 59.679949 -525.769228)
			(xy 59.609075 -525.777214) (xy 59.537753 -525.777214) (xy 59.466879 -525.769228) (xy 59.397344 -525.753358)
			(xy 59.330024 -525.729801) (xy 59.265765 -525.698856) (xy 59.205374 -525.66091) (xy 59.149612 -525.616441)
			(xy 59.099179 -525.566008) (xy 59.05471 -525.510246) (xy 59.016764 -525.449855) (xy 58.985819 -525.385596)
			(xy 58.962262 -525.318276) (xy 58.946392 -525.248741) (xy 58.938406 -525.177867) (xy 57.67655 -525.177867)
			(xy 57.668564 -525.248741) (xy 57.652694 -525.318276) (xy 57.629137 -525.385596) (xy 57.598192 -525.449855)
			(xy 57.560246 -525.510246) (xy 57.515777 -525.566008) (xy 57.465344 -525.616441) (xy 57.409582 -525.66091)
			(xy 57.349191 -525.698856) (xy 57.284932 -525.729801) (xy 57.217612 -525.753358) (xy 57.148077 -525.769228)
			(xy 57.077203 -525.777214) (xy 57.005881 -525.777214) (xy 56.935007 -525.769228) (xy 56.865472 -525.753358)
			(xy 56.798152 -525.729801) (xy 56.733893 -525.698856) (xy 56.673502 -525.66091) (xy 56.61774 -525.616441)
			(xy 56.567307 -525.566008) (xy 56.522838 -525.510246) (xy 56.484892 -525.449855) (xy 56.453947 -525.385596)
			(xy 56.43039 -525.318276) (xy 56.41452 -525.248741) (xy 56.406534 -525.177867) (xy 36.467343 -525.177867)
			(xy 36.471468 -525.199933) (xy 36.479486 -525.286462) (xy 36.479486 -525.373362) (xy 36.471468 -525.459891)
			(xy 36.4555 -525.545311) (xy 36.431719 -525.628893) (xy 36.400327 -525.709925) (xy 36.361593 -525.787714)
			(xy 36.315846 -525.861598) (xy 36.263477 -525.930945) (xy 36.204933 -525.995165) (xy 36.140713 -526.053709)
			(xy 36.071366 -526.106078) (xy 35.997482 -526.151825) (xy 35.919693 -526.190559) (xy 35.838661 -526.221951)
			(xy 35.755079 -526.245732) (xy 35.669659 -526.2617) (xy 35.58313 -526.269718) (xy 35.49623 -526.269718)
			(xy 35.409701 -526.2617) (xy 35.324281 -526.245732) (xy 35.240699 -526.221951) (xy 35.159667 -526.190559)
			(xy 35.081878 -526.151825) (xy 35.007994 -526.106078) (xy 34.938647 -526.053709) (xy 34.874427 -525.995165)
			(xy 34.815883 -525.930945) (xy 34.763514 -525.861598) (xy 34.717767 -525.787714) (xy 34.679033 -525.709925)
			(xy 34.647641 -525.628893) (xy 34.62386 -525.545311) (xy 34.607892 -525.459891) (xy 34.599874 -525.373362)
			(xy 31.399486 -525.373362) (xy 31.391468 -525.459891) (xy 31.3755 -525.545311) (xy 31.351719 -525.628893)
			(xy 31.320327 -525.709925) (xy 31.281593 -525.787714) (xy 31.235846 -525.861598) (xy 31.183477 -525.930945)
			(xy 31.124933 -525.995165) (xy 31.060713 -526.053709) (xy 30.991366 -526.106078) (xy 30.917482 -526.151825)
			(xy 30.839693 -526.190559) (xy 30.758661 -526.221951) (xy 30.675079 -526.245732) (xy 30.589659 -526.2617)
			(xy 30.50313 -526.269718) (xy 30.41623 -526.269718) (xy 30.329701 -526.2617) (xy 30.244281 -526.245732)
			(xy 30.160699 -526.221951) (xy 30.079667 -526.190559) (xy 30.001878 -526.151825) (xy 29.927994 -526.106078)
			(xy 29.858647 -526.053709) (xy 29.794427 -525.995165) (xy 29.735883 -525.930945) (xy 29.683514 -525.861598)
			(xy 29.637767 -525.787714) (xy 29.599033 -525.709925) (xy 29.567641 -525.628893) (xy 29.54386 -525.545311)
			(xy 29.527892 -525.459891) (xy 29.519874 -525.373362) (xy 1.031828 -525.373362) (xy 1.099423 -525.40702)
			(xy 1.184812 -525.4401) (xy 1.272889 -525.46516) (xy 1.362902 -525.481986) (xy 1.454084 -525.490435)
			(xy 1.49987 -525.490948) (xy 23.50008 -525.490948) (xy 23.563202 -525.491433) (xy 23.689196 -525.499359)
			(xy 23.814444 -525.515182) (xy 23.93845 -525.538839) (xy 24.060727 -525.570236) (xy 24.180791 -525.60925)
			(xy 24.298167 -525.655726) (xy 24.412394 -525.709482) (xy 24.523019 -525.770304) (xy 24.629607 -525.837954)
			(xy 24.731736 -525.912163) (xy 24.829004 -525.992639) (xy 24.921025 -526.079064) (xy 25.007438 -526.171097)
			(xy 25.087902 -526.268376) (xy 25.162097 -526.370515) (xy 25.229732 -526.477111) (xy 25.29054 -526.587745)
			(xy 25.34428 -526.701979) (xy 25.390741 -526.819362) (xy 25.429739 -526.93943) (xy 25.46112 -527.061711)
			(xy 25.48476 -527.185721) (xy 25.500566 -527.310971) (xy 25.508475 -527.436966) (xy 25.508966 -527.500088)
			(xy 25.508966 -528.500086) (xy 25.509507 -528.545875) (xy 25.517982 -528.637061) (xy 25.534832 -528.727076)
			(xy 25.559914 -528.815153) (xy 25.593014 -528.90054) (xy 25.633851 -528.98251) (xy 25.682074 -529.060363)
			(xy 25.737274 -529.133435) (xy 25.79898 -529.201104) (xy 25.866665 -529.262792) (xy 25.939752 -529.317973)
			(xy 26.017618 -529.366176) (xy 26.099598 -529.406991) (xy 26.184994 -529.440069) (xy 26.273077 -529.465128)
			(xy 26.363097 -529.481954) (xy 26.454285 -529.490405) (xy 26.500074 -529.49094)
		)
		(stroke
			(width 0)
			(type solid)
		)
		(fill yes)
		(layer "In5.Cu")
		(net "GND")
	)
	(gr_line
		(start 0 -524.500094)
		(end 0 -5.500116)
		(stroke
			(width 1.016)
			(type default)
		)
		(layer "In6.Cu")
	)
	(gr_arc
		(start 0 -524.500094)
		(mid 0.439393 -525.560749)
		(end 1.500124 -525.999964)
		(stroke
			(width 1.016)
			(type default)
		)
		(layer "In6.Cu")
	)
	(gr_poly
		(pts
			(xy 101.000052 -529.49094) (xy 101.055822 -529.490433) (xy 101.167051 -529.482101) (xy 101.277346 -529.46548)
			(xy 101.38609 -529.440662) (xy 101.492675 -529.407788) (xy 101.596506 -529.367039) (xy 101.697001 -529.318645)
			(xy 101.793598 -529.262876) (xy 101.885758 -529.200044) (xy 101.972964 -529.130501) (xy 102.054729 -529.054635)
			(xy 102.130596 -528.97287) (xy 102.20014 -528.885664) (xy 102.262972 -528.793505) (xy 102.318742 -528.696908)
			(xy 102.367136 -528.596413) (xy 102.407885 -528.492583) (xy 102.44076 -528.385998) (xy 102.465578 -528.277253)
			(xy 102.4822 -528.166959) (xy 102.490533 -528.05573) (xy 102.491032 -527.99996) (xy 102.491032 -1.999996)
			(xy 102.490523 -1.944227) (xy 102.482188 -1.833002) (xy 102.465563 -1.72271) (xy 102.440743 -1.613969)
			(xy 102.407866 -1.507387) (xy 102.367116 -1.40356) (xy 102.31872 -1.303069) (xy 102.26295 -1.206475)
			(xy 102.200118 -1.11432) (xy 102.130574 -1.027117) (xy 102.054708 -0.945356) (xy 101.972944 -0.869492)
			(xy 101.885739 -0.799951) (xy 101.793581 -0.737122) (xy 101.696985 -0.681355) (xy 101.596492 -0.632964)
			(xy 101.492664 -0.592217) (xy 101.386081 -0.559343) (xy 101.277339 -0.534527) (xy 101.167047 -0.517907)
			(xy 101.055821 -0.509575) (xy 101.000052 -0.509016) (xy 26.500074 -0.509016) (xy 26.454278 -0.509546)
			(xy 26.363077 -0.517999) (xy 26.273045 -0.534832) (xy 26.184949 -0.559899) (xy 26.099543 -0.592988)
			(xy 26.017554 -0.633817) (xy 25.939682 -0.682036) (xy 25.866592 -0.737234) (xy 25.798906 -0.798941)
			(xy 25.737202 -0.86663) (xy 25.682007 -0.939724) (xy 25.633792 -1.017598) (xy 25.592968 -1.099589)
			(xy 25.559883 -1.184997) (xy 25.53482 -1.273093) (xy 25.517992 -1.363126) (xy 25.509543 -1.454328)
			(xy 25.508966 -1.500124) (xy 25.508966 -2.500122) (xy 25.50847 -2.563238) (xy 25.500544 -2.689221)
			(xy 25.484723 -2.814458) (xy 25.461069 -2.938455) (xy 25.429676 -3.060721) (xy 25.390668 -3.180775)
			(xy 25.344199 -3.298143) (xy 25.290452 -3.412362) (xy 25.229639 -3.52298) (xy 25.162 -3.629561) (xy 25.087803 -3.731685)
			(xy 25.007339 -3.828949) (xy 24.920927 -3.920968) (xy 24.828907 -4.00738) (xy 24.731644 -4.087844)
			(xy 24.62952 -4.162041) (xy 24.522938 -4.22968) (xy 24.41232 -4.290493) (xy 24.298101 -4.34424) (xy 24.180733 -4.390709)
			(xy 24.060679 -4.429717) (xy 23.938413 -4.46111) (xy 23.814416 -4.484763) (xy 23.689179 -4.500584)
			(xy 23.563196 -4.50851) (xy 23.50008 -4.509008) (xy 1.500124 -4.509008) (xy 1.454327 -4.509537) (xy 1.363123 -4.517988)
			(xy 1.273088 -4.534819) (xy 1.18499 -4.559885) (xy 1.099581 -4.592972) (xy 1.017589 -4.6338) (xy 0.939714 -4.682018)
			(xy 0.86662 -4.737216) (xy 0.798931 -4.798923) (xy 0.737224 -4.866612) (xy 0.682026 -4.939706) (xy 0.633808 -5.017581)
			(xy 0.59298 -5.099573) (xy 0.559893 -5.184982) (xy 0.534827 -5.27308) (xy 0.517996 -5.363115) (xy 0.509545 -5.454319)
			(xy 0.509016 -5.500116) (xy 0.509016 -6.91007) (xy 39.818063 -6.91007) (xy 39.82207 -6.794046) (xy 39.834072 -6.678574)
			(xy 39.854012 -6.564206) (xy 39.881795 -6.451486) (xy 39.917289 -6.340952) (xy 39.960324 -6.233129)
			(xy 40.010695 -6.128532) (xy 40.068162 -6.02766) (xy 40.132452 -5.930993) (xy 40.203257 -5.838992)
			(xy 40.280241 -5.752095) (xy 40.363037 -5.670716) (xy 40.45125 -5.595243) (xy 40.54446 -5.526036)
			(xy 40.642223 -5.463424) (xy 40.744072 -5.407707) (xy 40.849522 -5.359149) (xy 40.958071 -5.317981)
			(xy 41.069202 -5.284401) (xy 41.182385 -5.258568) (xy 41.29708 -5.240605) (xy 41.412742 -5.230597)
			(xy 41.528818 -5.228594) (xy 41.644756 -5.234603) (xy 41.760003 -5.248596) (xy 41.874009 -5.270507)
			(xy 41.986233 -5.300232) (xy 42.096139 -5.337628) (xy 42.203202 -5.382517) (xy 42.306914 -5.434686)
			(xy 42.406779 -5.493886) (xy 42.502322 -5.559835) (xy 42.593088 -5.632218) (xy 42.678643 -5.710691)
			(xy 42.758581 -5.794879) (xy 42.83252 -5.884381) (xy 42.900108 -5.978772) (xy 42.961022 -6.0776)
			(xy 43.014974 -6.180396) (xy 43.061704 -6.286669) (xy 43.100992 -6.395913) (xy 43.132649 -6.507606)
			(xy 43.156525 -6.621218) (xy 43.172506 -6.736206) (xy 43.180515 -6.852023) (xy 43.181016 -6.91007)
			(xy 43.180515 -6.968117) (xy 43.172506 -7.083934) (xy 43.156525 -7.198922) (xy 43.132649 -7.312534)
			(xy 43.100992 -7.424227) (xy 43.061704 -7.533471) (xy 43.014974 -7.639744) (xy 42.961022 -7.74254)
			(xy 42.900108 -7.841368) (xy 42.83252 -7.935759) (xy 42.758581 -8.025261) (xy 42.678643 -8.109449)
			(xy 42.593088 -8.187922) (xy 42.502604 -8.26008) (xy 93.154506 -8.26008) (xy 93.158522 -8.14381)
			(xy 93.170549 -8.028095) (xy 93.190531 -7.913485) (xy 93.218373 -7.800526) (xy 93.253942 -7.689758)
			(xy 93.297068 -7.581707) (xy 93.347545 -7.476889) (xy 93.405134 -7.375804) (xy 93.46956 -7.278932)
			(xy 93.540515 -7.186736) (xy 93.617662 -7.099655) (xy 93.700633 -7.018104) (xy 93.789033 -6.942472)
			(xy 93.88244 -6.873118) (xy 93.980409 -6.810375) (xy 94.082473 -6.754539) (xy 94.188147 -6.705878)
			(xy 94.296926 -6.664624) (xy 94.408291 -6.630973) (xy 94.521714 -6.605085) (xy 94.636651 -6.587084)
			(xy 94.752557 -6.577055) (xy 94.868879 -6.575047) (xy 94.985062 -6.581069) (xy 95.100553 -6.595092)
			(xy 95.214801 -6.61705) (xy 95.327262 -6.646837) (xy 95.4374 -6.684312) (xy 95.54469 -6.729297) (xy 95.648621 -6.781576)
			(xy 95.748697 -6.840901) (xy 95.844443 -6.906989) (xy 95.9354 -6.979525) (xy 96.021136 -7.058164)
			(xy 96.101243 -7.14253) (xy 96.175339 -7.232222) (xy 96.243069 -7.326812) (xy 96.304113 -7.42585)
			(xy 96.358178 -7.528863) (xy 96.405008 -7.63536) (xy 96.444379 -7.744835) (xy 96.476103 -7.856765)
			(xy 96.500029 -7.970617) (xy 96.516043 -8.085849) (xy 96.52407 -8.201911) (xy 96.524572 -8.26008)
			(xy 96.52407 -8.318249) (xy 96.516043 -8.434311) (xy 96.500029 -8.549543) (xy 96.476103 -8.663395)
			(xy 96.444379 -8.775325) (xy 96.405008 -8.8848) (xy 96.358178 -8.991297) (xy 96.304113 -9.09431)
			(xy 96.243069 -9.193348) (xy 96.175339 -9.287938) (xy 96.101243 -9.37763) (xy 96.021136 -9.461996)
			(xy 95.9354 -9.540635) (xy 95.844443 -9.613171) (xy 95.748697 -9.679259) (xy 95.648621 -9.738584)
			(xy 95.54469 -9.790863) (xy 95.4374 -9.835848) (xy 95.327262 -9.873323) (xy 95.214801 -9.90311) (xy 95.100553 -9.925068)
			(xy 94.985062 -9.939091) (xy 94.868879 -9.945113) (xy 94.752557 -9.943105) (xy 94.636651 -9.933076)
			(xy 94.521714 -9.915075) (xy 94.408291 -9.889187) (xy 94.296926 -9.855536) (xy 94.188147 -9.814282)
			(xy 94.082473 -9.765621) (xy 93.980409 -9.709785) (xy 93.88244 -9.647042) (xy 93.789033 -9.577688)
			(xy 93.700633 -9.502056) (xy 93.617662 -9.420505) (xy 93.540515 -9.333424) (xy 93.46956 -9.241228)
			(xy 93.405134 -9.144356) (xy 93.347545 -9.043271) (xy 93.297068 -8.938453) (xy 93.253942 -8.830402)
			(xy 93.218373 -8.719634) (xy 93.190531 -8.606675) (xy 93.170549 -8.492065) (xy 93.158522 -8.37635)
			(xy 93.154506 -8.26008) (xy 42.502604 -8.26008) (xy 42.502322 -8.260305) (xy 42.406779 -8.326254)
			(xy 42.306914 -8.385454) (xy 42.203202 -8.437623) (xy 42.096139 -8.482512) (xy 41.986233 -8.519908)
			(xy 41.874009 -8.549633) (xy 41.760003 -8.571544) (xy 41.644756 -8.585537) (xy 41.528818 -8.591546)
			(xy 41.412742 -8.589543) (xy 41.29708 -8.579535) (xy 41.182385 -8.561572) (xy 41.069202 -8.535739)
			(xy 40.958071 -8.502159) (xy 40.849522 -8.460991) (xy 40.744072 -8.412433) (xy 40.642223 -8.356716)
			(xy 40.54446 -8.294104) (xy 40.45125 -8.224897) (xy 40.363037 -8.149424) (xy 40.280241 -8.068045)
			(xy 40.203257 -7.981148) (xy 40.132452 -7.889147) (xy 40.068162 -7.79248) (xy 40.010695 -7.691608)
			(xy 39.960324 -7.587011) (xy 39.917289 -7.479188) (xy 39.881795 -7.368654) (xy 39.854012 -7.255934)
			(xy 39.834072 -7.141566) (xy 39.82207 -7.026094) (xy 39.818063 -6.91007) (xy 0.509016 -6.91007) (xy 0.509016 -15.228062)
			(xy 1.150624 -15.228062) (xy 1.154655 -15.098496) (xy 1.166734 -14.969432) (xy 1.186813 -14.841368)
			(xy 1.214815 -14.714801) (xy 1.250632 -14.590218) (xy 1.294124 -14.468104) (xy 1.345124 -14.34893)
			(xy 1.403435 -14.233157) (xy 1.46883 -14.121233) (xy 1.541057 -14.013591) (xy 1.619837 -13.910648)
			(xy 1.704864 -13.812802) (xy 1.795809 -13.72043) (xy 1.892321 -13.633892) (xy 1.994027 -13.553521)
			(xy 2.100533 -13.479629) (xy 2.211426 -13.412501) (xy 2.326278 -13.352397) (xy 2.444645 -13.29955)
			(xy 2.566068 -13.254163) (xy 2.690078 -13.216414) (xy 2.816195 -13.186447) (xy 2.943931 -13.164378)
			(xy 3.072792 -13.150294) (xy 3.202279 -13.144248) (xy 3.331892 -13.146264) (xy 3.461128 -13.156334)
			(xy 3.589489 -13.174419) (xy 3.716477 -13.200449) (xy 3.841601 -13.234324) (xy 3.964377 -13.275912)
			(xy 4.08433 -13.325053) (xy 4.200995 -13.381556) (xy 4.313923 -13.445203) (xy 4.422675 -13.515747)
			(xy 4.526831 -13.592916) (xy 4.625988 -13.676411) (xy 4.719762 -13.765909) (xy 4.807791 -13.861064)
			(xy 4.889734 -13.961507) (xy 4.965273 -14.06685) (xy 5.034118 -14.176686) (xy 5.096001 -14.29059)
			(xy 5.150682 -14.40812) (xy 5.197952 -14.528823) (xy 5.237625 -14.652231) (xy 5.26955 -14.777867)
			(xy 5.293602 -14.905244) (xy 5.309689 -15.03387) (xy 5.317748 -15.163248) (xy 5.318252 -15.228062)
			(xy 12.580624 -15.228062) (xy 12.584655 -15.098496) (xy 12.596734 -14.969432) (xy 12.616813 -14.841368)
			(xy 12.644815 -14.714801) (xy 12.680632 -14.590218) (xy 12.724124 -14.468104) (xy 12.775124 -14.34893)
			(xy 12.833435 -14.233157) (xy 12.89883 -14.121233) (xy 12.971057 -14.013591) (xy 13.049837 -13.910648)
			(xy 13.134864 -13.812802) (xy 13.225809 -13.72043) (xy 13.322321 -13.633892) (xy 13.424027 -13.553521)
			(xy 13.530533 -13.479629) (xy 13.641426 -13.412501) (xy 13.756278 -13.352397) (xy 13.874645 -13.29955)
			(xy 13.996068 -13.254163) (xy 14.120078 -13.216414) (xy 14.246195 -13.186447) (xy 14.373931 -13.164378)
			(xy 14.502792 -13.150294) (xy 14.632279 -13.144248) (xy 14.761892 -13.146264) (xy 14.891128 -13.156334)
			(xy 15.019489 -13.174419) (xy 15.146477 -13.200449) (xy 15.271601 -13.234324) (xy 15.394377 -13.275912)
			(xy 15.51433 -13.325053) (xy 15.630995 -13.381556) (xy 15.743923 -13.445203) (xy 15.852675 -13.515747)
			(xy 15.956831 -13.592916) (xy 16.055988 -13.676411) (xy 16.149762 -13.765909) (xy 16.237791 -13.861064)
			(xy 16.319734 -13.961507) (xy 16.395273 -14.06685) (xy 16.464118 -14.176686) (xy 16.526001 -14.29059)
			(xy 16.580682 -14.40812) (xy 16.627952 -14.528823) (xy 16.667625 -14.652231) (xy 16.69955 -14.777867)
			(xy 16.723602 -14.905244) (xy 16.739689 -15.03387) (xy 16.747748 -15.163248) (xy 16.748252 -15.228062)
			(xy 16.747748 -15.292876) (xy 16.739689 -15.422254) (xy 16.723602 -15.55088) (xy 16.69955 -15.678257)
			(xy 16.667625 -15.803893) (xy 16.627952 -15.927301) (xy 16.580682 -16.048004) (xy 16.526001 -16.165534)
			(xy 16.464118 -16.279438) (xy 16.395273 -16.389274) (xy 16.319734 -16.494617) (xy 16.237791 -16.59506)
			(xy 16.149762 -16.690215) (xy 16.055988 -16.779713) (xy 15.956831 -16.863208) (xy 15.852675 -16.940377)
			(xy 15.743923 -17.010921) (xy 15.630995 -17.074568) (xy 15.51433 -17.131071) (xy 15.394377 -17.180212)
			(xy 15.271601 -17.2218) (xy 15.146477 -17.255675) (xy 15.019489 -17.281705) (xy 14.891128 -17.29979)
			(xy 14.761892 -17.30986) (xy 14.632279 -17.311876) (xy 14.502792 -17.30583) (xy 14.373931 -17.291746)
			(xy 14.246195 -17.269677) (xy 14.120078 -17.23971) (xy 13.996068 -17.201961) (xy 13.874645 -17.156574)
			(xy 13.756278 -17.103727) (xy 13.641426 -17.043623) (xy 13.530533 -16.976495) (xy 13.424027 -16.902603)
			(xy 13.322321 -16.822232) (xy 13.225809 -16.735694) (xy 13.134864 -16.643322) (xy 13.049837 -16.545476)
			(xy 12.971057 -16.442533) (xy 12.89883 -16.334891) (xy 12.833435 -16.222967) (xy 12.775124 -16.107194)
			(xy 12.724124 -15.98802) (xy 12.680632 -15.865906) (xy 12.644815 -15.741323) (xy 12.616813 -15.614756)
			(xy 12.596734 -15.486692) (xy 12.584655 -15.357628) (xy 12.580624 -15.228062) (xy 5.318252 -15.228062)
			(xy 5.317748 -15.292876) (xy 5.309689 -15.422254) (xy 5.293602 -15.55088) (xy 5.26955 -15.678257)
			(xy 5.237625 -15.803893) (xy 5.197952 -15.927301) (xy 5.150682 -16.048004) (xy 5.096001 -16.165534)
			(xy 5.034118 -16.279438) (xy 4.965273 -16.389274) (xy 4.889734 -16.494617) (xy 4.807791 -16.59506)
			(xy 4.719762 -16.690215) (xy 4.625988 -16.779713) (xy 4.526831 -16.863208) (xy 4.422675 -16.940377)
			(xy 4.313923 -17.010921) (xy 4.200995 -17.074568) (xy 4.08433 -17.131071) (xy 3.964377 -17.180212)
			(xy 3.841601 -17.2218) (xy 3.716477 -17.255675) (xy 3.589489 -17.281705) (xy 3.461128 -17.29979)
			(xy 3.331892 -17.30986) (xy 3.202279 -17.311876) (xy 3.072792 -17.30583) (xy 2.943931 -17.291746)
			(xy 2.816195 -17.269677) (xy 2.690078 -17.23971) (xy 2.566068 -17.201961) (xy 2.444645 -17.156574)
			(xy 2.326278 -17.103727) (xy 2.211426 -17.043623) (xy 2.100533 -16.976495) (xy 1.994027 -16.902603)
			(xy 1.892321 -16.822232) (xy 1.795809 -16.735694) (xy 1.704864 -16.643322) (xy 1.619837 -16.545476)
			(xy 1.541057 -16.442533) (xy 1.46883 -16.334891) (xy 1.403435 -16.222967) (xy 1.345124 -16.107194)
			(xy 1.294124 -15.98802) (xy 1.250632 -15.865906) (xy 1.214815 -15.741323) (xy 1.186813 -15.614756)
			(xy 1.166734 -15.486692) (xy 1.154655 -15.357628) (xy 1.150624 -15.228062) (xy 0.509016 -15.228062)
			(xy 0.509016 -20.01012) (xy 86.877404 -20.01012) (xy 86.881424 -19.819469) (xy 86.893478 -19.629156)
			(xy 86.913544 -19.439521) (xy 86.941587 -19.2509) (xy 86.977556 -19.06363) (xy 87.021388 -18.878042)
			(xy 87.073005 -18.694467) (xy 87.132315 -18.513231) (xy 87.199213 -18.334656) (xy 87.273579 -18.159061)
			(xy 87.355281 -17.986756) (xy 87.444175 -17.818049) (xy 87.540101 -17.653239) (xy 87.64289 -17.49262)
			(xy 87.752359 -17.336477) (xy 87.868313 -17.185088) (xy 87.990547 -17.038721) (xy 88.118841 -16.897637)
			(xy 88.252969 -16.762088) (xy 88.392693 -16.632313) (xy 88.537763 -16.508543) (xy 88.687921 -16.391)
			(xy 88.842902 -16.279891) (xy 89.002429 -16.175414) (xy 89.166218 -16.077755) (xy 89.333978 -15.987088)
			(xy 89.505412 -15.903574) (xy 89.680214 -15.827361) (xy 89.858073 -15.758585) (xy 90.038674 -15.697367)
			(xy 90.221694 -15.643818) (xy 90.40681 -15.598032) (xy 90.593691 -15.56009) (xy 90.782006 -15.530061)
			(xy 90.971419 -15.507996) (xy 91.161593 -15.493937) (xy 91.352192 -15.487907) (xy 91.542875 -15.489917)
			(xy 91.733304 -15.499964) (xy 91.92314 -15.51803) (xy 92.112046 -15.544083) (xy 92.299685 -15.578076)
			(xy 92.485725 -15.619949) (xy 92.669834 -15.669628) (xy 92.851685 -15.727024) (xy 93.030955 -15.792035)
			(xy 93.207325 -15.864546) (xy 93.380481 -15.944427) (xy 93.550116 -16.031537) (xy 93.715928 -16.125721)
			(xy 93.877622 -16.226812) (xy 94.03491 -16.334628) (xy 94.187513 -16.44898) (xy 94.335161 -16.569663)
			(xy 94.477589 -16.696464) (xy 94.614545 -16.829155) (xy 94.745786 -16.967503) (xy 94.871078 -17.11126)
			(xy 94.990198 -17.260171) (xy 95.102934 -17.413972) (xy 95.209087 -17.572388) (xy 95.308467 -17.735139)
			(xy 95.400897 -17.901934) (xy 95.486214 -18.072478) (xy 95.564266 -18.246466) (xy 95.634913 -18.423591)
			(xy 95.698031 -18.603536) (xy 95.753507 -18.785982) (xy 95.801242 -18.970605) (xy 95.841152 -19.157075)
			(xy 95.873165 -19.345063) (xy 95.897225 -19.534233) (xy 95.913288 -19.724249) (xy 95.921327 -19.914773)
			(xy 95.92183 -20.01012) (xy 95.921327 -20.105467) (xy 95.913288 -20.295991) (xy 95.897225 -20.486007)
			(xy 95.873165 -20.675177) (xy 95.841152 -20.863165) (xy 95.801242 -21.049635) (xy 95.753507 -21.234258)
			(xy 95.698031 -21.416704) (xy 95.634913 -21.596649) (xy 95.564266 -21.773774) (xy 95.486214 -21.947762)
			(xy 95.400897 -22.118306) (xy 95.308467 -22.285101) (xy 95.209087 -22.447852) (xy 95.102934 -22.606268)
			(xy 94.990198 -22.760069) (xy 94.871078 -22.90898) (xy 94.745786 -23.052737) (xy 94.614545 -23.191085)
			(xy 94.477589 -23.323776) (xy 94.335161 -23.450577) (xy 94.187513 -23.57126) (xy 94.03491 -23.685612)
			(xy 93.877622 -23.793428) (xy 93.715928 -23.894519) (xy 93.550116 -23.988703) (xy 93.380481 -24.075813)
			(xy 93.207325 -24.155694) (xy 93.030955 -24.228205) (xy 92.851685 -24.293216) (xy 92.669834 -24.350612)
			(xy 92.485725 -24.400291) (xy 92.299685 -24.442164) (xy 92.112046 -24.476157) (xy 91.92314 -24.50221)
			(xy 91.733304 -24.520276) (xy 91.542875 -24.530323) (xy 91.352192 -24.532333) (xy 91.161593 -24.526303)
			(xy 90.971419 -24.512244) (xy 90.782006 -24.490179) (xy 90.593691 -24.46015) (xy 90.40681 -24.422208)
			(xy 90.221694 -24.376422) (xy 90.038674 -24.322873) (xy 89.858073 -24.261655) (xy 89.680214 -24.192879)
			(xy 89.505412 -24.116666) (xy 89.333978 -24.033152) (xy 89.166218 -23.942485) (xy 89.002429 -23.844826)
			(xy 88.842902 -23.740349) (xy 88.687921 -23.62924) (xy 88.537763 -23.511697) (xy 88.392693 -23.387927)
			(xy 88.252969 -23.258152) (xy 88.118841 -23.122603) (xy 87.990547 -22.981519) (xy 87.868313 -22.835152)
			(xy 87.752359 -22.683763) (xy 87.64289 -22.52762) (xy 87.540101 -22.367001) (xy 87.444175 -22.202191)
			(xy 87.355281 -22.033484) (xy 87.273579 -21.861179) (xy 87.199213 -21.685584) (xy 87.132315 -21.507009)
			(xy 87.073005 -21.325773) (xy 87.021388 -21.142198) (xy 86.977556 -20.95661) (xy 86.941587 -20.76934)
			(xy 86.913544 -20.580719) (xy 86.893478 -20.391084) (xy 86.881424 -20.200771) (xy 86.877404 -20.01012)
			(xy 0.509016 -20.01012) (xy 0.509016 -29.19984) (xy 14.086591 -29.19984) (xy 14.090616 -29.057648)
			(xy 14.102679 -28.915912) (xy 14.122742 -28.775086) (xy 14.15074 -28.63562) (xy 14.186584 -28.497961)
			(xy 14.230158 -28.362551) (xy 14.281323 -28.229823) (xy 14.339916 -28.100202) (xy 14.405747 -27.974104)
			(xy 14.478608 -27.851932) (xy 14.558263 -27.734078) (xy 14.644459 -27.620919) (xy 14.736918 -27.512817)
			(xy 14.835346 -27.41012) (xy 14.939425 -27.313156) (xy 15.048824 -27.222236) (xy 15.163192 -27.13765)
			(xy 15.282161 -27.05967) (xy 15.405352 -26.988546) (xy 15.532369 -26.924505) (xy 15.662806 -26.867753)
			(xy 15.796245 -26.818471) (xy 15.932258 -26.776817) (xy 16.07041 -26.742925) (xy 16.210259 -26.716904)
			(xy 16.351355 -26.698836) (xy 16.493247 -26.688779) (xy 16.635482 -26.686766) (xy 16.777602 -26.692803)
			(xy 16.919153 -26.706871) (xy 17.059682 -26.728925) (xy 17.198737 -26.758894) (xy 17.335875 -26.796682)
			(xy 17.470655 -26.842168) (xy 17.602646 -26.895206) (xy 17.731425 -26.955627) (xy 17.856579 -27.023236)
			(xy 17.977707 -27.097818) (xy 18.094423 -27.179134) (xy 18.206351 -27.266922) (xy 18.313133 -27.360902)
			(xy 18.414427 -27.460772) (xy 18.509908 -27.566214) (xy 18.599272 -27.676888) (xy 18.68223 -27.792441)
			(xy 18.758519 -27.912502) (xy 18.827893 -28.036687) (xy 18.89013 -28.164598) (xy 18.945031 -28.295825)
			(xy 18.992419 -28.429948) (xy 19.032144 -28.566537) (xy 19.064077 -28.705155) (xy 19.088118 -28.845357)
			(xy 19.104187 -28.986695) (xy 19.112235 -29.128716) (xy 19.112738 -29.19984) (xy 19.112235 -29.270964)
			(xy 19.104187 -29.412985) (xy 19.088118 -29.554323) (xy 19.064077 -29.694525) (xy 19.032144 -29.833143)
			(xy 18.992419 -29.969732) (xy 18.945031 -30.103855) (xy 18.89013 -30.235082) (xy 18.827893 -30.362993)
			(xy 18.758519 -30.487178) (xy 18.68223 -30.607239) (xy 18.599272 -30.722792) (xy 18.509908 -30.833466)
			(xy 18.414427 -30.938908) (xy 18.313133 -31.038778) (xy 18.206351 -31.132758) (xy 18.094423 -31.220546)
			(xy 17.977707 -31.301862) (xy 17.856579 -31.376444) (xy 17.731425 -31.444053) (xy 17.602646 -31.504474)
			(xy 17.470655 -31.557512) (xy 17.335875 -31.602998) (xy 17.198737 -31.640786) (xy 17.059682 -31.670755)
			(xy 16.919153 -31.692809) (xy 16.777602 -31.706877) (xy 16.635482 -31.712914) (xy 16.493247 -31.710901)
			(xy 16.351355 -31.700844) (xy 16.210259 -31.682776) (xy 16.07041 -31.656755) (xy 15.932258 -31.622863)
			(xy 15.796245 -31.581209) (xy 15.662806 -31.531927) (xy 15.532369 -31.475175) (xy 15.405352 -31.411134)
			(xy 15.282161 -31.34001) (xy 15.163192 -31.26203) (xy 15.048824 -31.177444) (xy 14.939425 -31.086524)
			(xy 14.835346 -30.98956) (xy 14.736918 -30.886863) (xy 14.644459 -30.778761) (xy 14.558263 -30.665602)
			(xy 14.478608 -30.547748) (xy 14.405747 -30.425576) (xy 14.339916 -30.299478) (xy 14.281323 -30.169857)
			(xy 14.230158 -30.037129) (xy 14.186584 -29.901719) (xy 14.15074 -29.76406) (xy 14.122742 -29.624594)
			(xy 14.102679 -29.483768) (xy 14.090616 -29.342032) (xy 14.086591 -29.19984) (xy 0.509016 -29.19984)
			(xy 0.509016 -32.29991) (xy 75.486519 -32.29991) (xy 75.490544 -32.157718) (xy 75.502607 -32.015982)
			(xy 75.52267 -31.875156) (xy 75.550668 -31.73569) (xy 75.586512 -31.598031) (xy 75.630086 -31.462621)
			(xy 75.681251 -31.329893) (xy 75.739844 -31.200272) (xy 75.805675 -31.074174) (xy 75.878536 -30.952002)
			(xy 75.958191 -30.834148) (xy 76.044387 -30.720989) (xy 76.136846 -30.612887) (xy 76.235274 -30.51019)
			(xy 76.339353 -30.413226) (xy 76.448752 -30.322306) (xy 76.56312 -30.23772) (xy 76.682089 -30.15974)
			(xy 76.80528 -30.088616) (xy 76.932297 -30.024575) (xy 77.062734 -29.967823) (xy 77.196173 -29.918541)
			(xy 77.332186 -29.876887) (xy 77.470338 -29.842995) (xy 77.610187 -29.816974) (xy 77.751283 -29.798906)
			(xy 77.893175 -29.788849) (xy 78.03541 -29.786836) (xy 78.17753 -29.792873) (xy 78.319081 -29.806941)
			(xy 78.45961 -29.828995) (xy 78.598665 -29.858964) (xy 78.735803 -29.896752) (xy 78.870583 -29.942238)
			(xy 79.002574 -29.995276) (xy 79.131353 -30.055697) (xy 79.256507 -30.123306) (xy 79.377635 -30.197888)
			(xy 79.494351 -30.279204) (xy 79.606279 -30.366992) (xy 79.713061 -30.460972) (xy 79.814355 -30.560842)
			(xy 79.909836 -30.666284) (xy 79.9992 -30.776958) (xy 80.082158 -30.892511) (xy 80.158447 -31.012572)
			(xy 80.227821 -31.136757) (xy 80.290058 -31.264668) (xy 80.344959 -31.395895) (xy 80.392347 -31.530018)
			(xy 80.432072 -31.666607) (xy 80.464005 -31.805225) (xy 80.488046 -31.945427) (xy 80.504115 -32.086765)
			(xy 80.512163 -32.228786) (xy 80.512666 -32.29991) (xy 80.512163 -32.371034) (xy 80.504115 -32.513055)
			(xy 80.488046 -32.654393) (xy 80.464005 -32.794595) (xy 80.432072 -32.933213) (xy 80.392347 -33.069802)
			(xy 80.344959 -33.203925) (xy 80.290058 -33.335152) (xy 80.227821 -33.463063) (xy 80.158447 -33.587248)
			(xy 80.082158 -33.707309) (xy 79.9992 -33.822862) (xy 79.909836 -33.933536) (xy 79.814355 -34.038978)
			(xy 79.713061 -34.138848) (xy 79.606279 -34.232828) (xy 79.494351 -34.320616) (xy 79.377635 -34.401932)
			(xy 79.256507 -34.476514) (xy 79.131353 -34.544123) (xy 79.002574 -34.604544) (xy 78.870583 -34.657582)
			(xy 78.735803 -34.703068) (xy 78.598665 -34.740856) (xy 78.45961 -34.770825) (xy 78.319081 -34.792879)
			(xy 78.17753 -34.806947) (xy 78.03541 -34.812984) (xy 77.893175 -34.810971) (xy 77.751283 -34.800914)
			(xy 77.610187 -34.782846) (xy 77.470338 -34.756825) (xy 77.332186 -34.722933) (xy 77.196173 -34.681279)
			(xy 77.062734 -34.631997) (xy 76.932297 -34.575245) (xy 76.80528 -34.511204) (xy 76.682089 -34.44008)
			(xy 76.56312 -34.3621) (xy 76.448752 -34.277514) (xy 76.339353 -34.186594) (xy 76.235274 -34.08963)
			(xy 76.136846 -33.986933) (xy 76.044387 -33.878831) (xy 75.958191 -33.765672) (xy 75.878536 -33.647818)
			(xy 75.805675 -33.525646) (xy 75.739844 -33.399548) (xy 75.681251 -33.269927) (xy 75.630086 -33.137199)
			(xy 75.586512 -33.001789) (xy 75.550668 -32.86413) (xy 75.52267 -32.724664) (xy 75.502607 -32.583838)
			(xy 75.490544 -32.442102) (xy 75.486519 -32.29991) (xy 0.509016 -32.29991) (xy 0.509016 -46.221904)
			(xy 1.150624 -46.221904) (xy 1.154655 -46.092338) (xy 1.166734 -45.963274) (xy 1.186813 -45.83521)
			(xy 1.214815 -45.708643) (xy 1.250632 -45.58406) (xy 1.294124 -45.461946) (xy 1.345124 -45.342772)
			(xy 1.403435 -45.226999) (xy 1.46883 -45.115075) (xy 1.541057 -45.007433) (xy 1.619837 -44.90449)
			(xy 1.704864 -44.806644) (xy 1.795809 -44.714272) (xy 1.892321 -44.627734) (xy 1.994027 -44.547363)
			(xy 2.100533 -44.473471) (xy 2.211426 -44.406343) (xy 2.326278 -44.346239) (xy 2.444645 -44.293392)
			(xy 2.566068 -44.248005) (xy 2.690078 -44.210256) (xy 2.816195 -44.180289) (xy 2.943931 -44.15822)
			(xy 3.072792 -44.144136) (xy 3.202279 -44.13809) (xy 3.331892 -44.140106) (xy 3.461128 -44.150176)
			(xy 3.589489 -44.168261) (xy 3.716477 -44.194291) (xy 3.841601 -44.228166) (xy 3.964377 -44.269754)
			(xy 4.08433 -44.318895) (xy 4.200995 -44.375398) (xy 4.313923 -44.439045) (xy 4.422675 -44.509589)
			(xy 4.526831 -44.586758) (xy 4.625988 -44.670253) (xy 4.719762 -44.759751) (xy 4.807791 -44.854906)
			(xy 4.889734 -44.955349) (xy 4.965273 -45.060692) (xy 5.034118 -45.170528) (xy 5.096001 -45.284432)
			(xy 5.150682 -45.401962) (xy 5.197952 -45.522665) (xy 5.237625 -45.646073) (xy 5.26955 -45.771709)
			(xy 5.293602 -45.899086) (xy 5.309689 -46.027712) (xy 5.317748 -46.15709) (xy 5.318252 -46.221904)
			(xy 12.580624 -46.221904) (xy 12.584655 -46.092338) (xy 12.596734 -45.963274) (xy 12.616813 -45.83521)
			(xy 12.644815 -45.708643) (xy 12.680632 -45.58406) (xy 12.724124 -45.461946) (xy 12.775124 -45.342772)
			(xy 12.833435 -45.226999) (xy 12.89883 -45.115075) (xy 12.971057 -45.007433) (xy 13.049837 -44.90449)
			(xy 13.134864 -44.806644) (xy 13.225809 -44.714272) (xy 13.322321 -44.627734) (xy 13.424027 -44.547363)
			(xy 13.530533 -44.473471) (xy 13.641426 -44.406343) (xy 13.756278 -44.346239) (xy 13.874645 -44.293392)
			(xy 13.996068 -44.248005) (xy 14.120078 -44.210256) (xy 14.246195 -44.180289) (xy 14.373931 -44.15822)
			(xy 14.502792 -44.144136) (xy 14.632279 -44.13809) (xy 14.761892 -44.140106) (xy 14.891128 -44.150176)
			(xy 15.019489 -44.168261) (xy 15.146477 -44.194291) (xy 15.271601 -44.228166) (xy 15.394377 -44.269754)
			(xy 15.51433 -44.318895) (xy 15.630995 -44.375398) (xy 15.743923 -44.439045) (xy 15.852675 -44.509589)
			(xy 15.956831 -44.586758) (xy 16.055988 -44.670253) (xy 16.149762 -44.759751) (xy 16.237791 -44.854906)
			(xy 16.319734 -44.955349) (xy 16.395273 -45.060692) (xy 16.464118 -45.170528) (xy 16.526001 -45.284432)
			(xy 16.580682 -45.401962) (xy 16.627952 -45.522665) (xy 16.667625 -45.646073) (xy 16.69955 -45.771709)
			(xy 16.723602 -45.899086) (xy 16.739689 -46.027712) (xy 16.747748 -46.15709) (xy 16.748252 -46.221904)
			(xy 16.747748 -46.286718) (xy 16.739689 -46.416096) (xy 16.723602 -46.544722) (xy 16.69955 -46.672099)
			(xy 16.667625 -46.797735) (xy 16.627952 -46.921143) (xy 16.580682 -47.041846) (xy 16.526001 -47.159376)
			(xy 16.464118 -47.27328) (xy 16.395273 -47.383116) (xy 16.319734 -47.488459) (xy 16.237791 -47.588902)
			(xy 16.149762 -47.684057) (xy 16.055988 -47.773555) (xy 15.956831 -47.85705) (xy 15.852675 -47.934219)
			(xy 15.743923 -48.004763) (xy 15.630995 -48.06841) (xy 15.51433 -48.124913) (xy 15.394377 -48.174054)
			(xy 15.271601 -48.215642) (xy 15.146477 -48.249517) (xy 15.019489 -48.275547) (xy 14.891128 -48.293632)
			(xy 14.761892 -48.303702) (xy 14.632279 -48.305718) (xy 14.502792 -48.299672) (xy 14.373931 -48.285588)
			(xy 14.246195 -48.263519) (xy 14.120078 -48.233552) (xy 13.996068 -48.195803) (xy 13.874645 -48.150416)
			(xy 13.756278 -48.097569) (xy 13.641426 -48.037465) (xy 13.530533 -47.970337) (xy 13.424027 -47.896445)
			(xy 13.322321 -47.816074) (xy 13.225809 -47.729536) (xy 13.134864 -47.637164) (xy 13.049837 -47.539318)
			(xy 12.971057 -47.436375) (xy 12.89883 -47.328733) (xy 12.833435 -47.216809) (xy 12.775124 -47.101036)
			(xy 12.724124 -46.981862) (xy 12.680632 -46.859748) (xy 12.644815 -46.735165) (xy 12.616813 -46.608598)
			(xy 12.596734 -46.480534) (xy 12.584655 -46.35147) (xy 12.580624 -46.221904) (xy 5.318252 -46.221904)
			(xy 5.317748 -46.286718) (xy 5.309689 -46.416096) (xy 5.293602 -46.544722) (xy 5.26955 -46.672099)
			(xy 5.237625 -46.797735) (xy 5.197952 -46.921143) (xy 5.150682 -47.041846) (xy 5.096001 -47.159376)
			(xy 5.034118 -47.27328) (xy 4.965273 -47.383116) (xy 4.889734 -47.488459) (xy 4.807791 -47.588902)
			(xy 4.719762 -47.684057) (xy 4.625988 -47.773555) (xy 4.526831 -47.85705) (xy 4.422675 -47.934219)
			(xy 4.313923 -48.004763) (xy 4.200995 -48.06841) (xy 4.08433 -48.124913) (xy 3.964377 -48.174054)
			(xy 3.841601 -48.215642) (xy 3.716477 -48.249517) (xy 3.589489 -48.275547) (xy 3.461128 -48.293632)
			(xy 3.331892 -48.303702) (xy 3.202279 -48.305718) (xy 3.072792 -48.299672) (xy 2.943931 -48.285588)
			(xy 2.816195 -48.263519) (xy 2.690078 -48.233552) (xy 2.566068 -48.195803) (xy 2.444645 -48.150416)
			(xy 2.326278 -48.097569) (xy 2.211426 -48.037465) (xy 2.100533 -47.970337) (xy 1.994027 -47.896445)
			(xy 1.892321 -47.816074) (xy 1.795809 -47.729536) (xy 1.704864 -47.637164) (xy 1.619837 -47.539318)
			(xy 1.541057 -47.436375) (xy 1.46883 -47.328733) (xy 1.403435 -47.216809) (xy 1.345124 -47.101036)
			(xy 1.294124 -46.981862) (xy 1.250632 -46.859748) (xy 1.214815 -46.735165) (xy 1.186813 -46.608598)
			(xy 1.166734 -46.480534) (xy 1.154655 -46.35147) (xy 1.150624 -46.221904) (xy 0.509016 -46.221904)
			(xy 0.509016 -51.36007) (xy 39.818063 -51.36007) (xy 39.82207 -51.244046) (xy 39.834072 -51.128574)
			(xy 39.854012 -51.014206) (xy 39.881795 -50.901486) (xy 39.917289 -50.790952) (xy 39.960324 -50.683129)
			(xy 40.010695 -50.578532) (xy 40.068162 -50.47766) (xy 40.132452 -50.380993) (xy 40.203257 -50.288992)
			(xy 40.280241 -50.202095) (xy 40.363037 -50.120716) (xy 40.45125 -50.045243) (xy 40.54446 -49.976036)
			(xy 40.642223 -49.913424) (xy 40.744072 -49.857707) (xy 40.849522 -49.809149) (xy 40.958071 -49.767981)
			(xy 41.069202 -49.734401) (xy 41.182385 -49.708568) (xy 41.29708 -49.690605) (xy 41.412742 -49.680597)
			(xy 41.528818 -49.678594) (xy 41.644756 -49.684603) (xy 41.760003 -49.698596) (xy 41.874009 -49.720507)
			(xy 41.986233 -49.750232) (xy 42.096139 -49.787628) (xy 42.203202 -49.832517) (xy 42.306914 -49.884686)
			(xy 42.406779 -49.943886) (xy 42.502322 -50.009835) (xy 42.593088 -50.082218) (xy 42.678643 -50.160691)
			(xy 42.758581 -50.244879) (xy 42.83252 -50.334381) (xy 42.900108 -50.428772) (xy 42.961022 -50.5276)
			(xy 43.014974 -50.630396) (xy 43.061704 -50.736669) (xy 43.100992 -50.845913) (xy 43.132649 -50.957606)
			(xy 43.156525 -51.071218) (xy 43.172506 -51.186206) (xy 43.180515 -51.302023) (xy 43.181016 -51.36007)
			(xy 43.180515 -51.418117) (xy 43.172506 -51.533934) (xy 43.156525 -51.648922) (xy 43.132649 -51.762534)
			(xy 43.100992 -51.874227) (xy 43.061704 -51.983471) (xy 43.014974 -52.089744) (xy 42.961022 -52.19254)
			(xy 42.900108 -52.291368) (xy 42.83252 -52.385759) (xy 42.758581 -52.475261) (xy 42.678643 -52.559449)
			(xy 42.593088 -52.637922) (xy 42.502604 -52.71008) (xy 93.154506 -52.71008) (xy 93.158522 -52.59381)
			(xy 93.170549 -52.478095) (xy 93.190531 -52.363485) (xy 93.218373 -52.250526) (xy 93.253942 -52.139758)
			(xy 93.297068 -52.031707) (xy 93.347545 -51.926889) (xy 93.405134 -51.825804) (xy 93.46956 -51.728932)
			(xy 93.540515 -51.636736) (xy 93.617662 -51.549655) (xy 93.700633 -51.468104) (xy 93.789033 -51.392472)
			(xy 93.88244 -51.323118) (xy 93.980409 -51.260375) (xy 94.082473 -51.204539) (xy 94.188147 -51.155878)
			(xy 94.296926 -51.114624) (xy 94.408291 -51.080973) (xy 94.521714 -51.055085) (xy 94.636651 -51.037084)
			(xy 94.752557 -51.027055) (xy 94.868879 -51.025047) (xy 94.985062 -51.031069) (xy 95.100553 -51.045092)
			(xy 95.214801 -51.06705) (xy 95.327262 -51.096837) (xy 95.4374 -51.134312) (xy 95.54469 -51.179297)
			(xy 95.648621 -51.231576) (xy 95.748697 -51.290901) (xy 95.844443 -51.356989) (xy 95.9354 -51.429525)
			(xy 96.021136 -51.508164) (xy 96.101243 -51.59253) (xy 96.175339 -51.682222) (xy 96.243069 -51.776812)
			(xy 96.304113 -51.87585) (xy 96.358178 -51.978863) (xy 96.405008 -52.08536) (xy 96.444379 -52.194835)
			(xy 96.476103 -52.306765) (xy 96.500029 -52.420617) (xy 96.516043 -52.535849) (xy 96.52407 -52.651911)
			(xy 96.524572 -52.71008) (xy 96.52407 -52.768249) (xy 96.516043 -52.884311) (xy 96.500029 -52.999543)
			(xy 96.476103 -53.113395) (xy 96.444379 -53.225325) (xy 96.405008 -53.3348) (xy 96.358178 -53.441297)
			(xy 96.304113 -53.54431) (xy 96.243069 -53.643348) (xy 96.175339 -53.737938) (xy 96.101243 -53.82763)
			(xy 96.021136 -53.911996) (xy 95.9354 -53.990635) (xy 95.844443 -54.063171) (xy 95.748697 -54.129259)
			(xy 95.648621 -54.188584) (xy 95.54469 -54.240863) (xy 95.4374 -54.285848) (xy 95.327262 -54.323323)
			(xy 95.214801 -54.35311) (xy 95.100553 -54.375068) (xy 94.985062 -54.389091) (xy 94.868879 -54.395113)
			(xy 94.752557 -54.393105) (xy 94.636651 -54.383076) (xy 94.521714 -54.365075) (xy 94.408291 -54.339187)
			(xy 94.296926 -54.305536) (xy 94.188147 -54.264282) (xy 94.082473 -54.215621) (xy 93.980409 -54.159785)
			(xy 93.88244 -54.097042) (xy 93.789033 -54.027688) (xy 93.700633 -53.952056) (xy 93.617662 -53.870505)
			(xy 93.540515 -53.783424) (xy 93.46956 -53.691228) (xy 93.405134 -53.594356) (xy 93.347545 -53.493271)
			(xy 93.297068 -53.388453) (xy 93.253942 -53.280402) (xy 93.218373 -53.169634) (xy 93.190531 -53.056675)
			(xy 93.170549 -52.942065) (xy 93.158522 -52.82635) (xy 93.154506 -52.71008) (xy 42.502604 -52.71008)
			(xy 42.502322 -52.710305) (xy 42.406779 -52.776254) (xy 42.306914 -52.835454) (xy 42.203202 -52.887623)
			(xy 42.096139 -52.932512) (xy 41.986233 -52.969908) (xy 41.874009 -52.999633) (xy 41.760003 -53.021544)
			(xy 41.644756 -53.035537) (xy 41.528818 -53.041546) (xy 41.412742 -53.039543) (xy 41.29708 -53.029535)
			(xy 41.182385 -53.011572) (xy 41.069202 -52.985739) (xy 40.958071 -52.952159) (xy 40.849522 -52.910991)
			(xy 40.744072 -52.862433) (xy 40.642223 -52.806716) (xy 40.54446 -52.744104) (xy 40.45125 -52.674897)
			(xy 40.363037 -52.599424) (xy 40.280241 -52.518045) (xy 40.203257 -52.431148) (xy 40.132452 -52.339147)
			(xy 40.068162 -52.24248) (xy 40.010695 -52.141608) (xy 39.960324 -52.037011) (xy 39.917289 -51.929188)
			(xy 39.881795 -51.818654) (xy 39.854012 -51.705934) (xy 39.834072 -51.591566) (xy 39.82207 -51.476094)
			(xy 39.818063 -51.36007) (xy 0.509016 -51.36007) (xy 0.509016 -64.46012) (xy 86.877404 -64.46012)
			(xy 86.881424 -64.269469) (xy 86.893478 -64.079156) (xy 86.913544 -63.889521) (xy 86.941587 -63.7009)
			(xy 86.977556 -63.51363) (xy 87.021388 -63.328042) (xy 87.073005 -63.144467) (xy 87.132315 -62.963231)
			(xy 87.199213 -62.784656) (xy 87.273579 -62.609061) (xy 87.355281 -62.436756) (xy 87.444175 -62.268049)
			(xy 87.540101 -62.103239) (xy 87.64289 -61.94262) (xy 87.752359 -61.786477) (xy 87.868313 -61.635088)
			(xy 87.990547 -61.488721) (xy 88.118841 -61.347637) (xy 88.252969 -61.212088) (xy 88.392693 -61.082313)
			(xy 88.537763 -60.958543) (xy 88.687921 -60.841) (xy 88.842902 -60.729891) (xy 89.002429 -60.625414)
			(xy 89.166218 -60.527755) (xy 89.333978 -60.437088) (xy 89.505412 -60.353574) (xy 89.680214 -60.277361)
			(xy 89.858073 -60.208585) (xy 90.038674 -60.147367) (xy 90.221694 -60.093818) (xy 90.40681 -60.048032)
			(xy 90.593691 -60.01009) (xy 90.782006 -59.980061) (xy 90.971419 -59.957996) (xy 91.161593 -59.943937)
			(xy 91.352192 -59.937907) (xy 91.542875 -59.939917) (xy 91.733304 -59.949964) (xy 91.92314 -59.96803)
			(xy 92.112046 -59.994083) (xy 92.299685 -60.028076) (xy 92.485725 -60.069949) (xy 92.669834 -60.119628)
			(xy 92.851685 -60.177024) (xy 93.030955 -60.242035) (xy 93.207325 -60.314546) (xy 93.380481 -60.394427)
			(xy 93.550116 -60.481537) (xy 93.715928 -60.575721) (xy 93.877622 -60.676812) (xy 94.03491 -60.784628)
			(xy 94.187513 -60.89898) (xy 94.335161 -61.019663) (xy 94.477589 -61.146464) (xy 94.614545 -61.279155)
			(xy 94.745786 -61.417503) (xy 94.871078 -61.56126) (xy 94.990198 -61.710171) (xy 95.102934 -61.863972)
			(xy 95.209087 -62.022388) (xy 95.308467 -62.185139) (xy 95.400897 -62.351934) (xy 95.486214 -62.522478)
			(xy 95.564266 -62.696466) (xy 95.634913 -62.873591) (xy 95.698031 -63.053536) (xy 95.753507 -63.235982)
			(xy 95.801242 -63.420605) (xy 95.841152 -63.607075) (xy 95.873165 -63.795063) (xy 95.897225 -63.984233)
			(xy 95.913288 -64.174249) (xy 95.921327 -64.364773) (xy 95.92183 -64.46012) (xy 95.921327 -64.555467)
			(xy 95.913288 -64.745991) (xy 95.897225 -64.936007) (xy 95.873165 -65.125177) (xy 95.841152 -65.313165)
			(xy 95.801242 -65.499635) (xy 95.753507 -65.684258) (xy 95.698031 -65.866704) (xy 95.634913 -66.046649)
			(xy 95.564266 -66.223774) (xy 95.486214 -66.397762) (xy 95.400897 -66.568306) (xy 95.308467 -66.735101)
			(xy 95.209087 -66.897852) (xy 95.102934 -67.056268) (xy 94.990198 -67.210069) (xy 94.871078 -67.35898)
			(xy 94.745786 -67.502737) (xy 94.614545 -67.641085) (xy 94.477589 -67.773776) (xy 94.335161 -67.900577)
			(xy 94.187513 -68.02126) (xy 94.03491 -68.135612) (xy 93.877622 -68.243428) (xy 93.715928 -68.344519)
			(xy 93.550116 -68.438703) (xy 93.380481 -68.525813) (xy 93.207325 -68.605694) (xy 93.030955 -68.678205)
			(xy 92.851685 -68.743216) (xy 92.669834 -68.800612) (xy 92.485725 -68.850291) (xy 92.299685 -68.892164)
			(xy 92.112046 -68.926157) (xy 91.92314 -68.95221) (xy 91.733304 -68.970276) (xy 91.542875 -68.980323)
			(xy 91.352192 -68.982333) (xy 91.161593 -68.976303) (xy 90.971419 -68.962244) (xy 90.782006 -68.940179)
			(xy 90.593691 -68.91015) (xy 90.40681 -68.872208) (xy 90.221694 -68.826422) (xy 90.038674 -68.772873)
			(xy 89.858073 -68.711655) (xy 89.680214 -68.642879) (xy 89.505412 -68.566666) (xy 89.333978 -68.483152)
			(xy 89.166218 -68.392485) (xy 89.002429 -68.294826) (xy 88.842902 -68.190349) (xy 88.687921 -68.07924)
			(xy 88.537763 -67.961697) (xy 88.392693 -67.837927) (xy 88.252969 -67.708152) (xy 88.118841 -67.572603)
			(xy 87.990547 -67.431519) (xy 87.868313 -67.285152) (xy 87.752359 -67.133763) (xy 87.64289 -66.97762)
			(xy 87.540101 -66.817001) (xy 87.444175 -66.652191) (xy 87.355281 -66.483484) (xy 87.273579 -66.311179)
			(xy 87.199213 -66.135584) (xy 87.132315 -65.957009) (xy 87.073005 -65.775773) (xy 87.021388 -65.592198)
			(xy 86.977556 -65.40661) (xy 86.941587 -65.21934) (xy 86.913544 -65.030719) (xy 86.893478 -64.841084)
			(xy 86.881424 -64.650771) (xy 86.877404 -64.46012) (xy 0.509016 -64.46012) (xy 0.509016 -68.277994)
			(xy 1.150624 -68.277994) (xy 1.154655 -68.148428) (xy 1.166734 -68.019364) (xy 1.186813 -67.8913)
			(xy 1.214815 -67.764733) (xy 1.250632 -67.64015) (xy 1.294124 -67.518036) (xy 1.345124 -67.398862)
			(xy 1.403435 -67.283089) (xy 1.46883 -67.171165) (xy 1.541057 -67.063523) (xy 1.619837 -66.96058)
			(xy 1.704864 -66.862734) (xy 1.795809 -66.770362) (xy 1.892321 -66.683824) (xy 1.994027 -66.603453)
			(xy 2.100533 -66.529561) (xy 2.211426 -66.462433) (xy 2.326278 -66.402329) (xy 2.444645 -66.349482)
			(xy 2.566068 -66.304095) (xy 2.690078 -66.266346) (xy 2.816195 -66.236379) (xy 2.943931 -66.21431)
			(xy 3.072792 -66.200226) (xy 3.202279 -66.19418) (xy 3.331892 -66.196196) (xy 3.461128 -66.206266)
			(xy 3.589489 -66.224351) (xy 3.716477 -66.250381) (xy 3.841601 -66.284256) (xy 3.964377 -66.325844)
			(xy 4.08433 -66.374985) (xy 4.200995 -66.431488) (xy 4.313923 -66.495135) (xy 4.422675 -66.565679)
			(xy 4.526831 -66.642848) (xy 4.625988 -66.726343) (xy 4.719762 -66.815841) (xy 4.807791 -66.910996)
			(xy 4.889734 -67.011439) (xy 4.965273 -67.116782) (xy 5.034118 -67.226618) (xy 5.096001 -67.340522)
			(xy 5.150682 -67.458052) (xy 5.197952 -67.578755) (xy 5.237625 -67.702163) (xy 5.26955 -67.827799)
			(xy 5.293602 -67.955176) (xy 5.309689 -68.083802) (xy 5.317748 -68.21318) (xy 5.318252 -68.277994)
			(xy 12.580624 -68.277994) (xy 12.584655 -68.148428) (xy 12.596734 -68.019364) (xy 12.616813 -67.8913)
			(xy 12.644815 -67.764733) (xy 12.680632 -67.64015) (xy 12.724124 -67.518036) (xy 12.775124 -67.398862)
			(xy 12.833435 -67.283089) (xy 12.89883 -67.171165) (xy 12.971057 -67.063523) (xy 13.049837 -66.96058)
			(xy 13.134864 -66.862734) (xy 13.225809 -66.770362) (xy 13.322321 -66.683824) (xy 13.424027 -66.603453)
			(xy 13.530533 -66.529561) (xy 13.641426 -66.462433) (xy 13.756278 -66.402329) (xy 13.874645 -66.349482)
			(xy 13.996068 -66.304095) (xy 14.120078 -66.266346) (xy 14.246195 -66.236379) (xy 14.373931 -66.21431)
			(xy 14.502792 -66.200226) (xy 14.632279 -66.19418) (xy 14.761892 -66.196196) (xy 14.891128 -66.206266)
			(xy 15.019489 -66.224351) (xy 15.146477 -66.250381) (xy 15.271601 -66.284256) (xy 15.394377 -66.325844)
			(xy 15.51433 -66.374985) (xy 15.630995 -66.431488) (xy 15.743923 -66.495135) (xy 15.852675 -66.565679)
			(xy 15.956831 -66.642848) (xy 16.055988 -66.726343) (xy 16.149762 -66.815841) (xy 16.237791 -66.910996)
			(xy 16.319734 -67.011439) (xy 16.395273 -67.116782) (xy 16.464118 -67.226618) (xy 16.526001 -67.340522)
			(xy 16.580682 -67.458052) (xy 16.627952 -67.578755) (xy 16.667625 -67.702163) (xy 16.69955 -67.827799)
			(xy 16.723602 -67.955176) (xy 16.739689 -68.083802) (xy 16.747748 -68.21318) (xy 16.748252 -68.277994)
			(xy 16.747748 -68.342808) (xy 16.739689 -68.472186) (xy 16.723602 -68.600812) (xy 16.69955 -68.728189)
			(xy 16.667625 -68.853825) (xy 16.627952 -68.977233) (xy 16.580682 -69.097936) (xy 16.526001 -69.215466)
			(xy 16.464118 -69.32937) (xy 16.395273 -69.439206) (xy 16.319734 -69.544549) (xy 16.237791 -69.644992)
			(xy 16.149762 -69.740147) (xy 16.055988 -69.829645) (xy 15.956831 -69.91314) (xy 15.852675 -69.990309)
			(xy 15.743923 -70.060853) (xy 15.630995 -70.1245) (xy 15.51433 -70.181003) (xy 15.394377 -70.230144)
			(xy 15.271601 -70.271732) (xy 15.146477 -70.305607) (xy 15.019489 -70.331637) (xy 14.891128 -70.349722)
			(xy 14.761892 -70.359792) (xy 14.632279 -70.361808) (xy 14.502792 -70.355762) (xy 14.373931 -70.341678)
			(xy 14.246195 -70.319609) (xy 14.120078 -70.289642) (xy 13.996068 -70.251893) (xy 13.874645 -70.206506)
			(xy 13.756278 -70.153659) (xy 13.641426 -70.093555) (xy 13.530533 -70.026427) (xy 13.424027 -69.952535)
			(xy 13.322321 -69.872164) (xy 13.225809 -69.785626) (xy 13.134864 -69.693254) (xy 13.049837 -69.595408)
			(xy 12.971057 -69.492465) (xy 12.89883 -69.384823) (xy 12.833435 -69.272899) (xy 12.775124 -69.157126)
			(xy 12.724124 -69.037952) (xy 12.680632 -68.915838) (xy 12.644815 -68.791255) (xy 12.616813 -68.664688)
			(xy 12.596734 -68.536624) (xy 12.584655 -68.40756) (xy 12.580624 -68.277994) (xy 5.318252 -68.277994)
			(xy 5.317748 -68.342808) (xy 5.309689 -68.472186) (xy 5.293602 -68.600812) (xy 5.26955 -68.728189)
			(xy 5.237625 -68.853825) (xy 5.197952 -68.977233) (xy 5.150682 -69.097936) (xy 5.096001 -69.215466)
			(xy 5.034118 -69.32937) (xy 4.965273 -69.439206) (xy 4.889734 -69.544549) (xy 4.807791 -69.644992)
			(xy 4.719762 -69.740147) (xy 4.625988 -69.829645) (xy 4.526831 -69.91314) (xy 4.422675 -69.990309)
			(xy 4.313923 -70.060853) (xy 4.200995 -70.1245) (xy 4.08433 -70.181003) (xy 3.964377 -70.230144)
			(xy 3.841601 -70.271732) (xy 3.716477 -70.305607) (xy 3.589489 -70.331637) (xy 3.461128 -70.349722)
			(xy 3.331892 -70.359792) (xy 3.202279 -70.361808) (xy 3.072792 -70.355762) (xy 2.943931 -70.341678)
			(xy 2.816195 -70.319609) (xy 2.690078 -70.289642) (xy 2.566068 -70.251893) (xy 2.444645 -70.206506)
			(xy 2.326278 -70.153659) (xy 2.211426 -70.093555) (xy 2.100533 -70.026427) (xy 1.994027 -69.952535)
			(xy 1.892321 -69.872164) (xy 1.795809 -69.785626) (xy 1.704864 -69.693254) (xy 1.619837 -69.595408)
			(xy 1.541057 -69.492465) (xy 1.46883 -69.384823) (xy 1.403435 -69.272899) (xy 1.345124 -69.157126)
			(xy 1.294124 -69.037952) (xy 1.250632 -68.915838) (xy 1.214815 -68.791255) (xy 1.186813 -68.664688)
			(xy 1.166734 -68.536624) (xy 1.154655 -68.40756) (xy 1.150624 -68.277994) (xy 0.509016 -68.277994)
			(xy 0.509016 -78.378673) (xy 74.888081 -78.378673) (xy 74.888081 -78.220963) (xy 74.896069 -78.063456)
			(xy 74.912025 -77.906556) (xy 74.935906 -77.750665) (xy 74.967653 -77.596184) (xy 75.007183 -77.443509)
			(xy 75.054395 -77.293033) (xy 75.109169 -77.14514) (xy 75.171362 -77.000212) (xy 75.240817 -76.85862)
			(xy 75.317353 -76.720727) (xy 75.400776 -76.586888) (xy 75.49087 -76.457446) (xy 75.587405 -76.332733)
			(xy 75.690133 -76.21307) (xy 75.798789 -76.098763) (xy 75.913096 -75.990107) (xy 76.032759 -75.887379)
			(xy 76.157472 -75.790844) (xy 76.286914 -75.70075) (xy 76.420753 -75.617327) (xy 76.558646 -75.540791)
			(xy 76.700238 -75.471336) (xy 76.845166 -75.409143) (xy 76.993059 -75.354369) (xy 77.143535 -75.307157)
			(xy 77.29621 -75.267627) (xy 77.450691 -75.23588) (xy 77.606582 -75.211999) (xy 77.763482 -75.196043)
			(xy 77.920989 -75.188055) (xy 78.078699 -75.188055) (xy 78.236206 -75.196043) (xy 78.393106 -75.211999)
			(xy 78.548997 -75.23588) (xy 78.703478 -75.267627) (xy 78.856153 -75.307157) (xy 79.006629 -75.354369)
			(xy 79.154522 -75.409143) (xy 79.29945 -75.471336) (xy 79.441042 -75.540791) (xy 79.578935 -75.617327)
			(xy 79.712774 -75.70075) (xy 79.842216 -75.790844) (xy 79.966929 -75.887379) (xy 80.086592 -75.990107)
			(xy 80.200899 -76.098763) (xy 80.309555 -76.21307) (xy 80.412283 -76.332733) (xy 80.508818 -76.457446)
			(xy 80.598912 -76.586888) (xy 80.682335 -76.720727) (xy 80.758871 -76.85862) (xy 80.828326 -77.000212)
			(xy 80.890519 -77.14514) (xy 80.945293 -77.293033) (xy 80.992505 -77.443509) (xy 81.032035 -77.596184)
			(xy 81.063782 -77.750665) (xy 81.087663 -77.906556) (xy 81.103619 -78.063456) (xy 81.111607 -78.220963)
			(xy 81.112106 -78.299818) (xy 81.111607 -78.378673) (xy 81.111599 -78.37883) (xy 90.891859 -78.37883)
			(xy 90.891859 -78.221314) (xy 90.899837 -78.064) (xy 90.915772 -77.907291) (xy 90.939625 -77.751592)
			(xy 90.971333 -77.5973) (xy 91.010814 -77.444812) (xy 91.057969 -77.294519) (xy 91.112675 -77.146808)
			(xy 91.174793 -77.002057) (xy 91.244162 -76.860638) (xy 91.320605 -76.722914) (xy 91.403926 -76.589239)
			(xy 91.49391 -76.459955) (xy 91.590326 -76.335395) (xy 91.692928 -76.215878) (xy 91.801452 -76.101712)
			(xy 91.915618 -75.993188) (xy 92.035135 -75.890586) (xy 92.159695 -75.79417) (xy 92.288979 -75.704186)
			(xy 92.422654 -75.620865) (xy 92.560378 -75.544422) (xy 92.701797 -75.475053) (xy 92.846548 -75.412935)
			(xy 92.994259 -75.358229) (xy 93.144552 -75.311074) (xy 93.29704 -75.271593) (xy 93.451332 -75.239885)
			(xy 93.607031 -75.216032) (xy 93.76374 -75.200097) (xy 93.921054 -75.192119) (xy 94.07857 -75.192119)
			(xy 94.235884 -75.200097) (xy 94.392593 -75.216032) (xy 94.548292 -75.239885) (xy 94.702584 -75.271593)
			(xy 94.855072 -75.311074) (xy 95.005365 -75.358229) (xy 95.153076 -75.412935) (xy 95.297827 -75.475053)
			(xy 95.439246 -75.544422) (xy 95.57697 -75.620865) (xy 95.710645 -75.704186) (xy 95.839929 -75.79417)
			(xy 95.964489 -75.890586) (xy 96.084006 -75.993188) (xy 96.198172 -76.101712) (xy 96.306696 -76.215878)
			(xy 96.409298 -76.335395) (xy 96.505714 -76.459955) (xy 96.595698 -76.589239) (xy 96.679019 -76.722914)
			(xy 96.755462 -76.860638) (xy 96.824831 -77.002057) (xy 96.886949 -77.146808) (xy 96.941655 -77.294519)
			(xy 96.98881 -77.444812) (xy 97.028291 -77.5973) (xy 97.059999 -77.751592) (xy 97.083852 -77.907291)
			(xy 97.099787 -78.064) (xy 97.107765 -78.221314) (xy 97.108264 -78.300072) (xy 97.107765 -78.37883)
			(xy 97.099787 -78.536144) (xy 97.083852 -78.692853) (xy 97.059999 -78.848552) (xy 97.028291 -79.002844)
			(xy 96.98881 -79.155332) (xy 96.941655 -79.305625) (xy 96.886949 -79.453336) (xy 96.824831 -79.598087)
			(xy 96.755462 -79.739506) (xy 96.679019 -79.87723) (xy 96.595698 -80.010905) (xy 96.505714 -80.140189)
			(xy 96.409298 -80.264749) (xy 96.306696 -80.384266) (xy 96.198172 -80.498432) (xy 96.084006 -80.606956)
			(xy 95.964489 -80.709558) (xy 95.839929 -80.805974) (xy 95.710645 -80.895958) (xy 95.57697 -80.979279)
			(xy 95.439246 -81.055722) (xy 95.297827 -81.125091) (xy 95.153076 -81.187209) (xy 95.005365 -81.241915)
			(xy 94.855072 -81.28907) (xy 94.702584 -81.328551) (xy 94.548292 -81.360259) (xy 94.392593 -81.384112)
			(xy 94.235884 -81.400047) (xy 94.07857 -81.408025) (xy 93.921054 -81.408025) (xy 93.76374 -81.400047)
			(xy 93.607031 -81.384112) (xy 93.451332 -81.360259) (xy 93.29704 -81.328551) (xy 93.144552 -81.28907)
			(xy 92.994259 -81.241915) (xy 92.846548 -81.187209) (xy 92.701797 -81.125091) (xy 92.560378 -81.055722)
			(xy 92.422654 -80.979279) (xy 92.288979 -80.895958) (xy 92.159695 -80.805974) (xy 92.035135 -80.709558)
			(xy 91.915618 -80.606956) (xy 91.801452 -80.498432) (xy 91.692928 -80.384266) (xy 91.590326 -80.264749)
			(xy 91.49391 -80.140189) (xy 91.403926 -80.010905) (xy 91.320605 -79.87723) (xy 91.244162 -79.739506)
			(xy 91.174793 -79.598087) (xy 91.112675 -79.453336) (xy 91.057969 -79.305625) (xy 91.010814 -79.155332)
			(xy 90.971333 -79.002844) (xy 90.939625 -78.848552) (xy 90.915772 -78.692853) (xy 90.899837 -78.536144)
			(xy 90.891859 -78.37883) (xy 81.111599 -78.37883) (xy 81.103619 -78.53618) (xy 81.087663 -78.69308)
			(xy 81.063782 -78.848971) (xy 81.032035 -79.003452) (xy 80.992505 -79.156127) (xy 80.945293 -79.306603)
			(xy 80.890519 -79.454496) (xy 80.828326 -79.599424) (xy 80.758871 -79.741016) (xy 80.682335 -79.878909)
			(xy 80.598912 -80.012748) (xy 80.508818 -80.14219) (xy 80.412283 -80.266903) (xy 80.309555 -80.386566)
			(xy 80.200899 -80.500873) (xy 80.086592 -80.609529) (xy 79.966929 -80.712257) (xy 79.842216 -80.808792)
			(xy 79.712774 -80.898886) (xy 79.578935 -80.982309) (xy 79.441042 -81.058845) (xy 79.29945 -81.1283)
			(xy 79.154522 -81.190493) (xy 79.006629 -81.245267) (xy 78.856153 -81.292479) (xy 78.703478 -81.332009)
			(xy 78.548997 -81.363756) (xy 78.393106 -81.387637) (xy 78.236206 -81.403593) (xy 78.078699 -81.411581)
			(xy 77.920989 -81.411581) (xy 77.763482 -81.403593) (xy 77.606582 -81.387637) (xy 77.450691 -81.363756)
			(xy 77.29621 -81.332009) (xy 77.143535 -81.292479) (xy 76.993059 -81.245267) (xy 76.845166 -81.190493)
			(xy 76.700238 -81.1283) (xy 76.558646 -81.058845) (xy 76.420753 -80.982309) (xy 76.286914 -80.898886)
			(xy 76.157472 -80.808792) (xy 76.032759 -80.712257) (xy 75.913096 -80.609529) (xy 75.798789 -80.500873)
			(xy 75.690133 -80.386566) (xy 75.587405 -80.266903) (xy 75.49087 -80.14219) (xy 75.400776 -80.012748)
			(xy 75.317353 -79.878909) (xy 75.240817 -79.741016) (xy 75.171362 -79.599424) (xy 75.109169 -79.454496)
			(xy 75.054395 -79.306603) (xy 75.007183 -79.156127) (xy 74.967653 -79.003452) (xy 74.935906 -78.848971)
			(xy 74.912025 -78.69308) (xy 74.896069 -78.53618) (xy 74.888081 -78.378673) (xy 0.509016 -78.378673)
			(xy 0.509016 -95.81007) (xy 39.818063 -95.81007) (xy 39.82207 -95.694046) (xy 39.834072 -95.578574)
			(xy 39.854012 -95.464206) (xy 39.881795 -95.351486) (xy 39.917289 -95.240952) (xy 39.960324 -95.133129)
			(xy 40.010695 -95.028532) (xy 40.068162 -94.92766) (xy 40.132452 -94.830993) (xy 40.203257 -94.738992)
			(xy 40.280241 -94.652095) (xy 40.363037 -94.570716) (xy 40.45125 -94.495243) (xy 40.54446 -94.426036)
			(xy 40.642223 -94.363424) (xy 40.744072 -94.307707) (xy 40.849522 -94.259149) (xy 40.958071 -94.217981)
			(xy 41.069202 -94.184401) (xy 41.182385 -94.158568) (xy 41.29708 -94.140605) (xy 41.412742 -94.130597)
			(xy 41.528818 -94.128594) (xy 41.644756 -94.134603) (xy 41.760003 -94.148596) (xy 41.874009 -94.170507)
			(xy 41.986233 -94.200232) (xy 42.096139 -94.237628) (xy 42.203202 -94.282517) (xy 42.306914 -94.334686)
			(xy 42.406779 -94.393886) (xy 42.502322 -94.459835) (xy 42.593088 -94.532218) (xy 42.678643 -94.610691)
			(xy 42.758581 -94.694879) (xy 42.83252 -94.784381) (xy 42.900108 -94.878772) (xy 42.961022 -94.9776)
			(xy 43.014974 -95.080396) (xy 43.061704 -95.186669) (xy 43.100992 -95.295913) (xy 43.132649 -95.407606)
			(xy 43.156525 -95.521218) (xy 43.172506 -95.636206) (xy 43.180515 -95.752023) (xy 43.181016 -95.81007)
			(xy 43.180515 -95.868117) (xy 43.172506 -95.983934) (xy 43.156525 -96.098922) (xy 43.132649 -96.212534)
			(xy 43.100992 -96.324227) (xy 43.061704 -96.433471) (xy 43.014974 -96.539744) (xy 42.961022 -96.64254)
			(xy 42.900108 -96.741368) (xy 42.83252 -96.835759) (xy 42.758581 -96.925261) (xy 42.678643 -97.009449)
			(xy 42.593088 -97.087922) (xy 42.502604 -97.16008) (xy 93.154506 -97.16008) (xy 93.158522 -97.04381)
			(xy 93.170549 -96.928095) (xy 93.190531 -96.813485) (xy 93.218373 -96.700526) (xy 93.253942 -96.589758)
			(xy 93.297068 -96.481707) (xy 93.347545 -96.376889) (xy 93.405134 -96.275804) (xy 93.46956 -96.178932)
			(xy 93.540515 -96.086736) (xy 93.617662 -95.999655) (xy 93.700633 -95.918104) (xy 93.789033 -95.842472)
			(xy 93.88244 -95.773118) (xy 93.980409 -95.710375) (xy 94.082473 -95.654539) (xy 94.188147 -95.605878)
			(xy 94.296926 -95.564624) (xy 94.408291 -95.530973) (xy 94.521714 -95.505085) (xy 94.636651 -95.487084)
			(xy 94.752557 -95.477055) (xy 94.868879 -95.475047) (xy 94.985062 -95.481069) (xy 95.100553 -95.495092)
			(xy 95.214801 -95.51705) (xy 95.327262 -95.546837) (xy 95.4374 -95.584312) (xy 95.54469 -95.629297)
			(xy 95.648621 -95.681576) (xy 95.748697 -95.740901) (xy 95.844443 -95.806989) (xy 95.9354 -95.879525)
			(xy 96.021136 -95.958164) (xy 96.101243 -96.04253) (xy 96.175339 -96.132222) (xy 96.243069 -96.226812)
			(xy 96.304113 -96.32585) (xy 96.358178 -96.428863) (xy 96.405008 -96.53536) (xy 96.444379 -96.644835)
			(xy 96.476103 -96.756765) (xy 96.500029 -96.870617) (xy 96.516043 -96.985849) (xy 96.52407 -97.101911)
			(xy 96.524572 -97.16008) (xy 96.52407 -97.218249) (xy 96.516043 -97.334311) (xy 96.500029 -97.449543)
			(xy 96.476103 -97.563395) (xy 96.444379 -97.675325) (xy 96.405008 -97.7848) (xy 96.358178 -97.891297)
			(xy 96.304113 -97.99431) (xy 96.243069 -98.093348) (xy 96.175339 -98.187938) (xy 96.101243 -98.27763)
			(xy 96.021136 -98.361996) (xy 95.9354 -98.440635) (xy 95.844443 -98.513171) (xy 95.748697 -98.579259)
			(xy 95.648621 -98.638584) (xy 95.54469 -98.690863) (xy 95.4374 -98.735848) (xy 95.327262 -98.773323)
			(xy 95.214801 -98.80311) (xy 95.100553 -98.825068) (xy 94.985062 -98.839091) (xy 94.868879 -98.845113)
			(xy 94.752557 -98.843105) (xy 94.636651 -98.833076) (xy 94.521714 -98.815075) (xy 94.408291 -98.789187)
			(xy 94.296926 -98.755536) (xy 94.188147 -98.714282) (xy 94.082473 -98.665621) (xy 93.980409 -98.609785)
			(xy 93.88244 -98.547042) (xy 93.789033 -98.477688) (xy 93.700633 -98.402056) (xy 93.617662 -98.320505)
			(xy 93.540515 -98.233424) (xy 93.46956 -98.141228) (xy 93.405134 -98.044356) (xy 93.347545 -97.943271)
			(xy 93.297068 -97.838453) (xy 93.253942 -97.730402) (xy 93.218373 -97.619634) (xy 93.190531 -97.506675)
			(xy 93.170549 -97.392065) (xy 93.158522 -97.27635) (xy 93.154506 -97.16008) (xy 42.502604 -97.16008)
			(xy 42.502322 -97.160305) (xy 42.406779 -97.226254) (xy 42.306914 -97.285454) (xy 42.203202 -97.337623)
			(xy 42.096139 -97.382512) (xy 41.986233 -97.419908) (xy 41.874009 -97.449633) (xy 41.760003 -97.471544)
			(xy 41.644756 -97.485537) (xy 41.528818 -97.491546) (xy 41.412742 -97.489543) (xy 41.29708 -97.479535)
			(xy 41.182385 -97.461572) (xy 41.069202 -97.435739) (xy 40.958071 -97.402159) (xy 40.849522 -97.360991)
			(xy 40.744072 -97.312433) (xy 40.642223 -97.256716) (xy 40.54446 -97.194104) (xy 40.45125 -97.124897)
			(xy 40.363037 -97.049424) (xy 40.280241 -96.968045) (xy 40.203257 -96.881148) (xy 40.132452 -96.789147)
			(xy 40.068162 -96.69248) (xy 40.010695 -96.591608) (xy 39.960324 -96.487011) (xy 39.917289 -96.379188)
			(xy 39.881795 -96.268654) (xy 39.854012 -96.155934) (xy 39.834072 -96.041566) (xy 39.82207 -95.926094)
			(xy 39.818063 -95.81007) (xy 0.509016 -95.81007) (xy 0.509016 -99.271836) (xy 1.150624 -99.271836)
			(xy 1.154655 -99.14227) (xy 1.166734 -99.013206) (xy 1.186813 -98.885142) (xy 1.214815 -98.758575)
			(xy 1.250632 -98.633992) (xy 1.294124 -98.511878) (xy 1.345124 -98.392704) (xy 1.403435 -98.276931)
			(xy 1.46883 -98.165007) (xy 1.541057 -98.057365) (xy 1.619837 -97.954422) (xy 1.704864 -97.856576)
			(xy 1.795809 -97.764204) (xy 1.892321 -97.677666) (xy 1.994027 -97.597295) (xy 2.100533 -97.523403)
			(xy 2.211426 -97.456275) (xy 2.326278 -97.396171) (xy 2.444645 -97.343324) (xy 2.566068 -97.297937)
			(xy 2.690078 -97.260188) (xy 2.816195 -97.230221) (xy 2.943931 -97.208152) (xy 3.072792 -97.194068)
			(xy 3.202279 -97.188022) (xy 3.331892 -97.190038) (xy 3.461128 -97.200108) (xy 3.589489 -97.218193)
			(xy 3.716477 -97.244223) (xy 3.841601 -97.278098) (xy 3.964377 -97.319686) (xy 4.08433 -97.368827)
			(xy 4.200995 -97.42533) (xy 4.313923 -97.488977) (xy 4.422675 -97.559521) (xy 4.526831 -97.63669)
			(xy 4.625988 -97.720185) (xy 4.719762 -97.809683) (xy 4.807791 -97.904838) (xy 4.889734 -98.005281)
			(xy 4.965273 -98.110624) (xy 5.034118 -98.22046) (xy 5.096001 -98.334364) (xy 5.150682 -98.451894)
			(xy 5.197952 -98.572597) (xy 5.237625 -98.696005) (xy 5.26955 -98.821641) (xy 5.293602 -98.949018)
			(xy 5.309689 -99.077644) (xy 5.317748 -99.207022) (xy 5.318252 -99.271836) (xy 12.580624 -99.271836)
			(xy 12.584655 -99.14227) (xy 12.596734 -99.013206) (xy 12.616813 -98.885142) (xy 12.644815 -98.758575)
			(xy 12.680632 -98.633992) (xy 12.724124 -98.511878) (xy 12.775124 -98.392704) (xy 12.833435 -98.276931)
			(xy 12.89883 -98.165007) (xy 12.971057 -98.057365) (xy 13.049837 -97.954422) (xy 13.134864 -97.856576)
			(xy 13.225809 -97.764204) (xy 13.322321 -97.677666) (xy 13.424027 -97.597295) (xy 13.530533 -97.523403)
			(xy 13.641426 -97.456275) (xy 13.756278 -97.396171) (xy 13.874645 -97.343324) (xy 13.996068 -97.297937)
			(xy 14.120078 -97.260188) (xy 14.246195 -97.230221) (xy 14.373931 -97.208152) (xy 14.502792 -97.194068)
			(xy 14.632279 -97.188022) (xy 14.761892 -97.190038) (xy 14.891128 -97.200108) (xy 15.019489 -97.218193)
			(xy 15.146477 -97.244223) (xy 15.271601 -97.278098) (xy 15.394377 -97.319686) (xy 15.51433 -97.368827)
			(xy 15.630995 -97.42533) (xy 15.743923 -97.488977) (xy 15.852675 -97.559521) (xy 15.956831 -97.63669)
			(xy 16.055988 -97.720185) (xy 16.149762 -97.809683) (xy 16.237791 -97.904838) (xy 16.319734 -98.005281)
			(xy 16.395273 -98.110624) (xy 16.464118 -98.22046) (xy 16.526001 -98.334364) (xy 16.580682 -98.451894)
			(xy 16.627952 -98.572597) (xy 16.667625 -98.696005) (xy 16.69955 -98.821641) (xy 16.723602 -98.949018)
			(xy 16.739689 -99.077644) (xy 16.747748 -99.207022) (xy 16.748252 -99.271836) (xy 16.747748 -99.33665)
			(xy 16.739689 -99.466028) (xy 16.723602 -99.594654) (xy 16.69955 -99.722031) (xy 16.667625 -99.847667)
			(xy 16.627952 -99.971075) (xy 16.580682 -100.091778) (xy 16.526001 -100.209308) (xy 16.464118 -100.323212)
			(xy 16.395273 -100.433048) (xy 16.319734 -100.538391) (xy 16.237791 -100.638834) (xy 16.149762 -100.733989)
			(xy 16.055988 -100.823487) (xy 15.956831 -100.906982) (xy 15.852675 -100.984151) (xy 15.743923 -101.054695)
			(xy 15.630995 -101.118342) (xy 15.51433 -101.174845) (xy 15.394377 -101.223986) (xy 15.271601 -101.265574)
			(xy 15.146477 -101.299449) (xy 15.019489 -101.325479) (xy 14.891128 -101.343564) (xy 14.761892 -101.353634)
			(xy 14.632279 -101.35565) (xy 14.502792 -101.349604) (xy 14.373931 -101.33552) (xy 14.246195 -101.313451)
			(xy 14.120078 -101.283484) (xy 13.996068 -101.245735) (xy 13.874645 -101.200348) (xy 13.756278 -101.147501)
			(xy 13.641426 -101.087397) (xy 13.530533 -101.020269) (xy 13.424027 -100.946377) (xy 13.322321 -100.866006)
			(xy 13.225809 -100.779468) (xy 13.134864 -100.687096) (xy 13.049837 -100.58925) (xy 12.971057 -100.486307)
			(xy 12.89883 -100.378665) (xy 12.833435 -100.266741) (xy 12.775124 -100.150968) (xy 12.724124 -100.031794)
			(xy 12.680632 -99.90968) (xy 12.644815 -99.785097) (xy 12.616813 -99.65853) (xy 12.596734 -99.530466)
			(xy 12.584655 -99.401402) (xy 12.580624 -99.271836) (xy 5.318252 -99.271836) (xy 5.317748 -99.33665)
			(xy 5.309689 -99.466028) (xy 5.293602 -99.594654) (xy 5.26955 -99.722031) (xy 5.237625 -99.847667)
			(xy 5.197952 -99.971075) (xy 5.150682 -100.091778) (xy 5.096001 -100.209308) (xy 5.034118 -100.323212)
			(xy 4.965273 -100.433048) (xy 4.889734 -100.538391) (xy 4.807791 -100.638834) (xy 4.719762 -100.733989)
			(xy 4.625988 -100.823487) (xy 4.526831 -100.906982) (xy 4.422675 -100.984151) (xy 4.313923 -101.054695)
			(xy 4.200995 -101.118342) (xy 4.08433 -101.174845) (xy 3.964377 -101.223986) (xy 3.841601 -101.265574)
			(xy 3.716477 -101.299449) (xy 3.589489 -101.325479) (xy 3.461128 -101.343564) (xy 3.331892 -101.353634)
			(xy 3.202279 -101.35565) (xy 3.072792 -101.349604) (xy 2.943931 -101.33552) (xy 2.816195 -101.313451)
			(xy 2.690078 -101.283484) (xy 2.566068 -101.245735) (xy 2.444645 -101.200348) (xy 2.326278 -101.147501)
			(xy 2.211426 -101.087397) (xy 2.100533 -101.020269) (xy 1.994027 -100.946377) (xy 1.892321 -100.866006)
			(xy 1.795809 -100.779468) (xy 1.704864 -100.687096) (xy 1.619837 -100.58925) (xy 1.541057 -100.486307)
			(xy 1.46883 -100.378665) (xy 1.403435 -100.266741) (xy 1.345124 -100.150968) (xy 1.294124 -100.031794)
			(xy 1.250632 -99.90968) (xy 1.214815 -99.785097) (xy 1.186813 -99.65853) (xy 1.166734 -99.530466)
			(xy 1.154655 -99.401402) (xy 1.150624 -99.271836) (xy 0.509016 -99.271836) (xy 0.509016 -108.909866)
			(xy 86.877404 -108.909866) (xy 86.881424 -108.719215) (xy 86.893478 -108.528902) (xy 86.913544 -108.339267)
			(xy 86.941587 -108.150646) (xy 86.977556 -107.963376) (xy 87.021388 -107.777788) (xy 87.073005 -107.594213)
			(xy 87.132315 -107.412977) (xy 87.199213 -107.234402) (xy 87.273579 -107.058807) (xy 87.355281 -106.886502)
			(xy 87.444175 -106.717795) (xy 87.540101 -106.552985) (xy 87.64289 -106.392366) (xy 87.752359 -106.236223)
			(xy 87.868313 -106.084834) (xy 87.990547 -105.938467) (xy 88.118841 -105.797383) (xy 88.252969 -105.661834)
			(xy 88.392693 -105.532059) (xy 88.537763 -105.408289) (xy 88.687921 -105.290746) (xy 88.842902 -105.179637)
			(xy 89.002429 -105.07516) (xy 89.166218 -104.977501) (xy 89.333978 -104.886834) (xy 89.505412 -104.80332)
			(xy 89.680214 -104.727107) (xy 89.858073 -104.658331) (xy 90.038674 -104.597113) (xy 90.221694 -104.543564)
			(xy 90.40681 -104.497778) (xy 90.593691 -104.459836) (xy 90.782006 -104.429807) (xy 90.971419 -104.407742)
			(xy 91.161593 -104.393683) (xy 91.352192 -104.387653) (xy 91.542875 -104.389663) (xy 91.733304 -104.39971)
			(xy 91.92314 -104.417776) (xy 92.112046 -104.443829) (xy 92.299685 -104.477822) (xy 92.485725 -104.519695)
			(xy 92.669834 -104.569374) (xy 92.851685 -104.62677) (xy 93.030955 -104.691781) (xy 93.207325 -104.764292)
			(xy 93.380481 -104.844173) (xy 93.550116 -104.931283) (xy 93.715928 -105.025467) (xy 93.877622 -105.126558)
			(xy 94.03491 -105.234374) (xy 94.187513 -105.348726) (xy 94.335161 -105.469409) (xy 94.477589 -105.59621)
			(xy 94.614545 -105.728901) (xy 94.745786 -105.867249) (xy 94.871078 -106.011006) (xy 94.990198 -106.159917)
			(xy 95.102934 -106.313718) (xy 95.209087 -106.472134) (xy 95.308467 -106.634885) (xy 95.400897 -106.80168)
			(xy 95.486214 -106.972224) (xy 95.564266 -107.146212) (xy 95.634913 -107.323337) (xy 95.698031 -107.503282)
			(xy 95.753507 -107.685728) (xy 95.801242 -107.870351) (xy 95.841152 -108.056821) (xy 95.873165 -108.244809)
			(xy 95.897225 -108.433979) (xy 95.913288 -108.623995) (xy 95.921327 -108.814519) (xy 95.92183 -108.909866)
			(xy 95.921327 -109.005213) (xy 95.913288 -109.195737) (xy 95.897225 -109.385753) (xy 95.873165 -109.574923)
			(xy 95.841152 -109.762911) (xy 95.801242 -109.949381) (xy 95.753507 -110.134004) (xy 95.698031 -110.31645)
			(xy 95.634913 -110.496395) (xy 95.564266 -110.67352) (xy 95.486214 -110.847508) (xy 95.400897 -111.018052)
			(xy 95.308467 -111.184847) (xy 95.209087 -111.347598) (xy 95.102934 -111.506014) (xy 94.990198 -111.659815)
			(xy 94.871078 -111.808726) (xy 94.745786 -111.952483) (xy 94.614545 -112.090831) (xy 94.477589 -112.223522)
			(xy 94.335161 -112.350323) (xy 94.187513 -112.471006) (xy 94.03491 -112.585358) (xy 93.877622 -112.693174)
			(xy 93.715928 -112.794265) (xy 93.550116 -112.888449) (xy 93.380481 -112.975559) (xy 93.207325 -113.05544)
			(xy 93.030955 -113.127951) (xy 92.851685 -113.192962) (xy 92.669834 -113.250358) (xy 92.485725 -113.300037)
			(xy 92.299685 -113.34191) (xy 92.112046 -113.375903) (xy 91.92314 -113.401956) (xy 91.733304 -113.420022)
			(xy 91.542875 -113.430069) (xy 91.352192 -113.432079) (xy 91.161593 -113.426049) (xy 90.971419 -113.41199)
			(xy 90.782006 -113.389925) (xy 90.593691 -113.359896) (xy 90.40681 -113.321954) (xy 90.221694 -113.276168)
			(xy 90.038674 -113.222619) (xy 89.858073 -113.161401) (xy 89.680214 -113.092625) (xy 89.505412 -113.016412)
			(xy 89.333978 -112.932898) (xy 89.166218 -112.842231) (xy 89.002429 -112.744572) (xy 88.842902 -112.640095)
			(xy 88.687921 -112.528986) (xy 88.537763 -112.411443) (xy 88.392693 -112.287673) (xy 88.252969 -112.157898)
			(xy 88.118841 -112.022349) (xy 87.990547 -111.881265) (xy 87.868313 -111.734898) (xy 87.752359 -111.583509)
			(xy 87.64289 -111.427366) (xy 87.540101 -111.266747) (xy 87.444175 -111.101937) (xy 87.355281 -110.93323)
			(xy 87.273579 -110.760925) (xy 87.199213 -110.58533) (xy 87.132315 -110.406755) (xy 87.073005 -110.225519)
			(xy 87.021388 -110.041944) (xy 86.977556 -109.856356) (xy 86.941587 -109.669086) (xy 86.913544 -109.480465)
			(xy 86.893478 -109.29083) (xy 86.881424 -109.100517) (xy 86.877404 -108.909866) (xy 0.509016 -108.909866)
			(xy 0.509016 -118.09984) (xy 14.086591 -118.09984) (xy 14.090616 -117.957648) (xy 14.102679 -117.815912)
			(xy 14.122742 -117.675086) (xy 14.15074 -117.53562) (xy 14.186584 -117.397961) (xy 14.230158 -117.262551)
			(xy 14.281323 -117.129823) (xy 14.339916 -117.000202) (xy 14.405747 -116.874104) (xy 14.478608 -116.751932)
			(xy 14.558263 -116.634078) (xy 14.644459 -116.520919) (xy 14.736918 -116.412817) (xy 14.835346 -116.31012)
			(xy 14.939425 -116.213156) (xy 15.048824 -116.122236) (xy 15.163192 -116.03765) (xy 15.282161 -115.95967)
			(xy 15.405352 -115.888546) (xy 15.532369 -115.824505) (xy 15.662806 -115.767753) (xy 15.796245 -115.718471)
			(xy 15.932258 -115.676817) (xy 16.07041 -115.642925) (xy 16.210259 -115.616904) (xy 16.351355 -115.598836)
			(xy 16.493247 -115.588779) (xy 16.635482 -115.586766) (xy 16.777602 -115.592803) (xy 16.919153 -115.606871)
			(xy 17.059682 -115.628925) (xy 17.198737 -115.658894) (xy 17.335875 -115.696682) (xy 17.470655 -115.742168)
			(xy 17.602646 -115.795206) (xy 17.731425 -115.855627) (xy 17.856579 -115.923236) (xy 17.977707 -115.997818)
			(xy 18.094423 -116.079134) (xy 18.206351 -116.166922) (xy 18.313133 -116.260902) (xy 18.414427 -116.360772)
			(xy 18.509908 -116.466214) (xy 18.599272 -116.576888) (xy 18.68223 -116.692441) (xy 18.758519 -116.812502)
			(xy 18.827893 -116.936687) (xy 18.89013 -117.064598) (xy 18.945031 -117.195825) (xy 18.992419 -117.329948)
			(xy 19.032144 -117.466537) (xy 19.064077 -117.605155) (xy 19.088118 -117.745357) (xy 19.104187 -117.886695)
			(xy 19.112235 -118.028716) (xy 19.112738 -118.09984) (xy 19.112235 -118.170964) (xy 19.104187 -118.312985)
			(xy 19.088118 -118.454323) (xy 19.064077 -118.594525) (xy 19.032144 -118.733143) (xy 18.992419 -118.869732)
			(xy 18.945031 -119.003855) (xy 18.89013 -119.135082) (xy 18.827893 -119.262993) (xy 18.758519 -119.387178)
			(xy 18.68223 -119.507239) (xy 18.599272 -119.622792) (xy 18.509908 -119.733466) (xy 18.414427 -119.838908)
			(xy 18.313133 -119.938778) (xy 18.206351 -120.032758) (xy 18.094423 -120.120546) (xy 17.977707 -120.201862)
			(xy 17.856579 -120.276444) (xy 17.731425 -120.344053) (xy 17.602646 -120.404474) (xy 17.470655 -120.457512)
			(xy 17.335875 -120.502998) (xy 17.198737 -120.540786) (xy 17.059682 -120.570755) (xy 16.919153 -120.592809)
			(xy 16.777602 -120.606877) (xy 16.635482 -120.612914) (xy 16.493247 -120.610901) (xy 16.351355 -120.600844)
			(xy 16.210259 -120.582776) (xy 16.07041 -120.556755) (xy 15.932258 -120.522863) (xy 15.796245 -120.481209)
			(xy 15.662806 -120.431927) (xy 15.532369 -120.375175) (xy 15.405352 -120.311134) (xy 15.282161 -120.24001)
			(xy 15.163192 -120.16203) (xy 15.048824 -120.077444) (xy 14.939425 -119.986524) (xy 14.835346 -119.88956)
			(xy 14.736918 -119.786863) (xy 14.644459 -119.678761) (xy 14.558263 -119.565602) (xy 14.478608 -119.447748)
			(xy 14.405747 -119.325576) (xy 14.339916 -119.199478) (xy 14.281323 -119.069857) (xy 14.230158 -118.937129)
			(xy 14.186584 -118.801719) (xy 14.15074 -118.66406) (xy 14.122742 -118.524594) (xy 14.102679 -118.383768)
			(xy 14.090616 -118.242032) (xy 14.086591 -118.09984) (xy 0.509016 -118.09984) (xy 0.509016 -121.19991)
			(xy 75.486519 -121.19991) (xy 75.490544 -121.057718) (xy 75.502607 -120.915982) (xy 75.52267 -120.775156)
			(xy 75.550668 -120.63569) (xy 75.586512 -120.498031) (xy 75.630086 -120.362621) (xy 75.681251 -120.229893)
			(xy 75.739844 -120.100272) (xy 75.805675 -119.974174) (xy 75.878536 -119.852002) (xy 75.958191 -119.734148)
			(xy 76.044387 -119.620989) (xy 76.136846 -119.512887) (xy 76.235274 -119.41019) (xy 76.339353 -119.313226)
			(xy 76.448752 -119.222306) (xy 76.56312 -119.13772) (xy 76.682089 -119.05974) (xy 76.80528 -118.988616)
			(xy 76.932297 -118.924575) (xy 77.062734 -118.867823) (xy 77.196173 -118.818541) (xy 77.332186 -118.776887)
			(xy 77.470338 -118.742995) (xy 77.610187 -118.716974) (xy 77.751283 -118.698906) (xy 77.893175 -118.688849)
			(xy 78.03541 -118.686836) (xy 78.17753 -118.692873) (xy 78.319081 -118.706941) (xy 78.45961 -118.728995)
			(xy 78.598665 -118.758964) (xy 78.735803 -118.796752) (xy 78.870583 -118.842238) (xy 79.002574 -118.895276)
			(xy 79.131353 -118.955697) (xy 79.256507 -119.023306) (xy 79.377635 -119.097888) (xy 79.494351 -119.179204)
			(xy 79.606279 -119.266992) (xy 79.713061 -119.360972) (xy 79.814355 -119.460842) (xy 79.909836 -119.566284)
			(xy 79.9992 -119.676958) (xy 80.082158 -119.792511) (xy 80.158447 -119.912572) (xy 80.227821 -120.036757)
			(xy 80.290058 -120.164668) (xy 80.344959 -120.295895) (xy 80.392347 -120.430018) (xy 80.432072 -120.566607)
			(xy 80.464005 -120.705225) (xy 80.488046 -120.845427) (xy 80.504115 -120.986765) (xy 80.512163 -121.128786)
			(xy 80.512666 -121.19991) (xy 80.512163 -121.271034) (xy 80.504115 -121.413055) (xy 80.488046 -121.554393)
			(xy 80.464005 -121.694595) (xy 80.432072 -121.833213) (xy 80.392347 -121.969802) (xy 80.344959 -122.103925)
			(xy 80.290058 -122.235152) (xy 80.227821 -122.363063) (xy 80.158447 -122.487248) (xy 80.082158 -122.607309)
			(xy 79.9992 -122.722862) (xy 79.909836 -122.833536) (xy 79.814355 -122.938978) (xy 79.713061 -123.038848)
			(xy 79.606279 -123.132828) (xy 79.494351 -123.220616) (xy 79.377635 -123.301932) (xy 79.256507 -123.376514)
			(xy 79.131353 -123.444123) (xy 79.002574 -123.504544) (xy 78.870583 -123.557582) (xy 78.735803 -123.603068)
			(xy 78.598665 -123.640856) (xy 78.45961 -123.670825) (xy 78.319081 -123.692879) (xy 78.17753 -123.706947)
			(xy 78.03541 -123.712984) (xy 77.893175 -123.710971) (xy 77.751283 -123.700914) (xy 77.610187 -123.682846)
			(xy 77.470338 -123.656825) (xy 77.332186 -123.622933) (xy 77.196173 -123.581279) (xy 77.062734 -123.531997)
			(xy 76.932297 -123.475245) (xy 76.80528 -123.411204) (xy 76.682089 -123.34008) (xy 76.56312 -123.2621)
			(xy 76.448752 -123.177514) (xy 76.339353 -123.086594) (xy 76.235274 -122.98963) (xy 76.136846 -122.886933)
			(xy 76.044387 -122.778831) (xy 75.958191 -122.665672) (xy 75.878536 -122.547818) (xy 75.805675 -122.425646)
			(xy 75.739844 -122.299548) (xy 75.681251 -122.169927) (xy 75.630086 -122.037199) (xy 75.586512 -121.901789)
			(xy 75.550668 -121.76413) (xy 75.52267 -121.624664) (xy 75.502607 -121.483838) (xy 75.490544 -121.342102)
			(xy 75.486519 -121.19991) (xy 0.509016 -121.19991) (xy 0.509016 -138.163122) (xy 1.547863 -138.163122)
			(xy 1.547863 -138.036986) (xy 1.555783 -137.911098) (xy 1.571593 -137.785956) (xy 1.595228 -137.662053)
			(xy 1.626597 -137.53988) (xy 1.665575 -137.419917) (xy 1.712009 -137.302638) (xy 1.765716 -137.188506)
			(xy 1.826483 -137.077971) (xy 1.89407 -136.971471) (xy 1.968211 -136.869424) (xy 2.048614 -136.772234)
			(xy 2.13496 -136.680284) (xy 2.22691 -136.593938) (xy 2.3241 -136.513535) (xy 2.426147 -136.439394)
			(xy 2.532647 -136.371807) (xy 2.643182 -136.31104) (xy 2.757314 -136.257333) (xy 2.874593 -136.210899)
			(xy 2.994556 -136.171921) (xy 3.116729 -136.140552) (xy 3.240632 -136.116917) (xy 3.365774 -136.101107)
			(xy 3.491662 -136.093187) (xy 3.617798 -136.093187) (xy 3.743686 -136.101107) (xy 3.868828 -136.116917)
			(xy 3.992731 -136.140552) (xy 4.114904 -136.171921) (xy 4.234867 -136.210899) (xy 4.352146 -136.257333)
			(xy 4.466278 -136.31104) (xy 4.576813 -136.371807) (xy 4.683313 -136.439394) (xy 4.78536 -136.513535)
			(xy 4.88255 -136.593938) (xy 4.9745 -136.680284) (xy 5.060846 -136.772234) (xy 5.141249 -136.869424)
			(xy 5.21539 -136.971471) (xy 5.282977 -137.077971) (xy 5.343744 -137.188506) (xy 5.397451 -137.302638)
			(xy 5.443885 -137.419917) (xy 5.482863 -137.53988) (xy 5.514232 -137.662053) (xy 5.537867 -137.785956)
			(xy 5.553677 -137.911098) (xy 5.561597 -138.036986) (xy 5.562092 -138.100054) (xy 5.561597 -138.163122)
			(xy 12.977863 -138.163122) (xy 12.977863 -138.036986) (xy 12.985783 -137.911098) (xy 13.001593 -137.785956)
			(xy 13.025228 -137.662053) (xy 13.056597 -137.53988) (xy 13.095575 -137.419917) (xy 13.142009 -137.302638)
			(xy 13.195716 -137.188506) (xy 13.256483 -137.077971) (xy 13.32407 -136.971471) (xy 13.398211 -136.869424)
			(xy 13.478614 -136.772234) (xy 13.56496 -136.680284) (xy 13.65691 -136.593938) (xy 13.7541 -136.513535)
			(xy 13.856147 -136.439394) (xy 13.962647 -136.371807) (xy 14.073182 -136.31104) (xy 14.187314 -136.257333)
			(xy 14.304593 -136.210899) (xy 14.424556 -136.171921) (xy 14.546729 -136.140552) (xy 14.670632 -136.116917)
			(xy 14.795774 -136.101107) (xy 14.921662 -136.093187) (xy 15.047798 -136.093187) (xy 15.173686 -136.101107)
			(xy 15.298828 -136.116917) (xy 15.422731 -136.140552) (xy 15.544904 -136.171921) (xy 15.664867 -136.210899)
			(xy 15.782146 -136.257333) (xy 15.896278 -136.31104) (xy 16.006813 -136.371807) (xy 16.113313 -136.439394)
			(xy 16.21536 -136.513535) (xy 16.31255 -136.593938) (xy 16.4045 -136.680284) (xy 16.490846 -136.772234)
			(xy 16.571249 -136.869424) (xy 16.64539 -136.971471) (xy 16.712977 -137.077971) (xy 16.773744 -137.188506)
			(xy 16.827451 -137.302638) (xy 16.873885 -137.419917) (xy 16.912863 -137.53988) (xy 16.944232 -137.662053)
			(xy 16.967867 -137.785956) (xy 16.983677 -137.911098) (xy 16.991597 -138.036986) (xy 16.992092 -138.100054)
			(xy 16.991597 -138.163122) (xy 16.983677 -138.28901) (xy 16.967867 -138.414152) (xy 16.944232 -138.538055)
			(xy 16.912863 -138.660228) (xy 16.873885 -138.780191) (xy 16.827451 -138.89747) (xy 16.773744 -139.011602)
			(xy 16.712977 -139.122137) (xy 16.64539 -139.228637) (xy 16.571249 -139.330684) (xy 16.490846 -139.427874)
			(xy 16.4045 -139.519824) (xy 16.31255 -139.60617) (xy 16.21536 -139.686573) (xy 16.113313 -139.760714)
			(xy 16.006813 -139.828301) (xy 15.896278 -139.889068) (xy 15.782146 -139.942775) (xy 15.664867 -139.989209)
			(xy 15.544904 -140.028187) (xy 15.422731 -140.059556) (xy 15.298828 -140.083191) (xy 15.173686 -140.099001)
			(xy 15.047798 -140.106921) (xy 14.921662 -140.106921) (xy 14.795774 -140.099001) (xy 14.670632 -140.083191)
			(xy 14.546729 -140.059556) (xy 14.424556 -140.028187) (xy 14.304593 -139.989209) (xy 14.187314 -139.942775)
			(xy 14.073182 -139.889068) (xy 13.962647 -139.828301) (xy 13.856147 -139.760714) (xy 13.7541 -139.686573)
			(xy 13.65691 -139.60617) (xy 13.56496 -139.519824) (xy 13.478614 -139.427874) (xy 13.398211 -139.330684)
			(xy 13.32407 -139.228637) (xy 13.256483 -139.122137) (xy 13.195716 -139.011602) (xy 13.142009 -138.89747)
			(xy 13.095575 -138.780191) (xy 13.056597 -138.660228) (xy 13.025228 -138.538055) (xy 13.001593 -138.414152)
			(xy 12.985783 -138.28901) (xy 12.977863 -138.163122) (xy 5.561597 -138.163122) (xy 5.553677 -138.28901)
			(xy 5.537867 -138.414152) (xy 5.514232 -138.538055) (xy 5.482863 -138.660228) (xy 5.443885 -138.780191)
			(xy 5.397451 -138.89747) (xy 5.343744 -139.011602) (xy 5.282977 -139.122137) (xy 5.21539 -139.228637)
			(xy 5.141249 -139.330684) (xy 5.060846 -139.427874) (xy 4.9745 -139.519824) (xy 4.88255 -139.60617)
			(xy 4.78536 -139.686573) (xy 4.683313 -139.760714) (xy 4.576813 -139.828301) (xy 4.466278 -139.889068)
			(xy 4.352146 -139.942775) (xy 4.234867 -139.989209) (xy 4.114904 -140.028187) (xy 3.992731 -140.059556)
			(xy 3.868828 -140.083191) (xy 3.743686 -140.099001) (xy 3.617798 -140.106921) (xy 3.491662 -140.106921)
			(xy 3.365774 -140.099001) (xy 3.240632 -140.083191) (xy 3.116729 -140.059556) (xy 2.994556 -140.028187)
			(xy 2.874593 -139.989209) (xy 2.757314 -139.942775) (xy 2.643182 -139.889068) (xy 2.532647 -139.828301)
			(xy 2.426147 -139.760714) (xy 2.3241 -139.686573) (xy 2.22691 -139.60617) (xy 2.13496 -139.519824)
			(xy 2.048614 -139.427874) (xy 1.968211 -139.330684) (xy 1.89407 -139.228637) (xy 1.826483 -139.122137)
			(xy 1.765716 -139.011602) (xy 1.712009 -138.89747) (xy 1.665575 -138.780191) (xy 1.626597 -138.660228)
			(xy 1.595228 -138.538055) (xy 1.571593 -138.414152) (xy 1.555783 -138.28901) (xy 1.547863 -138.163122)
			(xy 0.509016 -138.163122) (xy 0.509016 -140.26007) (xy 39.818317 -140.26007) (xy 39.822324 -140.144046)
			(xy 39.834326 -140.028574) (xy 39.854266 -139.914206) (xy 39.882049 -139.801486) (xy 39.917543 -139.690952)
			(xy 39.960578 -139.583129) (xy 40.010949 -139.478532) (xy 40.068416 -139.37766) (xy 40.132706 -139.280993)
			(xy 40.203511 -139.188992) (xy 40.280495 -139.102095) (xy 40.363291 -139.020716) (xy 40.451504 -138.945243)
			(xy 40.544714 -138.876036) (xy 40.642477 -138.813424) (xy 40.744326 -138.757707) (xy 40.849776 -138.709149)
			(xy 40.958325 -138.667981) (xy 41.069456 -138.634401) (xy 41.182639 -138.608568) (xy 41.297334 -138.590605)
			(xy 41.412996 -138.580597) (xy 41.529072 -138.578594) (xy 41.64501 -138.584603) (xy 41.760257 -138.598596)
			(xy 41.874263 -138.620507) (xy 41.986487 -138.650232) (xy 42.096393 -138.687628) (xy 42.203456 -138.732517)
			(xy 42.307168 -138.784686) (xy 42.407033 -138.843886) (xy 42.502576 -138.909835) (xy 42.593342 -138.982218)
			(xy 42.678897 -139.060691) (xy 42.758835 -139.144879) (xy 42.832774 -139.234381) (xy 42.900362 -139.328772)
			(xy 42.961276 -139.4276) (xy 43.015228 -139.530396) (xy 43.061958 -139.636669) (xy 43.101246 -139.745913)
			(xy 43.132903 -139.857606) (xy 43.156779 -139.971218) (xy 43.17276 -140.086206) (xy 43.180769 -140.202023)
			(xy 43.18127 -140.26007) (xy 43.180769 -140.318117) (xy 43.17276 -140.433934) (xy 43.156779 -140.548922)
			(xy 43.132903 -140.662534) (xy 43.101246 -140.774227) (xy 43.061958 -140.883471) (xy 43.015228 -140.989744)
			(xy 42.961276 -141.09254) (xy 42.900362 -141.191368) (xy 42.832774 -141.285759) (xy 42.758835 -141.375261)
			(xy 42.678897 -141.459449) (xy 42.593342 -141.537922) (xy 42.502858 -141.61008) (xy 93.15476 -141.61008)
			(xy 93.158776 -141.49381) (xy 93.170803 -141.378095) (xy 93.190785 -141.263485) (xy 93.218627 -141.150526)
			(xy 93.254196 -141.039758) (xy 93.297322 -140.931707) (xy 93.347799 -140.826889) (xy 93.405388 -140.725804)
			(xy 93.469814 -140.628932) (xy 93.540769 -140.536736) (xy 93.617916 -140.449655) (xy 93.700887 -140.368104)
			(xy 93.789287 -140.292472) (xy 93.882694 -140.223118) (xy 93.980663 -140.160375) (xy 94.082727 -140.104539)
			(xy 94.188401 -140.055878) (xy 94.29718 -140.014624) (xy 94.408545 -139.980973) (xy 94.521968 -139.955085)
			(xy 94.636905 -139.937084) (xy 94.752811 -139.927055) (xy 94.869133 -139.925047) (xy 94.985316 -139.931069)
			(xy 95.100807 -139.945092) (xy 95.215055 -139.96705) (xy 95.327516 -139.996837) (xy 95.437654 -140.034312)
			(xy 95.544944 -140.079297) (xy 95.648875 -140.131576) (xy 95.748951 -140.190901) (xy 95.844697 -140.256989)
			(xy 95.935654 -140.329525) (xy 96.02139 -140.408164) (xy 96.101497 -140.49253) (xy 96.175593 -140.582222)
			(xy 96.243323 -140.676812) (xy 96.304367 -140.77585) (xy 96.358432 -140.878863) (xy 96.405262 -140.98536)
			(xy 96.444633 -141.094835) (xy 96.476357 -141.206765) (xy 96.500283 -141.320617) (xy 96.516297 -141.435849)
			(xy 96.524324 -141.551911) (xy 96.524826 -141.61008) (xy 96.524324 -141.668249) (xy 96.516297 -141.784311)
			(xy 96.500283 -141.899543) (xy 96.476357 -142.013395) (xy 96.444633 -142.125325) (xy 96.405262 -142.2348)
			(xy 96.358432 -142.341297) (xy 96.304367 -142.44431) (xy 96.243323 -142.543348) (xy 96.175593 -142.637938)
			(xy 96.101497 -142.72763) (xy 96.02139 -142.811996) (xy 95.935654 -142.890635) (xy 95.844697 -142.963171)
			(xy 95.748951 -143.029259) (xy 95.648875 -143.088584) (xy 95.544944 -143.140863) (xy 95.437654 -143.185848)
			(xy 95.327516 -143.223323) (xy 95.215055 -143.25311) (xy 95.100807 -143.275068) (xy 94.985316 -143.289091)
			(xy 94.869133 -143.295113) (xy 94.752811 -143.293105) (xy 94.636905 -143.283076) (xy 94.521968 -143.265075)
			(xy 94.408545 -143.239187) (xy 94.29718 -143.205536) (xy 94.188401 -143.164282) (xy 94.082727 -143.115621)
			(xy 93.980663 -143.059785) (xy 93.882694 -142.997042) (xy 93.789287 -142.927688) (xy 93.700887 -142.852056)
			(xy 93.617916 -142.770505) (xy 93.540769 -142.683424) (xy 93.469814 -142.591228) (xy 93.405388 -142.494356)
			(xy 93.347799 -142.393271) (xy 93.297322 -142.288453) (xy 93.254196 -142.180402) (xy 93.218627 -142.069634)
			(xy 93.190785 -141.956675) (xy 93.170803 -141.842065) (xy 93.158776 -141.72635) (xy 93.15476 -141.61008)
			(xy 42.502858 -141.61008) (xy 42.502576 -141.610305) (xy 42.407033 -141.676254) (xy 42.307168 -141.735454)
			(xy 42.203456 -141.787623) (xy 42.096393 -141.832512) (xy 41.986487 -141.869908) (xy 41.874263 -141.899633)
			(xy 41.760257 -141.921544) (xy 41.64501 -141.935537) (xy 41.529072 -141.941546) (xy 41.412996 -141.939543)
			(xy 41.297334 -141.929535) (xy 41.182639 -141.911572) (xy 41.069456 -141.885739) (xy 40.958325 -141.852159)
			(xy 40.849776 -141.810991) (xy 40.744326 -141.762433) (xy 40.642477 -141.706716) (xy 40.544714 -141.644104)
			(xy 40.451504 -141.574897) (xy 40.363291 -141.499424) (xy 40.280495 -141.418045) (xy 40.203511 -141.331148)
			(xy 40.132706 -141.239147) (xy 40.068416 -141.14248) (xy 40.010949 -141.041608) (xy 39.960578 -140.937011)
			(xy 39.917543 -140.829188) (xy 39.882049 -140.718654) (xy 39.854266 -140.605934) (xy 39.834326 -140.491566)
			(xy 39.822324 -140.376094) (xy 39.818317 -140.26007) (xy 0.509016 -140.26007) (xy 0.509016 -153.359866)
			(xy 86.877404 -153.359866) (xy 86.881424 -153.169215) (xy 86.893478 -152.978902) (xy 86.913544 -152.789267)
			(xy 86.941587 -152.600646) (xy 86.977556 -152.413376) (xy 87.021388 -152.227788) (xy 87.073005 -152.044213)
			(xy 87.132315 -151.862977) (xy 87.199213 -151.684402) (xy 87.273579 -151.508807) (xy 87.355281 -151.336502)
			(xy 87.444175 -151.167795) (xy 87.540101 -151.002985) (xy 87.64289 -150.842366) (xy 87.752359 -150.686223)
			(xy 87.868313 -150.534834) (xy 87.990547 -150.388467) (xy 88.118841 -150.247383) (xy 88.252969 -150.111834)
			(xy 88.392693 -149.982059) (xy 88.537763 -149.858289) (xy 88.687921 -149.740746) (xy 88.842902 -149.629637)
			(xy 89.002429 -149.52516) (xy 89.166218 -149.427501) (xy 89.333978 -149.336834) (xy 89.505412 -149.25332)
			(xy 89.680214 -149.177107) (xy 89.858073 -149.108331) (xy 90.038674 -149.047113) (xy 90.221694 -148.993564)
			(xy 90.40681 -148.947778) (xy 90.593691 -148.909836) (xy 90.782006 -148.879807) (xy 90.971419 -148.857742)
			(xy 91.161593 -148.843683) (xy 91.352192 -148.837653) (xy 91.542875 -148.839663) (xy 91.733304 -148.84971)
			(xy 91.92314 -148.867776) (xy 92.112046 -148.893829) (xy 92.299685 -148.927822) (xy 92.485725 -148.969695)
			(xy 92.669834 -149.019374) (xy 92.851685 -149.07677) (xy 93.030955 -149.141781) (xy 93.207325 -149.214292)
			(xy 93.380481 -149.294173) (xy 93.550116 -149.381283) (xy 93.715928 -149.475467) (xy 93.877622 -149.576558)
			(xy 94.03491 -149.684374) (xy 94.187513 -149.798726) (xy 94.335161 -149.919409) (xy 94.477589 -150.04621)
			(xy 94.614545 -150.178901) (xy 94.745786 -150.317249) (xy 94.871078 -150.461006) (xy 94.990198 -150.609917)
			(xy 95.102934 -150.763718) (xy 95.209087 -150.922134) (xy 95.308467 -151.084885) (xy 95.400897 -151.25168)
			(xy 95.486214 -151.422224) (xy 95.564266 -151.596212) (xy 95.634913 -151.773337) (xy 95.698031 -151.953282)
			(xy 95.753507 -152.135728) (xy 95.801242 -152.320351) (xy 95.841152 -152.506821) (xy 95.873165 -152.694809)
			(xy 95.897225 -152.883979) (xy 95.913288 -153.073995) (xy 95.921327 -153.264519) (xy 95.92183 -153.359866)
			(xy 95.921327 -153.455213) (xy 95.913288 -153.645737) (xy 95.897225 -153.835753) (xy 95.873165 -154.024923)
			(xy 95.841152 -154.212911) (xy 95.801242 -154.399381) (xy 95.753507 -154.584004) (xy 95.698031 -154.76645)
			(xy 95.634913 -154.946395) (xy 95.564266 -155.12352) (xy 95.486214 -155.297508) (xy 95.400897 -155.468052)
			(xy 95.308467 -155.634847) (xy 95.209087 -155.797598) (xy 95.102934 -155.956014) (xy 94.990198 -156.109815)
			(xy 94.871078 -156.258726) (xy 94.745786 -156.402483) (xy 94.614545 -156.540831) (xy 94.477589 -156.673522)
			(xy 94.335161 -156.800323) (xy 94.187513 -156.921006) (xy 94.03491 -157.035358) (xy 93.877622 -157.143174)
			(xy 93.715928 -157.244265) (xy 93.550116 -157.338449) (xy 93.380481 -157.425559) (xy 93.207325 -157.50544)
			(xy 93.030955 -157.577951) (xy 92.851685 -157.642962) (xy 92.669834 -157.700358) (xy 92.485725 -157.750037)
			(xy 92.299685 -157.79191) (xy 92.112046 -157.825903) (xy 91.92314 -157.851956) (xy 91.733304 -157.870022)
			(xy 91.542875 -157.880069) (xy 91.352192 -157.882079) (xy 91.161593 -157.876049) (xy 90.971419 -157.86199)
			(xy 90.782006 -157.839925) (xy 90.593691 -157.809896) (xy 90.40681 -157.771954) (xy 90.221694 -157.726168)
			(xy 90.038674 -157.672619) (xy 89.858073 -157.611401) (xy 89.680214 -157.542625) (xy 89.505412 -157.466412)
			(xy 89.333978 -157.382898) (xy 89.166218 -157.292231) (xy 89.002429 -157.194572) (xy 88.842902 -157.090095)
			(xy 88.687921 -156.978986) (xy 88.537763 -156.861443) (xy 88.392693 -156.737673) (xy 88.252969 -156.607898)
			(xy 88.118841 -156.472349) (xy 87.990547 -156.331265) (xy 87.868313 -156.184898) (xy 87.752359 -156.033509)
			(xy 87.64289 -155.877366) (xy 87.540101 -155.716747) (xy 87.444175 -155.551937) (xy 87.355281 -155.38323)
			(xy 87.273579 -155.210925) (xy 87.199213 -155.03533) (xy 87.132315 -154.856755) (xy 87.073005 -154.675519)
			(xy 87.021388 -154.491944) (xy 86.977556 -154.306356) (xy 86.941587 -154.119086) (xy 86.913544 -153.930465)
			(xy 86.893478 -153.74083) (xy 86.881424 -153.550517) (xy 86.877404 -153.359866) (xy 0.509016 -153.359866)
			(xy 0.509016 -184.71007) (xy 39.818317 -184.71007) (xy 39.822324 -184.594046) (xy 39.834326 -184.478574)
			(xy 39.854266 -184.364206) (xy 39.882049 -184.251486) (xy 39.917543 -184.140952) (xy 39.960578 -184.033129)
			(xy 40.010949 -183.928532) (xy 40.068416 -183.82766) (xy 40.132706 -183.730993) (xy 40.203511 -183.638992)
			(xy 40.280495 -183.552095) (xy 40.363291 -183.470716) (xy 40.451504 -183.395243) (xy 40.544714 -183.326036)
			(xy 40.642477 -183.263424) (xy 40.744326 -183.207707) (xy 40.849776 -183.159149) (xy 40.958325 -183.117981)
			(xy 41.069456 -183.084401) (xy 41.182639 -183.058568) (xy 41.297334 -183.040605) (xy 41.412996 -183.030597)
			(xy 41.529072 -183.028594) (xy 41.64501 -183.034603) (xy 41.760257 -183.048596) (xy 41.874263 -183.070507)
			(xy 41.986487 -183.100232) (xy 42.096393 -183.137628) (xy 42.203456 -183.182517) (xy 42.307168 -183.234686)
			(xy 42.407033 -183.293886) (xy 42.502576 -183.359835) (xy 42.593342 -183.432218) (xy 42.678897 -183.510691)
			(xy 42.758835 -183.594879) (xy 42.832774 -183.684381) (xy 42.900362 -183.778772) (xy 42.961276 -183.8776)
			(xy 43.015228 -183.980396) (xy 43.061958 -184.086669) (xy 43.101246 -184.195913) (xy 43.132903 -184.307606)
			(xy 43.156779 -184.421218) (xy 43.17276 -184.536206) (xy 43.180769 -184.652023) (xy 43.18127 -184.71007)
			(xy 43.180769 -184.768117) (xy 43.17276 -184.883934) (xy 43.156779 -184.998922) (xy 43.132903 -185.112534)
			(xy 43.101246 -185.224227) (xy 43.061958 -185.333471) (xy 43.015228 -185.439744) (xy 42.961276 -185.54254)
			(xy 42.900362 -185.641368) (xy 42.832774 -185.735759) (xy 42.758835 -185.825261) (xy 42.678897 -185.909449)
			(xy 42.593342 -185.987922) (xy 42.502858 -186.06008) (xy 93.15476 -186.06008) (xy 93.158776 -185.94381)
			(xy 93.170803 -185.828095) (xy 93.190785 -185.713485) (xy 93.218627 -185.600526) (xy 93.254196 -185.489758)
			(xy 93.297322 -185.381707) (xy 93.347799 -185.276889) (xy 93.405388 -185.175804) (xy 93.469814 -185.078932)
			(xy 93.540769 -184.986736) (xy 93.617916 -184.899655) (xy 93.700887 -184.818104) (xy 93.789287 -184.742472)
			(xy 93.882694 -184.673118) (xy 93.980663 -184.610375) (xy 94.082727 -184.554539) (xy 94.188401 -184.505878)
			(xy 94.29718 -184.464624) (xy 94.408545 -184.430973) (xy 94.521968 -184.405085) (xy 94.636905 -184.387084)
			(xy 94.752811 -184.377055) (xy 94.869133 -184.375047) (xy 94.985316 -184.381069) (xy 95.100807 -184.395092)
			(xy 95.215055 -184.41705) (xy 95.327516 -184.446837) (xy 95.437654 -184.484312) (xy 95.544944 -184.529297)
			(xy 95.648875 -184.581576) (xy 95.748951 -184.640901) (xy 95.844697 -184.706989) (xy 95.935654 -184.779525)
			(xy 96.02139 -184.858164) (xy 96.101497 -184.94253) (xy 96.175593 -185.032222) (xy 96.243323 -185.126812)
			(xy 96.304367 -185.22585) (xy 96.358432 -185.328863) (xy 96.405262 -185.43536) (xy 96.444633 -185.544835)
			(xy 96.476357 -185.656765) (xy 96.500283 -185.770617) (xy 96.516297 -185.885849) (xy 96.524324 -186.001911)
			(xy 96.524826 -186.06008) (xy 96.524324 -186.118249) (xy 96.516297 -186.234311) (xy 96.500283 -186.349543)
			(xy 96.476357 -186.463395) (xy 96.444633 -186.575325) (xy 96.405262 -186.6848) (xy 96.358432 -186.791297)
			(xy 96.304367 -186.89431) (xy 96.243323 -186.993348) (xy 96.175593 -187.087938) (xy 96.101497 -187.17763)
			(xy 96.02139 -187.261996) (xy 95.935654 -187.340635) (xy 95.844697 -187.413171) (xy 95.748951 -187.479259)
			(xy 95.648875 -187.538584) (xy 95.544944 -187.590863) (xy 95.437654 -187.635848) (xy 95.327516 -187.673323)
			(xy 95.215055 -187.70311) (xy 95.100807 -187.725068) (xy 94.985316 -187.739091) (xy 94.869133 -187.745113)
			(xy 94.752811 -187.743105) (xy 94.636905 -187.733076) (xy 94.521968 -187.715075) (xy 94.408545 -187.689187)
			(xy 94.29718 -187.655536) (xy 94.188401 -187.614282) (xy 94.082727 -187.565621) (xy 93.980663 -187.509785)
			(xy 93.882694 -187.447042) (xy 93.789287 -187.377688) (xy 93.700887 -187.302056) (xy 93.617916 -187.220505)
			(xy 93.540769 -187.133424) (xy 93.469814 -187.041228) (xy 93.405388 -186.944356) (xy 93.347799 -186.843271)
			(xy 93.297322 -186.738453) (xy 93.254196 -186.630402) (xy 93.218627 -186.519634) (xy 93.190785 -186.406675)
			(xy 93.170803 -186.292065) (xy 93.158776 -186.17635) (xy 93.15476 -186.06008) (xy 42.502858 -186.06008)
			(xy 42.502576 -186.060305) (xy 42.407033 -186.126254) (xy 42.307168 -186.185454) (xy 42.203456 -186.237623)
			(xy 42.096393 -186.282512) (xy 41.986487 -186.319908) (xy 41.874263 -186.349633) (xy 41.760257 -186.371544)
			(xy 41.64501 -186.385537) (xy 41.529072 -186.391546) (xy 41.412996 -186.389543) (xy 41.297334 -186.379535)
			(xy 41.182639 -186.361572) (xy 41.069456 -186.335739) (xy 40.958325 -186.302159) (xy 40.849776 -186.260991)
			(xy 40.744326 -186.212433) (xy 40.642477 -186.156716) (xy 40.544714 -186.094104) (xy 40.451504 -186.024897)
			(xy 40.363291 -185.949424) (xy 40.280495 -185.868045) (xy 40.203511 -185.781148) (xy 40.132706 -185.689147)
			(xy 40.068416 -185.59248) (xy 40.010949 -185.491608) (xy 39.960578 -185.387011) (xy 39.917543 -185.279188)
			(xy 39.882049 -185.168654) (xy 39.854266 -185.055934) (xy 39.834326 -184.941566) (xy 39.822324 -184.826094)
			(xy 39.818317 -184.71007) (xy 0.509016 -184.71007) (xy 0.509016 -197.81012) (xy 86.877404 -197.81012)
			(xy 86.881424 -197.619469) (xy 86.893478 -197.429156) (xy 86.913544 -197.239521) (xy 86.941587 -197.0509)
			(xy 86.977556 -196.86363) (xy 87.021388 -196.678042) (xy 87.073005 -196.494467) (xy 87.132315 -196.313231)
			(xy 87.199213 -196.134656) (xy 87.273579 -195.959061) (xy 87.355281 -195.786756) (xy 87.444175 -195.618049)
			(xy 87.540101 -195.453239) (xy 87.64289 -195.29262) (xy 87.752359 -195.136477) (xy 87.868313 -194.985088)
			(xy 87.990547 -194.838721) (xy 88.118841 -194.697637) (xy 88.252969 -194.562088) (xy 88.392693 -194.432313)
			(xy 88.537763 -194.308543) (xy 88.687921 -194.191) (xy 88.842902 -194.079891) (xy 89.002429 -193.975414)
			(xy 89.166218 -193.877755) (xy 89.333978 -193.787088) (xy 89.505412 -193.703574) (xy 89.680214 -193.627361)
			(xy 89.858073 -193.558585) (xy 90.038674 -193.497367) (xy 90.221694 -193.443818) (xy 90.40681 -193.398032)
			(xy 90.593691 -193.36009) (xy 90.782006 -193.330061) (xy 90.971419 -193.307996) (xy 91.161593 -193.293937)
			(xy 91.352192 -193.287907) (xy 91.542875 -193.289917) (xy 91.733304 -193.299964) (xy 91.92314 -193.31803)
			(xy 92.112046 -193.344083) (xy 92.299685 -193.378076) (xy 92.485725 -193.419949) (xy 92.669834 -193.469628)
			(xy 92.851685 -193.527024) (xy 93.030955 -193.592035) (xy 93.207325 -193.664546) (xy 93.380481 -193.744427)
			(xy 93.550116 -193.831537) (xy 93.715928 -193.925721) (xy 93.877622 -194.026812) (xy 94.03491 -194.134628)
			(xy 94.187513 -194.24898) (xy 94.335161 -194.369663) (xy 94.477589 -194.496464) (xy 94.614545 -194.629155)
			(xy 94.745786 -194.767503) (xy 94.871078 -194.91126) (xy 94.990198 -195.060171) (xy 95.102934 -195.213972)
			(xy 95.209087 -195.372388) (xy 95.308467 -195.535139) (xy 95.400897 -195.701934) (xy 95.486214 -195.872478)
			(xy 95.564266 -196.046466) (xy 95.634913 -196.223591) (xy 95.698031 -196.403536) (xy 95.753507 -196.585982)
			(xy 95.801242 -196.770605) (xy 95.841152 -196.957075) (xy 95.873165 -197.145063) (xy 95.897225 -197.334233)
			(xy 95.913288 -197.524249) (xy 95.921327 -197.714773) (xy 95.92183 -197.81012) (xy 95.921327 -197.905467)
			(xy 95.913288 -198.095991) (xy 95.897225 -198.286007) (xy 95.873165 -198.475177) (xy 95.841152 -198.663165)
			(xy 95.801242 -198.849635) (xy 95.753507 -199.034258) (xy 95.698031 -199.216704) (xy 95.634913 -199.396649)
			(xy 95.564266 -199.573774) (xy 95.486214 -199.747762) (xy 95.400897 -199.918306) (xy 95.308467 -200.085101)
			(xy 95.209087 -200.247852) (xy 95.102934 -200.406268) (xy 94.990198 -200.560069) (xy 94.871078 -200.70898)
			(xy 94.745786 -200.852737) (xy 94.614545 -200.991085) (xy 94.477589 -201.123776) (xy 94.335161 -201.250577)
			(xy 94.187513 -201.37126) (xy 94.03491 -201.485612) (xy 93.877622 -201.593428) (xy 93.715928 -201.694519)
			(xy 93.550116 -201.788703) (xy 93.380481 -201.875813) (xy 93.207325 -201.955694) (xy 93.030955 -202.028205)
			(xy 92.851685 -202.093216) (xy 92.669834 -202.150612) (xy 92.485725 -202.200291) (xy 92.299685 -202.242164)
			(xy 92.112046 -202.276157) (xy 91.92314 -202.30221) (xy 91.733304 -202.320276) (xy 91.542875 -202.330323)
			(xy 91.352192 -202.332333) (xy 91.161593 -202.326303) (xy 90.971419 -202.312244) (xy 90.782006 -202.290179)
			(xy 90.593691 -202.26015) (xy 90.40681 -202.222208) (xy 90.221694 -202.176422) (xy 90.038674 -202.122873)
			(xy 89.858073 -202.061655) (xy 89.680214 -201.992879) (xy 89.505412 -201.916666) (xy 89.333978 -201.833152)
			(xy 89.166218 -201.742485) (xy 89.002429 -201.644826) (xy 88.842902 -201.540349) (xy 88.687921 -201.42924)
			(xy 88.537763 -201.311697) (xy 88.392693 -201.187927) (xy 88.252969 -201.058152) (xy 88.118841 -200.922603)
			(xy 87.990547 -200.781519) (xy 87.868313 -200.635152) (xy 87.752359 -200.483763) (xy 87.64289 -200.32762)
			(xy 87.540101 -200.167001) (xy 87.444175 -200.002191) (xy 87.355281 -199.833484) (xy 87.273579 -199.661179)
			(xy 87.199213 -199.485584) (xy 87.132315 -199.307009) (xy 87.073005 -199.125773) (xy 87.021388 -198.942198)
			(xy 86.977556 -198.75661) (xy 86.941587 -198.56934) (xy 86.913544 -198.380719) (xy 86.893478 -198.191084)
			(xy 86.881424 -198.000771) (xy 86.877404 -197.81012) (xy 0.509016 -197.81012) (xy 0.509016 -206.99984)
			(xy 14.086591 -206.99984) (xy 14.090616 -206.857648) (xy 14.102679 -206.715912) (xy 14.122742 -206.575086)
			(xy 14.15074 -206.43562) (xy 14.186584 -206.297961) (xy 14.230158 -206.162551) (xy 14.281323 -206.029823)
			(xy 14.339916 -205.900202) (xy 14.405747 -205.774104) (xy 14.478608 -205.651932) (xy 14.558263 -205.534078)
			(xy 14.644459 -205.420919) (xy 14.736918 -205.312817) (xy 14.835346 -205.21012) (xy 14.939425 -205.113156)
			(xy 15.048824 -205.022236) (xy 15.163192 -204.93765) (xy 15.282161 -204.85967) (xy 15.405352 -204.788546)
			(xy 15.532369 -204.724505) (xy 15.662806 -204.667753) (xy 15.796245 -204.618471) (xy 15.932258 -204.576817)
			(xy 16.07041 -204.542925) (xy 16.210259 -204.516904) (xy 16.351355 -204.498836) (xy 16.493247 -204.488779)
			(xy 16.635482 -204.486766) (xy 16.777602 -204.492803) (xy 16.919153 -204.506871) (xy 17.059682 -204.528925)
			(xy 17.198737 -204.558894) (xy 17.335875 -204.596682) (xy 17.470655 -204.642168) (xy 17.602646 -204.695206)
			(xy 17.731425 -204.755627) (xy 17.856579 -204.823236) (xy 17.977707 -204.897818) (xy 18.094423 -204.979134)
			(xy 18.206351 -205.066922) (xy 18.313133 -205.160902) (xy 18.414427 -205.260772) (xy 18.509908 -205.366214)
			(xy 18.599272 -205.476888) (xy 18.68223 -205.592441) (xy 18.758519 -205.712502) (xy 18.827893 -205.836687)
			(xy 18.89013 -205.964598) (xy 18.945031 -206.095825) (xy 18.992419 -206.229948) (xy 19.032144 -206.366537)
			(xy 19.064077 -206.505155) (xy 19.088118 -206.645357) (xy 19.104187 -206.786695) (xy 19.112235 -206.928716)
			(xy 19.112738 -206.99984) (xy 19.112235 -207.070964) (xy 19.104187 -207.212985) (xy 19.088118 -207.354323)
			(xy 19.064077 -207.494525) (xy 19.032144 -207.633143) (xy 18.992419 -207.769732) (xy 18.945031 -207.903855)
			(xy 18.89013 -208.035082) (xy 18.827893 -208.162993) (xy 18.758519 -208.287178) (xy 18.68223 -208.407239)
			(xy 18.599272 -208.522792) (xy 18.509908 -208.633466) (xy 18.414427 -208.738908) (xy 18.313133 -208.838778)
			(xy 18.206351 -208.932758) (xy 18.094423 -209.020546) (xy 17.977707 -209.101862) (xy 17.856579 -209.176444)
			(xy 17.731425 -209.244053) (xy 17.602646 -209.304474) (xy 17.470655 -209.357512) (xy 17.335875 -209.402998)
			(xy 17.198737 -209.440786) (xy 17.059682 -209.470755) (xy 16.919153 -209.492809) (xy 16.777602 -209.506877)
			(xy 16.635482 -209.512914) (xy 16.493247 -209.510901) (xy 16.351355 -209.500844) (xy 16.210259 -209.482776)
			(xy 16.07041 -209.456755) (xy 15.932258 -209.422863) (xy 15.796245 -209.381209) (xy 15.662806 -209.331927)
			(xy 15.532369 -209.275175) (xy 15.405352 -209.211134) (xy 15.282161 -209.14001) (xy 15.163192 -209.06203)
			(xy 15.048824 -208.977444) (xy 14.939425 -208.886524) (xy 14.835346 -208.78956) (xy 14.736918 -208.686863)
			(xy 14.644459 -208.578761) (xy 14.558263 -208.465602) (xy 14.478608 -208.347748) (xy 14.405747 -208.225576)
			(xy 14.339916 -208.099478) (xy 14.281323 -207.969857) (xy 14.230158 -207.837129) (xy 14.186584 -207.701719)
			(xy 14.15074 -207.56406) (xy 14.122742 -207.424594) (xy 14.102679 -207.283768) (xy 14.090616 -207.142032)
			(xy 14.086591 -206.99984) (xy 0.509016 -206.99984) (xy 0.509016 -210.09991) (xy 75.486519 -210.09991)
			(xy 75.490544 -209.957718) (xy 75.502607 -209.815982) (xy 75.52267 -209.675156) (xy 75.550668 -209.53569)
			(xy 75.586512 -209.398031) (xy 75.630086 -209.262621) (xy 75.681251 -209.129893) (xy 75.739844 -209.000272)
			(xy 75.805675 -208.874174) (xy 75.878536 -208.752002) (xy 75.958191 -208.634148) (xy 76.044387 -208.520989)
			(xy 76.136846 -208.412887) (xy 76.235274 -208.31019) (xy 76.339353 -208.213226) (xy 76.448752 -208.122306)
			(xy 76.56312 -208.03772) (xy 76.682089 -207.95974) (xy 76.80528 -207.888616) (xy 76.932297 -207.824575)
			(xy 77.062734 -207.767823) (xy 77.196173 -207.718541) (xy 77.332186 -207.676887) (xy 77.470338 -207.642995)
			(xy 77.610187 -207.616974) (xy 77.751283 -207.598906) (xy 77.893175 -207.588849) (xy 78.03541 -207.586836)
			(xy 78.17753 -207.592873) (xy 78.319081 -207.606941) (xy 78.45961 -207.628995) (xy 78.598665 -207.658964)
			(xy 78.735803 -207.696752) (xy 78.870583 -207.742238) (xy 79.002574 -207.795276) (xy 79.131353 -207.855697)
			(xy 79.256507 -207.923306) (xy 79.377635 -207.997888) (xy 79.494351 -208.079204) (xy 79.606279 -208.166992)
			(xy 79.713061 -208.260972) (xy 79.814355 -208.360842) (xy 79.909836 -208.466284) (xy 79.9992 -208.576958)
			(xy 80.082158 -208.692511) (xy 80.158447 -208.812572) (xy 80.227821 -208.936757) (xy 80.290058 -209.064668)
			(xy 80.344959 -209.195895) (xy 80.392347 -209.330018) (xy 80.432072 -209.466607) (xy 80.464005 -209.605225)
			(xy 80.488046 -209.745427) (xy 80.504115 -209.886765) (xy 80.512163 -210.028786) (xy 80.512666 -210.09991)
			(xy 80.512163 -210.171034) (xy 80.504115 -210.313055) (xy 80.488046 -210.454393) (xy 80.464005 -210.594595)
			(xy 80.432072 -210.733213) (xy 80.392347 -210.869802) (xy 80.344959 -211.003925) (xy 80.290058 -211.135152)
			(xy 80.227821 -211.263063) (xy 80.158447 -211.387248) (xy 80.082158 -211.507309) (xy 79.9992 -211.622862)
			(xy 79.909836 -211.733536) (xy 79.814355 -211.838978) (xy 79.713061 -211.938848) (xy 79.606279 -212.032828)
			(xy 79.494351 -212.120616) (xy 79.377635 -212.201932) (xy 79.256507 -212.276514) (xy 79.131353 -212.344123)
			(xy 79.002574 -212.404544) (xy 78.870583 -212.457582) (xy 78.735803 -212.503068) (xy 78.598665 -212.540856)
			(xy 78.45961 -212.570825) (xy 78.319081 -212.592879) (xy 78.17753 -212.606947) (xy 78.03541 -212.612984)
			(xy 77.893175 -212.610971) (xy 77.751283 -212.600914) (xy 77.610187 -212.582846) (xy 77.470338 -212.556825)
			(xy 77.332186 -212.522933) (xy 77.196173 -212.481279) (xy 77.062734 -212.431997) (xy 76.932297 -212.375245)
			(xy 76.80528 -212.311204) (xy 76.682089 -212.24008) (xy 76.56312 -212.1621) (xy 76.448752 -212.077514)
			(xy 76.339353 -211.986594) (xy 76.235274 -211.88963) (xy 76.136846 -211.786933) (xy 76.044387 -211.678831)
			(xy 75.958191 -211.565672) (xy 75.878536 -211.447818) (xy 75.805675 -211.325646) (xy 75.739844 -211.199548)
			(xy 75.681251 -211.069927) (xy 75.630086 -210.937199) (xy 75.586512 -210.801789) (xy 75.550668 -210.66413)
			(xy 75.52267 -210.524664) (xy 75.502607 -210.383838) (xy 75.490544 -210.242102) (xy 75.486519 -210.09991)
			(xy 0.509016 -210.09991) (xy 0.509016 -229.16007) (xy 39.818063 -229.16007) (xy 39.82207 -229.044046)
			(xy 39.834072 -228.928574) (xy 39.854012 -228.814206) (xy 39.881795 -228.701486) (xy 39.917289 -228.590952)
			(xy 39.960324 -228.483129) (xy 40.010695 -228.378532) (xy 40.068162 -228.27766) (xy 40.132452 -228.180993)
			(xy 40.203257 -228.088992) (xy 40.280241 -228.002095) (xy 40.363037 -227.920716) (xy 40.45125 -227.845243)
			(xy 40.54446 -227.776036) (xy 40.642223 -227.713424) (xy 40.744072 -227.657707) (xy 40.849522 -227.609149)
			(xy 40.958071 -227.567981) (xy 41.069202 -227.534401) (xy 41.182385 -227.508568) (xy 41.29708 -227.490605)
			(xy 41.412742 -227.480597) (xy 41.528818 -227.478594) (xy 41.644756 -227.484603) (xy 41.760003 -227.498596)
			(xy 41.874009 -227.520507) (xy 41.986233 -227.550232) (xy 42.096139 -227.587628) (xy 42.203202 -227.632517)
			(xy 42.306914 -227.684686) (xy 42.406779 -227.743886) (xy 42.502322 -227.809835) (xy 42.593088 -227.882218)
			(xy 42.678643 -227.960691) (xy 42.758581 -228.044879) (xy 42.83252 -228.134381) (xy 42.900108 -228.228772)
			(xy 42.961022 -228.3276) (xy 43.014974 -228.430396) (xy 43.061704 -228.536669) (xy 43.100992 -228.645913)
			(xy 43.132649 -228.757606) (xy 43.156525 -228.871218) (xy 43.172506 -228.986206) (xy 43.180515 -229.102023)
			(xy 43.181016 -229.16007) (xy 43.180515 -229.218117) (xy 43.172506 -229.333934) (xy 43.156525 -229.448922)
			(xy 43.132649 -229.562534) (xy 43.100992 -229.674227) (xy 43.061704 -229.783471) (xy 43.014974 -229.889744)
			(xy 42.961022 -229.99254) (xy 42.900108 -230.091368) (xy 42.83252 -230.185759) (xy 42.758581 -230.275261)
			(xy 42.678643 -230.359449) (xy 42.593088 -230.437922) (xy 42.502604 -230.51008) (xy 93.154506 -230.51008)
			(xy 93.158522 -230.39381) (xy 93.170549 -230.278095) (xy 93.190531 -230.163485) (xy 93.218373 -230.050526)
			(xy 93.253942 -229.939758) (xy 93.297068 -229.831707) (xy 93.347545 -229.726889) (xy 93.405134 -229.625804)
			(xy 93.46956 -229.528932) (xy 93.540515 -229.436736) (xy 93.617662 -229.349655) (xy 93.700633 -229.268104)
			(xy 93.789033 -229.192472) (xy 93.88244 -229.123118) (xy 93.980409 -229.060375) (xy 94.082473 -229.004539)
			(xy 94.188147 -228.955878) (xy 94.296926 -228.914624) (xy 94.408291 -228.880973) (xy 94.521714 -228.855085)
			(xy 94.636651 -228.837084) (xy 94.752557 -228.827055) (xy 94.868879 -228.825047) (xy 94.985062 -228.831069)
			(xy 95.100553 -228.845092) (xy 95.214801 -228.86705) (xy 95.327262 -228.896837) (xy 95.4374 -228.934312)
			(xy 95.54469 -228.979297) (xy 95.648621 -229.031576) (xy 95.748697 -229.090901) (xy 95.844443 -229.156989)
			(xy 95.9354 -229.229525) (xy 96.021136 -229.308164) (xy 96.101243 -229.39253) (xy 96.175339 -229.482222)
			(xy 96.243069 -229.576812) (xy 96.304113 -229.67585) (xy 96.358178 -229.778863) (xy 96.405008 -229.88536)
			(xy 96.444379 -229.994835) (xy 96.476103 -230.106765) (xy 96.500029 -230.220617) (xy 96.516043 -230.335849)
			(xy 96.52407 -230.451911) (xy 96.524572 -230.51008) (xy 96.52407 -230.568249) (xy 96.516043 -230.684311)
			(xy 96.500029 -230.799543) (xy 96.476103 -230.913395) (xy 96.444379 -231.025325) (xy 96.405008 -231.1348)
			(xy 96.358178 -231.241297) (xy 96.304113 -231.34431) (xy 96.243069 -231.443348) (xy 96.175339 -231.537938)
			(xy 96.101243 -231.62763) (xy 96.021136 -231.711996) (xy 95.9354 -231.790635) (xy 95.844443 -231.863171)
			(xy 95.748697 -231.929259) (xy 95.648621 -231.988584) (xy 95.54469 -232.040863) (xy 95.4374 -232.085848)
			(xy 95.327262 -232.123323) (xy 95.214801 -232.15311) (xy 95.100553 -232.175068) (xy 94.985062 -232.189091)
			(xy 94.868879 -232.195113) (xy 94.752557 -232.193105) (xy 94.636651 -232.183076) (xy 94.521714 -232.165075)
			(xy 94.408291 -232.139187) (xy 94.296926 -232.105536) (xy 94.188147 -232.064282) (xy 94.082473 -232.015621)
			(xy 93.980409 -231.959785) (xy 93.88244 -231.897042) (xy 93.789033 -231.827688) (xy 93.700633 -231.752056)
			(xy 93.617662 -231.670505) (xy 93.540515 -231.583424) (xy 93.46956 -231.491228) (xy 93.405134 -231.394356)
			(xy 93.347545 -231.293271) (xy 93.297068 -231.188453) (xy 93.253942 -231.080402) (xy 93.218373 -230.969634)
			(xy 93.190531 -230.856675) (xy 93.170549 -230.742065) (xy 93.158522 -230.62635) (xy 93.154506 -230.51008)
			(xy 42.502604 -230.51008) (xy 42.502322 -230.510305) (xy 42.406779 -230.576254) (xy 42.306914 -230.635454)
			(xy 42.203202 -230.687623) (xy 42.096139 -230.732512) (xy 41.986233 -230.769908) (xy 41.874009 -230.799633)
			(xy 41.760003 -230.821544) (xy 41.644756 -230.835537) (xy 41.528818 -230.841546) (xy 41.412742 -230.839543)
			(xy 41.29708 -230.829535) (xy 41.182385 -230.811572) (xy 41.069202 -230.785739) (xy 40.958071 -230.752159)
			(xy 40.849522 -230.710991) (xy 40.744072 -230.662433) (xy 40.642223 -230.606716) (xy 40.54446 -230.544104)
			(xy 40.45125 -230.474897) (xy 40.363037 -230.399424) (xy 40.280241 -230.318045) (xy 40.203257 -230.231148)
			(xy 40.132452 -230.139147) (xy 40.068162 -230.04248) (xy 40.010695 -229.941608) (xy 39.960324 -229.837011)
			(xy 39.917289 -229.729188) (xy 39.881795 -229.618654) (xy 39.854012 -229.505934) (xy 39.834072 -229.391566)
			(xy 39.82207 -229.276094) (xy 39.818063 -229.16007) (xy 0.509016 -229.16007) (xy 0.509016 -242.26012)
			(xy 86.877404 -242.26012) (xy 86.881424 -242.069469) (xy 86.893478 -241.879156) (xy 86.913544 -241.689521)
			(xy 86.941587 -241.5009) (xy 86.977556 -241.31363) (xy 87.021388 -241.128042) (xy 87.073005 -240.944467)
			(xy 87.132315 -240.763231) (xy 87.199213 -240.584656) (xy 87.273579 -240.409061) (xy 87.355281 -240.236756)
			(xy 87.444175 -240.068049) (xy 87.540101 -239.903239) (xy 87.64289 -239.74262) (xy 87.752359 -239.586477)
			(xy 87.868313 -239.435088) (xy 87.990547 -239.288721) (xy 88.118841 -239.147637) (xy 88.252969 -239.012088)
			(xy 88.392693 -238.882313) (xy 88.537763 -238.758543) (xy 88.687921 -238.641) (xy 88.842902 -238.529891)
			(xy 89.002429 -238.425414) (xy 89.166218 -238.327755) (xy 89.333978 -238.237088) (xy 89.505412 -238.153574)
			(xy 89.680214 -238.077361) (xy 89.858073 -238.008585) (xy 90.038674 -237.947367) (xy 90.221694 -237.893818)
			(xy 90.40681 -237.848032) (xy 90.593691 -237.81009) (xy 90.782006 -237.780061) (xy 90.971419 -237.757996)
			(xy 91.161593 -237.743937) (xy 91.352192 -237.737907) (xy 91.542875 -237.739917) (xy 91.733304 -237.749964)
			(xy 91.92314 -237.76803) (xy 92.112046 -237.794083) (xy 92.299685 -237.828076) (xy 92.485725 -237.869949)
			(xy 92.669834 -237.919628) (xy 92.851685 -237.977024) (xy 93.030955 -238.042035) (xy 93.207325 -238.114546)
			(xy 93.380481 -238.194427) (xy 93.550116 -238.281537) (xy 93.715928 -238.375721) (xy 93.877622 -238.476812)
			(xy 94.03491 -238.584628) (xy 94.187513 -238.69898) (xy 94.335161 -238.819663) (xy 94.477589 -238.946464)
			(xy 94.614545 -239.079155) (xy 94.745786 -239.217503) (xy 94.871078 -239.36126) (xy 94.990198 -239.510171)
			(xy 95.102934 -239.663972) (xy 95.209087 -239.822388) (xy 95.308467 -239.985139) (xy 95.400897 -240.151934)
			(xy 95.486214 -240.322478) (xy 95.564266 -240.496466) (xy 95.634913 -240.673591) (xy 95.698031 -240.853536)
			(xy 95.753507 -241.035982) (xy 95.801242 -241.220605) (xy 95.841152 -241.407075) (xy 95.873165 -241.595063)
			(xy 95.897225 -241.784233) (xy 95.913288 -241.974249) (xy 95.921327 -242.164773) (xy 95.92183 -242.26012)
			(xy 95.921327 -242.355467) (xy 95.913288 -242.545991) (xy 95.897225 -242.736007) (xy 95.873165 -242.925177)
			(xy 95.841152 -243.113165) (xy 95.801242 -243.299635) (xy 95.753507 -243.484258) (xy 95.698031 -243.666704)
			(xy 95.634913 -243.846649) (xy 95.564266 -244.023774) (xy 95.486214 -244.197762) (xy 95.400897 -244.368306)
			(xy 95.308467 -244.535101) (xy 95.209087 -244.697852) (xy 95.102934 -244.856268) (xy 94.990198 -245.010069)
			(xy 94.871078 -245.15898) (xy 94.745786 -245.302737) (xy 94.614545 -245.441085) (xy 94.477589 -245.573776)
			(xy 94.335161 -245.700577) (xy 94.187513 -245.82126) (xy 94.03491 -245.935612) (xy 93.877622 -246.043428)
			(xy 93.715928 -246.144519) (xy 93.550116 -246.238703) (xy 93.380481 -246.325813) (xy 93.207325 -246.405694)
			(xy 93.030955 -246.478205) (xy 92.851685 -246.543216) (xy 92.669834 -246.600612) (xy 92.485725 -246.650291)
			(xy 92.299685 -246.692164) (xy 92.112046 -246.726157) (xy 91.92314 -246.75221) (xy 91.733304 -246.770276)
			(xy 91.542875 -246.780323) (xy 91.352192 -246.782333) (xy 91.161593 -246.776303) (xy 90.971419 -246.762244)
			(xy 90.782006 -246.740179) (xy 90.593691 -246.71015) (xy 90.40681 -246.672208) (xy 90.221694 -246.626422)
			(xy 90.038674 -246.572873) (xy 89.858073 -246.511655) (xy 89.680214 -246.442879) (xy 89.505412 -246.366666)
			(xy 89.333978 -246.283152) (xy 89.166218 -246.192485) (xy 89.002429 -246.094826) (xy 88.842902 -245.990349)
			(xy 88.687921 -245.87924) (xy 88.537763 -245.761697) (xy 88.392693 -245.637927) (xy 88.252969 -245.508152)
			(xy 88.118841 -245.372603) (xy 87.990547 -245.231519) (xy 87.868313 -245.085152) (xy 87.752359 -244.933763)
			(xy 87.64289 -244.77762) (xy 87.540101 -244.617001) (xy 87.444175 -244.452191) (xy 87.355281 -244.283484)
			(xy 87.273579 -244.111179) (xy 87.199213 -243.935584) (xy 87.132315 -243.757009) (xy 87.073005 -243.575773)
			(xy 87.021388 -243.392198) (xy 86.977556 -243.20661) (xy 86.941587 -243.01934) (xy 86.913544 -242.830719)
			(xy 86.893478 -242.641084) (xy 86.881424 -242.450771) (xy 86.877404 -242.26012) (xy 0.509016 -242.26012)
			(xy 0.509016 -250.020582) (xy 3.582162 -250.020582) (xy 3.582659 -249.96334) (xy 3.590757 -249.849142)
			(xy 3.606915 -249.735803) (xy 3.631052 -249.623892) (xy 3.663046 -249.513969) (xy 3.702737 -249.406585)
			(xy 3.749927 -249.302279) (xy 3.804379 -249.201573) (xy 3.865819 -249.104971) (xy 3.93394 -249.012959)
			(xy 4.008401 -248.925998) (xy 4.088828 -248.844523) (xy 4.174818 -248.768942) (xy 4.26594 -248.699635)
			(xy 4.361737 -248.636949) (xy 4.46173 -248.581198) (xy 4.565416 -248.532661) (xy 4.672277 -248.491582)
			(xy 4.781777 -248.458167) (xy 4.893366 -248.432584) (xy 5.006486 -248.414959) (xy 5.120569 -248.405383)
			(xy 5.235044 -248.403902) (xy 5.349337 -248.410524) (xy 5.462875 -248.425217) (xy 5.575088 -248.447906)
			(xy 5.685416 -248.478477) (xy 5.793303 -248.516778) (xy 5.898211 -248.562616) (xy 5.999612 -248.615762)
			(xy 6.096999 -248.67595) (xy 6.189883 -248.742876) (xy 6.277799 -248.816208) (xy 6.360307 -248.895575)
			(xy 6.436992 -248.980582) (xy 6.50747 -249.070801) (xy 6.571389 -249.16578) (xy 6.628427 -249.265044)
			(xy 6.678299 -249.368095) (xy 6.720755 -249.474417) (xy 6.755581 -249.583475) (xy 6.782604 -249.694725)
			(xy 6.801689 -249.807607) (xy 6.812738 -249.921558) (xy 6.815698 -250.036004) (xy 6.810552 -250.150373)
			(xy 6.797328 -250.264091) (xy 6.77609 -250.376588) (xy 6.746947 -250.487301) (xy 6.710043 -250.595675)
			(xy 6.665563 -250.701165) (xy 6.613732 -250.803245) (xy 6.554808 -250.901401) (xy 6.489086 -250.995142)
			(xy 6.453378 -251.039884) (xy 6.059424 -251.039884) (xy 6.020367 -251.072253) (xy 5.938107 -251.131626)
			(xy 5.895086 -251.158502) (xy 5.881509 -251.167452) (xy 5.858992 -251.190897) (xy 5.843109 -251.219259)
			(xy 5.834884 -251.250707) (xy 5.83438 -251.26696) (xy 5.83438 -251.50699) (xy 5.779686 -251.529797)
			(xy 5.667599 -251.568292) (xy 5.552993 -251.598476) (xy 5.436486 -251.620186) (xy 5.318701 -251.633307)
			(xy 5.200272 -251.637768) (xy 5.081834 -251.633545) (xy 4.964023 -251.62066) (xy 4.847473 -251.599183)
			(xy 4.732807 -251.569229) (xy 4.620643 -251.530959) (xy 4.565904 -251.50826) (xy 4.565904 -251.26823)
			(xy 4.56544 -251.25195) (xy 4.557181 -251.220454) (xy 4.541219 -251.192074) (xy 4.518594 -251.168658)
			(xy 4.504944 -251.159772) (xy 4.45885 -251.131059) (xy 4.370982 -251.067228) (xy 4.32943 -251.032264)
			(xy 3.937762 -251.032264) (xy 3.903919 -250.989342) (xy 3.841441 -250.89964) (xy 3.785164 -250.805923)
			(xy 3.735346 -250.708619) (xy 3.692214 -250.608172) (xy 3.655964 -250.505042) (xy 3.626762 -250.399698)
			(xy 3.604742 -250.292623) (xy 3.590005 -250.184306) (xy 3.582617 -250.07524) (xy 3.582162 -250.020582)
			(xy 0.509016 -250.020582) (xy 0.509016 -267.869924) (xy 3.584453 -267.869924) (xy 3.588477 -267.755973)
			(xy 3.600528 -267.642589) (xy 3.620548 -267.530339) (xy 3.648436 -267.419779) (xy 3.684054 -267.311463)
			(xy 3.727223 -267.205929) (xy 3.777729 -267.103702) (xy 3.83532 -267.005294) (xy 3.899709 -266.911192)
			(xy 3.970576 -266.821867) (xy 4.047567 -266.737763) (xy 4.130299 -266.6593) (xy 4.218359 -266.586868)
			(xy 4.31131 -266.520828) (xy 4.408687 -266.461509) (xy 4.510006 -266.409207) (xy 4.614762 -266.364182)
			(xy 4.722433 -266.326658) (xy 4.832482 -266.296824) (xy 4.944363 -266.274826) (xy 5.057516 -266.260775)
			(xy 5.171378 -266.25474) (xy 5.285382 -266.256752) (xy 5.398961 -266.266801) (xy 5.511548 -266.284837)
			(xy 5.622582 -266.31077) (xy 5.73151 -266.34447) (xy 5.83779 -266.38577) (xy 5.940891 -266.434464)
			(xy 6.040301 -266.490309) (xy 6.135524 -266.553028) (xy 6.226086 -266.622307) (xy 6.311536 -266.697801)
			(xy 6.391447 -266.779136) (xy 6.465422 -266.865904) (xy 6.533092 -266.957675) (xy 6.59412 -267.05399)
			(xy 6.648202 -267.15437) (xy 6.695069 -267.258315) (xy 6.734487 -267.365307) (xy 6.766259 -267.474813)
			(xy 6.790228 -267.586287) (xy 6.806274 -267.699175) (xy 6.814317 -267.812913) (xy 6.81482 -267.869924)
			(xy 6.814317 -267.926935) (xy 6.806274 -268.040673) (xy 6.790228 -268.153561) (xy 6.766259 -268.265035)
			(xy 6.734487 -268.374541) (xy 6.695069 -268.481533) (xy 6.648202 -268.585478) (xy 6.59412 -268.685858)
			(xy 6.533092 -268.782173) (xy 6.465422 -268.873944) (xy 6.391447 -268.960712) (xy 6.311536 -269.042047)
			(xy 6.226086 -269.117541) (xy 6.135524 -269.18682) (xy 6.040301 -269.249539) (xy 5.940891 -269.305384)
			(xy 5.83779 -269.354078) (xy 5.73151 -269.395378) (xy 5.622582 -269.429078) (xy 5.511548 -269.455011)
			(xy 5.398961 -269.473047) (xy 5.285382 -269.483096) (xy 5.171378 -269.485108) (xy 5.057516 -269.479073)
			(xy 4.944363 -269.465022) (xy 4.832482 -269.443024) (xy 4.722433 -269.41319) (xy 4.614762 -269.375666)
			(xy 4.510006 -269.330641) (xy 4.408687 -269.278339) (xy 4.31131 -269.21902) (xy 4.218359 -269.15298)
			(xy 4.130299 -269.080548) (xy 4.047567 -269.002085) (xy 3.970576 -268.917981) (xy 3.899709 -268.828656)
			(xy 3.83532 -268.734554) (xy 3.777729 -268.636146) (xy 3.727223 -268.533919) (xy 3.684054 -268.428385)
			(xy 3.648436 -268.320069) (xy 3.620548 -268.209509) (xy 3.600528 -268.097259) (xy 3.588477 -267.983875)
			(xy 3.584453 -267.869924) (xy 0.509016 -267.869924) (xy 0.509016 -273.61007) (xy 39.818063 -273.61007)
			(xy 39.82207 -273.494046) (xy 39.834072 -273.378574) (xy 39.854012 -273.264206) (xy 39.881795 -273.151486)
			(xy 39.917289 -273.040952) (xy 39.960324 -272.933129) (xy 40.010695 -272.828532) (xy 40.068162 -272.72766)
			(xy 40.132452 -272.630993) (xy 40.203257 -272.538992) (xy 40.280241 -272.452095) (xy 40.363037 -272.370716)
			(xy 40.45125 -272.295243) (xy 40.54446 -272.226036) (xy 40.642223 -272.163424) (xy 40.744072 -272.107707)
			(xy 40.849522 -272.059149) (xy 40.958071 -272.017981) (xy 41.069202 -271.984401) (xy 41.182385 -271.958568)
			(xy 41.29708 -271.940605) (xy 41.412742 -271.930597) (xy 41.528818 -271.928594) (xy 41.644756 -271.934603)
			(xy 41.760003 -271.948596) (xy 41.874009 -271.970507) (xy 41.986233 -272.000232) (xy 42.096139 -272.037628)
			(xy 42.203202 -272.082517) (xy 42.306914 -272.134686) (xy 42.406779 -272.193886) (xy 42.502322 -272.259835)
			(xy 42.593088 -272.332218) (xy 42.678643 -272.410691) (xy 42.758581 -272.494879) (xy 42.83252 -272.584381)
			(xy 42.900108 -272.678772) (xy 42.961022 -272.7776) (xy 43.014974 -272.880396) (xy 43.061704 -272.986669)
			(xy 43.100992 -273.095913) (xy 43.132649 -273.207606) (xy 43.156525 -273.321218) (xy 43.172506 -273.436206)
			(xy 43.180515 -273.552023) (xy 43.181016 -273.61007) (xy 43.180515 -273.668117) (xy 43.172506 -273.783934)
			(xy 43.156525 -273.898922) (xy 43.132649 -274.012534) (xy 43.100992 -274.124227) (xy 43.061704 -274.233471)
			(xy 43.014974 -274.339744) (xy 42.961022 -274.44254) (xy 42.900108 -274.541368) (xy 42.83252 -274.635759)
			(xy 42.758581 -274.725261) (xy 42.678643 -274.809449) (xy 42.593088 -274.887922) (xy 42.502604 -274.96008)
			(xy 93.154506 -274.96008) (xy 93.158522 -274.84381) (xy 93.170549 -274.728095) (xy 93.190531 -274.613485)
			(xy 93.218373 -274.500526) (xy 93.253942 -274.389758) (xy 93.297068 -274.281707) (xy 93.347545 -274.176889)
			(xy 93.405134 -274.075804) (xy 93.46956 -273.978932) (xy 93.540515 -273.886736) (xy 93.617662 -273.799655)
			(xy 93.700633 -273.718104) (xy 93.789033 -273.642472) (xy 93.88244 -273.573118) (xy 93.980409 -273.510375)
			(xy 94.082473 -273.454539) (xy 94.188147 -273.405878) (xy 94.296926 -273.364624) (xy 94.408291 -273.330973)
			(xy 94.521714 -273.305085) (xy 94.636651 -273.287084) (xy 94.752557 -273.277055) (xy 94.868879 -273.275047)
			(xy 94.985062 -273.281069) (xy 95.100553 -273.295092) (xy 95.214801 -273.31705) (xy 95.327262 -273.346837)
			(xy 95.4374 -273.384312) (xy 95.54469 -273.429297) (xy 95.648621 -273.481576) (xy 95.748697 -273.540901)
			(xy 95.844443 -273.606989) (xy 95.9354 -273.679525) (xy 96.021136 -273.758164) (xy 96.101243 -273.84253)
			(xy 96.175339 -273.932222) (xy 96.243069 -274.026812) (xy 96.304113 -274.12585) (xy 96.358178 -274.228863)
			(xy 96.405008 -274.33536) (xy 96.444379 -274.444835) (xy 96.476103 -274.556765) (xy 96.500029 -274.670617)
			(xy 96.516043 -274.785849) (xy 96.52407 -274.901911) (xy 96.524572 -274.96008) (xy 96.52407 -275.018249)
			(xy 96.516043 -275.134311) (xy 96.500029 -275.249543) (xy 96.476103 -275.363395) (xy 96.444379 -275.475325)
			(xy 96.405008 -275.5848) (xy 96.358178 -275.691297) (xy 96.304113 -275.79431) (xy 96.243069 -275.893348)
			(xy 96.175339 -275.987938) (xy 96.101243 -276.07763) (xy 96.021136 -276.161996) (xy 95.9354 -276.240635)
			(xy 95.844443 -276.313171) (xy 95.748697 -276.379259) (xy 95.648621 -276.438584) (xy 95.54469 -276.490863)
			(xy 95.4374 -276.535848) (xy 95.327262 -276.573323) (xy 95.214801 -276.60311) (xy 95.100553 -276.625068)
			(xy 94.985062 -276.639091) (xy 94.868879 -276.645113) (xy 94.752557 -276.643105) (xy 94.636651 -276.633076)
			(xy 94.521714 -276.615075) (xy 94.408291 -276.589187) (xy 94.296926 -276.555536) (xy 94.188147 -276.514282)
			(xy 94.082473 -276.465621) (xy 93.980409 -276.409785) (xy 93.88244 -276.347042) (xy 93.789033 -276.277688)
			(xy 93.700633 -276.202056) (xy 93.617662 -276.120505) (xy 93.540515 -276.033424) (xy 93.46956 -275.941228)
			(xy 93.405134 -275.844356) (xy 93.347545 -275.743271) (xy 93.297068 -275.638453) (xy 93.253942 -275.530402)
			(xy 93.218373 -275.419634) (xy 93.190531 -275.306675) (xy 93.170549 -275.192065) (xy 93.158522 -275.07635)
			(xy 93.154506 -274.96008) (xy 42.502604 -274.96008) (xy 42.502322 -274.960305) (xy 42.406779 -275.026254)
			(xy 42.306914 -275.085454) (xy 42.203202 -275.137623) (xy 42.096139 -275.182512) (xy 41.986233 -275.219908)
			(xy 41.874009 -275.249633) (xy 41.760003 -275.271544) (xy 41.644756 -275.285537) (xy 41.528818 -275.291546)
			(xy 41.412742 -275.289543) (xy 41.29708 -275.279535) (xy 41.182385 -275.261572) (xy 41.069202 -275.235739)
			(xy 40.958071 -275.202159) (xy 40.849522 -275.160991) (xy 40.744072 -275.112433) (xy 40.642223 -275.056716)
			(xy 40.54446 -274.994104) (xy 40.45125 -274.924897) (xy 40.363037 -274.849424) (xy 40.280241 -274.768045)
			(xy 40.203257 -274.681148) (xy 40.132452 -274.589147) (xy 40.068162 -274.49248) (xy 40.010695 -274.391608)
			(xy 39.960324 -274.287011) (xy 39.917289 -274.179188) (xy 39.881795 -274.068654) (xy 39.854012 -273.955934)
			(xy 39.834072 -273.841566) (xy 39.82207 -273.726094) (xy 39.818063 -273.61007) (xy 0.509016 -273.61007)
			(xy 0.509016 -286.709866) (xy 86.877404 -286.709866) (xy 86.881424 -286.519215) (xy 86.893478 -286.328902)
			(xy 86.913544 -286.139267) (xy 86.941587 -285.950646) (xy 86.977556 -285.763376) (xy 87.021388 -285.577788)
			(xy 87.073005 -285.394213) (xy 87.132315 -285.212977) (xy 87.199213 -285.034402) (xy 87.273579 -284.858807)
			(xy 87.355281 -284.686502) (xy 87.444175 -284.517795) (xy 87.540101 -284.352985) (xy 87.64289 -284.192366)
			(xy 87.752359 -284.036223) (xy 87.868313 -283.884834) (xy 87.990547 -283.738467) (xy 88.118841 -283.597383)
			(xy 88.252969 -283.461834) (xy 88.392693 -283.332059) (xy 88.537763 -283.208289) (xy 88.687921 -283.090746)
			(xy 88.842902 -282.979637) (xy 89.002429 -282.87516) (xy 89.166218 -282.777501) (xy 89.333978 -282.686834)
			(xy 89.505412 -282.60332) (xy 89.680214 -282.527107) (xy 89.858073 -282.458331) (xy 90.038674 -282.397113)
			(xy 90.221694 -282.343564) (xy 90.40681 -282.297778) (xy 90.593691 -282.259836) (xy 90.782006 -282.229807)
			(xy 90.971419 -282.207742) (xy 91.161593 -282.193683) (xy 91.352192 -282.187653) (xy 91.542875 -282.189663)
			(xy 91.733304 -282.19971) (xy 91.92314 -282.217776) (xy 92.112046 -282.243829) (xy 92.299685 -282.277822)
			(xy 92.485725 -282.319695) (xy 92.669834 -282.369374) (xy 92.851685 -282.42677) (xy 93.030955 -282.491781)
			(xy 93.207325 -282.564292) (xy 93.380481 -282.644173) (xy 93.550116 -282.731283) (xy 93.715928 -282.825467)
			(xy 93.877622 -282.926558) (xy 94.03491 -283.034374) (xy 94.187513 -283.148726) (xy 94.335161 -283.269409)
			(xy 94.477589 -283.39621) (xy 94.614545 -283.528901) (xy 94.745786 -283.667249) (xy 94.871078 -283.811006)
			(xy 94.990198 -283.959917) (xy 95.102934 -284.113718) (xy 95.209087 -284.272134) (xy 95.308467 -284.434885)
			(xy 95.400897 -284.60168) (xy 95.486214 -284.772224) (xy 95.564266 -284.946212) (xy 95.634913 -285.123337)
			(xy 95.698031 -285.303282) (xy 95.753507 -285.485728) (xy 95.801242 -285.670351) (xy 95.841152 -285.856821)
			(xy 95.873165 -286.044809) (xy 95.897225 -286.233979) (xy 95.913288 -286.423995) (xy 95.921327 -286.614519)
			(xy 95.92183 -286.709866) (xy 95.921327 -286.805213) (xy 95.913288 -286.995737) (xy 95.897225 -287.185753)
			(xy 95.873165 -287.374923) (xy 95.841152 -287.562911) (xy 95.801242 -287.749381) (xy 95.753507 -287.934004)
			(xy 95.698031 -288.11645) (xy 95.634913 -288.296395) (xy 95.564266 -288.47352) (xy 95.486214 -288.647508)
			(xy 95.400897 -288.818052) (xy 95.308467 -288.984847) (xy 95.209087 -289.147598) (xy 95.102934 -289.306014)
			(xy 94.990198 -289.459815) (xy 94.871078 -289.608726) (xy 94.745786 -289.752483) (xy 94.614545 -289.890831)
			(xy 94.477589 -290.023522) (xy 94.335161 -290.150323) (xy 94.187513 -290.271006) (xy 94.03491 -290.385358)
			(xy 93.877622 -290.493174) (xy 93.715928 -290.594265) (xy 93.550116 -290.688449) (xy 93.380481 -290.775559)
			(xy 93.207325 -290.85544) (xy 93.030955 -290.927951) (xy 92.851685 -290.992962) (xy 92.669834 -291.050358)
			(xy 92.485725 -291.100037) (xy 92.299685 -291.14191) (xy 92.112046 -291.175903) (xy 91.92314 -291.201956)
			(xy 91.733304 -291.220022) (xy 91.542875 -291.230069) (xy 91.352192 -291.232079) (xy 91.161593 -291.226049)
			(xy 90.971419 -291.21199) (xy 90.782006 -291.189925) (xy 90.593691 -291.159896) (xy 90.40681 -291.121954)
			(xy 90.221694 -291.076168) (xy 90.038674 -291.022619) (xy 89.858073 -290.961401) (xy 89.680214 -290.892625)
			(xy 89.505412 -290.816412) (xy 89.333978 -290.732898) (xy 89.166218 -290.642231) (xy 89.002429 -290.544572)
			(xy 88.842902 -290.440095) (xy 88.687921 -290.328986) (xy 88.537763 -290.211443) (xy 88.392693 -290.087673)
			(xy 88.252969 -289.957898) (xy 88.118841 -289.822349) (xy 87.990547 -289.681265) (xy 87.868313 -289.534898)
			(xy 87.752359 -289.383509) (xy 87.64289 -289.227366) (xy 87.540101 -289.066747) (xy 87.444175 -288.901937)
			(xy 87.355281 -288.73323) (xy 87.273579 -288.560925) (xy 87.199213 -288.38533) (xy 87.132315 -288.206755)
			(xy 87.073005 -288.025519) (xy 87.021388 -287.841944) (xy 86.977556 -287.656356) (xy 86.941587 -287.469086)
			(xy 86.913544 -287.280465) (xy 86.893478 -287.09083) (xy 86.881424 -286.900517) (xy 86.877404 -286.709866)
			(xy 0.509016 -286.709866) (xy 0.509016 -295.89984) (xy 14.086591 -295.89984) (xy 14.090616 -295.757648)
			(xy 14.102679 -295.615912) (xy 14.122742 -295.475086) (xy 14.15074 -295.33562) (xy 14.186584 -295.197961)
			(xy 14.230158 -295.062551) (xy 14.281323 -294.929823) (xy 14.339916 -294.800202) (xy 14.405747 -294.674104)
			(xy 14.478608 -294.551932) (xy 14.558263 -294.434078) (xy 14.644459 -294.320919) (xy 14.736918 -294.212817)
			(xy 14.835346 -294.11012) (xy 14.939425 -294.013156) (xy 15.048824 -293.922236) (xy 15.163192 -293.83765)
			(xy 15.282161 -293.75967) (xy 15.405352 -293.688546) (xy 15.532369 -293.624505) (xy 15.662806 -293.567753)
			(xy 15.796245 -293.518471) (xy 15.932258 -293.476817) (xy 16.07041 -293.442925) (xy 16.210259 -293.416904)
			(xy 16.351355 -293.398836) (xy 16.493247 -293.388779) (xy 16.635482 -293.386766) (xy 16.777602 -293.392803)
			(xy 16.919153 -293.406871) (xy 17.059682 -293.428925) (xy 17.198737 -293.458894) (xy 17.335875 -293.496682)
			(xy 17.470655 -293.542168) (xy 17.602646 -293.595206) (xy 17.731425 -293.655627) (xy 17.856579 -293.723236)
			(xy 17.977707 -293.797818) (xy 18.094423 -293.879134) (xy 18.206351 -293.966922) (xy 18.313133 -294.060902)
			(xy 18.414427 -294.160772) (xy 18.509908 -294.266214) (xy 18.599272 -294.376888) (xy 18.68223 -294.492441)
			(xy 18.758519 -294.612502) (xy 18.827893 -294.736687) (xy 18.89013 -294.864598) (xy 18.945031 -294.995825)
			(xy 18.992419 -295.129948) (xy 19.032144 -295.266537) (xy 19.064077 -295.405155) (xy 19.088118 -295.545357)
			(xy 19.104187 -295.686695) (xy 19.112235 -295.828716) (xy 19.112738 -295.89984) (xy 19.112235 -295.970964)
			(xy 19.104187 -296.112985) (xy 19.088118 -296.254323) (xy 19.064077 -296.394525) (xy 19.032144 -296.533143)
			(xy 18.992419 -296.669732) (xy 18.945031 -296.803855) (xy 18.89013 -296.935082) (xy 18.827893 -297.062993)
			(xy 18.758519 -297.187178) (xy 18.68223 -297.307239) (xy 18.599272 -297.422792) (xy 18.509908 -297.533466)
			(xy 18.414427 -297.638908) (xy 18.313133 -297.738778) (xy 18.206351 -297.832758) (xy 18.094423 -297.920546)
			(xy 17.977707 -298.001862) (xy 17.856579 -298.076444) (xy 17.731425 -298.144053) (xy 17.602646 -298.204474)
			(xy 17.470655 -298.257512) (xy 17.335875 -298.302998) (xy 17.198737 -298.340786) (xy 17.059682 -298.370755)
			(xy 16.919153 -298.392809) (xy 16.777602 -298.406877) (xy 16.635482 -298.412914) (xy 16.493247 -298.410901)
			(xy 16.351355 -298.400844) (xy 16.210259 -298.382776) (xy 16.07041 -298.356755) (xy 15.932258 -298.322863)
			(xy 15.796245 -298.281209) (xy 15.662806 -298.231927) (xy 15.532369 -298.175175) (xy 15.405352 -298.111134)
			(xy 15.282161 -298.04001) (xy 15.163192 -297.96203) (xy 15.048824 -297.877444) (xy 14.939425 -297.786524)
			(xy 14.835346 -297.68956) (xy 14.736918 -297.586863) (xy 14.644459 -297.478761) (xy 14.558263 -297.365602)
			(xy 14.478608 -297.247748) (xy 14.405747 -297.125576) (xy 14.339916 -296.999478) (xy 14.281323 -296.869857)
			(xy 14.230158 -296.737129) (xy 14.186584 -296.601719) (xy 14.15074 -296.46406) (xy 14.122742 -296.324594)
			(xy 14.102679 -296.183768) (xy 14.090616 -296.042032) (xy 14.086591 -295.89984) (xy 0.509016 -295.89984)
			(xy 0.509016 -318.06007) (xy 39.818063 -318.06007) (xy 39.82207 -317.944046) (xy 39.834072 -317.828574)
			(xy 39.854012 -317.714206) (xy 39.881795 -317.601486) (xy 39.917289 -317.490952) (xy 39.960324 -317.383129)
			(xy 40.010695 -317.278532) (xy 40.068162 -317.17766) (xy 40.132452 -317.080993) (xy 40.203257 -316.988992)
			(xy 40.280241 -316.902095) (xy 40.363037 -316.820716) (xy 40.45125 -316.745243) (xy 40.54446 -316.676036)
			(xy 40.642223 -316.613424) (xy 40.744072 -316.557707) (xy 40.849522 -316.509149) (xy 40.958071 -316.467981)
			(xy 41.069202 -316.434401) (xy 41.182385 -316.408568) (xy 41.29708 -316.390605) (xy 41.412742 -316.380597)
			(xy 41.528818 -316.378594) (xy 41.644756 -316.384603) (xy 41.760003 -316.398596) (xy 41.874009 -316.420507)
			(xy 41.986233 -316.450232) (xy 42.096139 -316.487628) (xy 42.203202 -316.532517) (xy 42.306914 -316.584686)
			(xy 42.406779 -316.643886) (xy 42.502322 -316.709835) (xy 42.593088 -316.782218) (xy 42.678643 -316.860691)
			(xy 42.758581 -316.944879) (xy 42.83252 -317.034381) (xy 42.900108 -317.128772) (xy 42.961022 -317.2276)
			(xy 43.014974 -317.330396) (xy 43.061704 -317.436669) (xy 43.100992 -317.545913) (xy 43.132649 -317.657606)
			(xy 43.156525 -317.771218) (xy 43.172506 -317.886206) (xy 43.180515 -318.002023) (xy 43.181016 -318.06007)
			(xy 43.180515 -318.118117) (xy 43.172506 -318.233934) (xy 43.156525 -318.348922) (xy 43.132649 -318.462534)
			(xy 43.100992 -318.574227) (xy 43.061704 -318.683471) (xy 43.014974 -318.789744) (xy 42.961022 -318.89254)
			(xy 42.900108 -318.991368) (xy 42.83252 -319.085759) (xy 42.758581 -319.175261) (xy 42.678643 -319.259449)
			(xy 42.593088 -319.337922) (xy 42.502604 -319.41008) (xy 93.154506 -319.41008) (xy 93.158522 -319.29381)
			(xy 93.170549 -319.178095) (xy 93.190531 -319.063485) (xy 93.218373 -318.950526) (xy 93.253942 -318.839758)
			(xy 93.297068 -318.731707) (xy 93.347545 -318.626889) (xy 93.405134 -318.525804) (xy 93.46956 -318.428932)
			(xy 93.540515 -318.336736) (xy 93.617662 -318.249655) (xy 93.700633 -318.168104) (xy 93.789033 -318.092472)
			(xy 93.88244 -318.023118) (xy 93.980409 -317.960375) (xy 94.082473 -317.904539) (xy 94.188147 -317.855878)
			(xy 94.296926 -317.814624) (xy 94.408291 -317.780973) (xy 94.521714 -317.755085) (xy 94.636651 -317.737084)
			(xy 94.752557 -317.727055) (xy 94.868879 -317.725047) (xy 94.985062 -317.731069) (xy 95.100553 -317.745092)
			(xy 95.214801 -317.76705) (xy 95.327262 -317.796837) (xy 95.4374 -317.834312) (xy 95.54469 -317.879297)
			(xy 95.648621 -317.931576) (xy 95.748697 -317.990901) (xy 95.844443 -318.056989) (xy 95.9354 -318.129525)
			(xy 96.021136 -318.208164) (xy 96.101243 -318.29253) (xy 96.175339 -318.382222) (xy 96.243069 -318.476812)
			(xy 96.304113 -318.57585) (xy 96.358178 -318.678863) (xy 96.405008 -318.78536) (xy 96.444379 -318.894835)
			(xy 96.476103 -319.006765) (xy 96.500029 -319.120617) (xy 96.516043 -319.235849) (xy 96.52407 -319.351911)
			(xy 96.524572 -319.41008) (xy 96.52407 -319.468249) (xy 96.516043 -319.584311) (xy 96.500029 -319.699543)
			(xy 96.476103 -319.813395) (xy 96.444379 -319.925325) (xy 96.405008 -320.0348) (xy 96.358178 -320.141297)
			(xy 96.304113 -320.24431) (xy 96.243069 -320.343348) (xy 96.175339 -320.437938) (xy 96.101243 -320.52763)
			(xy 96.021136 -320.611996) (xy 95.9354 -320.690635) (xy 95.844443 -320.763171) (xy 95.748697 -320.829259)
			(xy 95.648621 -320.888584) (xy 95.54469 -320.940863) (xy 95.4374 -320.985848) (xy 95.327262 -321.023323)
			(xy 95.214801 -321.05311) (xy 95.100553 -321.075068) (xy 94.985062 -321.089091) (xy 94.868879 -321.095113)
			(xy 94.752557 -321.093105) (xy 94.636651 -321.083076) (xy 94.521714 -321.065075) (xy 94.408291 -321.039187)
			(xy 94.296926 -321.005536) (xy 94.188147 -320.964282) (xy 94.082473 -320.915621) (xy 93.980409 -320.859785)
			(xy 93.88244 -320.797042) (xy 93.789033 -320.727688) (xy 93.700633 -320.652056) (xy 93.617662 -320.570505)
			(xy 93.540515 -320.483424) (xy 93.46956 -320.391228) (xy 93.405134 -320.294356) (xy 93.347545 -320.193271)
			(xy 93.297068 -320.088453) (xy 93.253942 -319.980402) (xy 93.218373 -319.869634) (xy 93.190531 -319.756675)
			(xy 93.170549 -319.642065) (xy 93.158522 -319.52635) (xy 93.154506 -319.41008) (xy 42.502604 -319.41008)
			(xy 42.502322 -319.410305) (xy 42.406779 -319.476254) (xy 42.306914 -319.535454) (xy 42.203202 -319.587623)
			(xy 42.096139 -319.632512) (xy 41.986233 -319.669908) (xy 41.874009 -319.699633) (xy 41.760003 -319.721544)
			(xy 41.644756 -319.735537) (xy 41.528818 -319.741546) (xy 41.412742 -319.739543) (xy 41.29708 -319.729535)
			(xy 41.182385 -319.711572) (xy 41.069202 -319.685739) (xy 40.958071 -319.652159) (xy 40.849522 -319.610991)
			(xy 40.744072 -319.562433) (xy 40.642223 -319.506716) (xy 40.54446 -319.444104) (xy 40.45125 -319.374897)
			(xy 40.363037 -319.299424) (xy 40.280241 -319.218045) (xy 40.203257 -319.131148) (xy 40.132452 -319.039147)
			(xy 40.068162 -318.94248) (xy 40.010695 -318.841608) (xy 39.960324 -318.737011) (xy 39.917289 -318.629188)
			(xy 39.881795 -318.518654) (xy 39.854012 -318.405934) (xy 39.834072 -318.291566) (xy 39.82207 -318.176094)
			(xy 39.818063 -318.06007) (xy 0.509016 -318.06007) (xy 0.509016 -331.16012) (xy 86.877404 -331.16012)
			(xy 86.881424 -330.969469) (xy 86.893478 -330.779156) (xy 86.913544 -330.589521) (xy 86.941587 -330.4009)
			(xy 86.977556 -330.21363) (xy 87.021388 -330.028042) (xy 87.073005 -329.844467) (xy 87.132315 -329.663231)
			(xy 87.199213 -329.484656) (xy 87.273579 -329.309061) (xy 87.355281 -329.136756) (xy 87.444175 -328.968049)
			(xy 87.540101 -328.803239) (xy 87.64289 -328.64262) (xy 87.752359 -328.486477) (xy 87.868313 -328.335088)
			(xy 87.990547 -328.188721) (xy 88.118841 -328.047637) (xy 88.252969 -327.912088) (xy 88.392693 -327.782313)
			(xy 88.537763 -327.658543) (xy 88.687921 -327.541) (xy 88.842902 -327.429891) (xy 89.002429 -327.325414)
			(xy 89.166218 -327.227755) (xy 89.333978 -327.137088) (xy 89.505412 -327.053574) (xy 89.680214 -326.977361)
			(xy 89.858073 -326.908585) (xy 90.038674 -326.847367) (xy 90.221694 -326.793818) (xy 90.40681 -326.748032)
			(xy 90.593691 -326.71009) (xy 90.782006 -326.680061) (xy 90.971419 -326.657996) (xy 91.161593 -326.643937)
			(xy 91.352192 -326.637907) (xy 91.542875 -326.639917) (xy 91.733304 -326.649964) (xy 91.92314 -326.66803)
			(xy 92.112046 -326.694083) (xy 92.299685 -326.728076) (xy 92.485725 -326.769949) (xy 92.669834 -326.819628)
			(xy 92.851685 -326.877024) (xy 93.030955 -326.942035) (xy 93.207325 -327.014546) (xy 93.380481 -327.094427)
			(xy 93.550116 -327.181537) (xy 93.715928 -327.275721) (xy 93.877622 -327.376812) (xy 94.03491 -327.484628)
			(xy 94.187513 -327.59898) (xy 94.335161 -327.719663) (xy 94.477589 -327.846464) (xy 94.614545 -327.979155)
			(xy 94.745786 -328.117503) (xy 94.871078 -328.26126) (xy 94.990198 -328.410171) (xy 95.102934 -328.563972)
			(xy 95.209087 -328.722388) (xy 95.308467 -328.885139) (xy 95.400897 -329.051934) (xy 95.486214 -329.222478)
			(xy 95.564266 -329.396466) (xy 95.634913 -329.573591) (xy 95.698031 -329.753536) (xy 95.753507 -329.935982)
			(xy 95.801242 -330.120605) (xy 95.841152 -330.307075) (xy 95.873165 -330.495063) (xy 95.897225 -330.684233)
			(xy 95.913288 -330.874249) (xy 95.921327 -331.064773) (xy 95.92183 -331.16012) (xy 95.921327 -331.255467)
			(xy 95.913288 -331.445991) (xy 95.897225 -331.636007) (xy 95.873165 -331.825177) (xy 95.841152 -332.013165)
			(xy 95.801242 -332.199635) (xy 95.753507 -332.384258) (xy 95.698031 -332.566704) (xy 95.634913 -332.746649)
			(xy 95.564266 -332.923774) (xy 95.486214 -333.097762) (xy 95.400897 -333.268306) (xy 95.308467 -333.435101)
			(xy 95.209087 -333.597852) (xy 95.102934 -333.756268) (xy 94.990198 -333.910069) (xy 94.871078 -334.05898)
			(xy 94.745786 -334.202737) (xy 94.614545 -334.341085) (xy 94.477589 -334.473776) (xy 94.335161 -334.600577)
			(xy 94.187513 -334.72126) (xy 94.03491 -334.835612) (xy 93.877622 -334.943428) (xy 93.715928 -335.044519)
			(xy 93.550116 -335.138703) (xy 93.380481 -335.225813) (xy 93.207325 -335.305694) (xy 93.030955 -335.378205)
			(xy 92.851685 -335.443216) (xy 92.669834 -335.500612) (xy 92.485725 -335.550291) (xy 92.299685 -335.592164)
			(xy 92.112046 -335.626157) (xy 91.92314 -335.65221) (xy 91.733304 -335.670276) (xy 91.542875 -335.680323)
			(xy 91.352192 -335.682333) (xy 91.161593 -335.676303) (xy 90.971419 -335.662244) (xy 90.782006 -335.640179)
			(xy 90.593691 -335.61015) (xy 90.40681 -335.572208) (xy 90.221694 -335.526422) (xy 90.038674 -335.472873)
			(xy 89.858073 -335.411655) (xy 89.680214 -335.342879) (xy 89.505412 -335.266666) (xy 89.333978 -335.183152)
			(xy 89.166218 -335.092485) (xy 89.002429 -334.994826) (xy 88.842902 -334.890349) (xy 88.687921 -334.77924)
			(xy 88.537763 -334.661697) (xy 88.392693 -334.537927) (xy 88.252969 -334.408152) (xy 88.118841 -334.272603)
			(xy 87.990547 -334.131519) (xy 87.868313 -333.985152) (xy 87.752359 -333.833763) (xy 87.64289 -333.67762)
			(xy 87.540101 -333.517001) (xy 87.444175 -333.352191) (xy 87.355281 -333.183484) (xy 87.273579 -333.011179)
			(xy 87.199213 -332.835584) (xy 87.132315 -332.657009) (xy 87.073005 -332.475773) (xy 87.021388 -332.292198)
			(xy 86.977556 -332.10661) (xy 86.941587 -331.91934) (xy 86.913544 -331.730719) (xy 86.893478 -331.541084)
			(xy 86.881424 -331.350771) (xy 86.877404 -331.16012) (xy 0.509016 -331.16012) (xy 0.509016 -341.019892)
			(xy 3.583178 -341.019892) (xy 3.583678 -340.962646) (xy 3.59178 -340.848441) (xy 3.607943 -340.735095)
			(xy 3.632086 -340.623177) (xy 3.664086 -340.513247) (xy 3.703785 -340.405858) (xy 3.750982 -340.301546)
			(xy 3.805442 -340.200836) (xy 3.866891 -340.104231) (xy 3.935021 -340.012216) (xy 4.009491 -339.925252)
			(xy 4.089928 -339.843775) (xy 4.175928 -339.768194) (xy 4.26706 -339.698887) (xy 4.362867 -339.636202)
			(xy 4.46287 -339.580453) (xy 4.566566 -339.531919) (xy 4.673437 -339.490844) (xy 4.782946 -339.457434)
			(xy 4.894545 -339.431855) (xy 5.007674 -339.414237) (xy 5.121765 -339.404668) (xy 5.236248 -339.403195)
			(xy 5.350548 -339.409826) (xy 5.464093 -339.424528) (xy 5.576313 -339.447227) (xy 5.686645 -339.477809)
			(xy 5.794537 -339.516121) (xy 5.899448 -339.561971) (xy 6.000852 -339.615129) (xy 6.09824 -339.675328)
			(xy 6.191125 -339.742268) (xy 6.279041 -339.815611) (xy 6.361547 -339.894992) (xy 6.43823 -339.980011)
			(xy 6.508705 -340.070243) (xy 6.572619 -340.165235) (xy 6.629651 -340.264511) (xy 6.679516 -340.367574)
			(xy 6.721964 -340.473907) (xy 6.756783 -340.582977) (xy 6.783796 -340.694236) (xy 6.80287 -340.807129)
			(xy 6.813908 -340.921088) (xy 6.816855 -341.035542) (xy 6.811697 -341.149918) (xy 6.800045 -341.250016)
			(xy 75.486519 -341.250016) (xy 75.490544 -341.107824) (xy 75.502607 -340.966088) (xy 75.52267 -340.825262)
			(xy 75.550668 -340.685796) (xy 75.586512 -340.548137) (xy 75.630086 -340.412727) (xy 75.681251 -340.279999)
			(xy 75.739844 -340.150378) (xy 75.805675 -340.02428) (xy 75.878536 -339.902108) (xy 75.958191 -339.784254)
			(xy 76.044387 -339.671095) (xy 76.136846 -339.562993) (xy 76.235274 -339.460296) (xy 76.339353 -339.363332)
			(xy 76.448752 -339.272412) (xy 76.56312 -339.187826) (xy 76.682089 -339.109846) (xy 76.80528 -339.038722)
			(xy 76.932297 -338.974681) (xy 77.062734 -338.917929) (xy 77.196173 -338.868647) (xy 77.332186 -338.826993)
			(xy 77.470338 -338.793101) (xy 77.610187 -338.76708) (xy 77.751283 -338.749012) (xy 77.893175 -338.738955)
			(xy 78.03541 -338.736942) (xy 78.17753 -338.742979) (xy 78.319081 -338.757047) (xy 78.45961 -338.779101)
			(xy 78.598665 -338.80907) (xy 78.735803 -338.846858) (xy 78.870583 -338.892344) (xy 79.002574 -338.945382)
			(xy 79.131353 -339.005803) (xy 79.256507 -339.073412) (xy 79.377635 -339.147994) (xy 79.494351 -339.22931)
			(xy 79.606279 -339.317098) (xy 79.713061 -339.411078) (xy 79.814355 -339.510948) (xy 79.909836 -339.61639)
			(xy 79.9992 -339.727064) (xy 80.082158 -339.842617) (xy 80.158447 -339.962678) (xy 80.227821 -340.086863)
			(xy 80.290058 -340.214774) (xy 80.344959 -340.346001) (xy 80.392347 -340.480124) (xy 80.432072 -340.616713)
			(xy 80.464005 -340.755331) (xy 80.488046 -340.895533) (xy 80.504115 -341.036871) (xy 80.512163 -341.178892)
			(xy 80.512666 -341.250016) (xy 80.512163 -341.32114) (xy 80.504115 -341.463161) (xy 80.488046 -341.604499)
			(xy 80.464005 -341.744701) (xy 80.432072 -341.883319) (xy 80.392347 -342.019908) (xy 80.344959 -342.154031)
			(xy 80.290058 -342.285258) (xy 80.227821 -342.413169) (xy 80.158447 -342.537354) (xy 80.082158 -342.657415)
			(xy 79.9992 -342.772968) (xy 79.909836 -342.883642) (xy 79.814355 -342.989084) (xy 79.713061 -343.088954)
			(xy 79.606279 -343.182934) (xy 79.494351 -343.270722) (xy 79.377635 -343.352038) (xy 79.256507 -343.42662)
			(xy 79.131353 -343.494229) (xy 79.002574 -343.55465) (xy 78.870583 -343.607688) (xy 78.735803 -343.653174)
			(xy 78.598665 -343.690962) (xy 78.45961 -343.720931) (xy 78.319081 -343.742985) (xy 78.17753 -343.757053)
			(xy 78.03541 -343.76309) (xy 77.893175 -343.761077) (xy 77.751283 -343.75102) (xy 77.610187 -343.732952)
			(xy 77.470338 -343.706931) (xy 77.332186 -343.673039) (xy 77.196173 -343.631385) (xy 77.062734 -343.582103)
			(xy 76.932297 -343.525351) (xy 76.80528 -343.46131) (xy 76.682089 -343.390186) (xy 76.56312 -343.312206)
			(xy 76.448752 -343.22762) (xy 76.339353 -343.1367) (xy 76.235274 -343.039736) (xy 76.136846 -342.937039)
			(xy 76.044387 -342.828937) (xy 75.958191 -342.715778) (xy 75.878536 -342.597924) (xy 75.805675 -342.475752)
			(xy 75.739844 -342.349654) (xy 75.681251 -342.220033) (xy 75.630086 -342.087305) (xy 75.586512 -341.951895)
			(xy 75.550668 -341.814236) (xy 75.52267 -341.67477) (xy 75.502607 -341.533944) (xy 75.490544 -341.392208)
			(xy 75.486519 -341.250016) (xy 6.800045 -341.250016) (xy 6.798459 -341.263643) (xy 6.777208 -341.376146)
			(xy 6.748049 -341.486863) (xy 6.71113 -341.595239) (xy 6.666635 -341.700732) (xy 6.614788 -341.802812)
			(xy 6.555848 -341.900968) (xy 6.49011 -341.994707) (xy 6.454394 -342.039448) (xy 6.060186 -342.039448)
			(xy 6.021179 -342.071737) (xy 5.939048 -342.130983) (xy 5.896102 -342.157812) (xy 5.882524 -342.166761)
			(xy 5.860006 -342.190206) (xy 5.844123 -342.218568) (xy 5.8359 -342.250017) (xy 5.835396 -342.26627)
			(xy 5.835396 -342.5063) (xy 5.780703 -342.52911) (xy 5.668615 -342.567604) (xy 5.55401 -342.597788)
			(xy 5.437502 -342.619498) (xy 5.319718 -342.632619) (xy 5.201288 -342.63708) (xy 5.08285 -342.632856)
			(xy 4.96504 -342.619971) (xy 4.848489 -342.598494) (xy 4.733823 -342.56854) (xy 4.621659 -342.53027)
			(xy 4.56692 -342.50757) (xy 4.56692 -342.26754) (xy 4.566441 -342.251261) (xy 4.558186 -342.219766)
			(xy 4.542229 -342.191387) (xy 4.519608 -342.167969) (xy 4.50596 -342.159082) (xy 4.459776 -342.130343)
			(xy 4.371783 -342.066378) (xy 4.330192 -342.03132) (xy 3.938778 -342.03132) (xy 3.904941 -341.988409)
			(xy 3.842477 -341.898728) (xy 3.78621 -341.805035) (xy 3.736399 -341.707756) (xy 3.69327 -341.607335)
			(xy 3.657021 -341.504231) (xy 3.627816 -341.398915) (xy 3.60579 -341.291867) (xy 3.591042 -341.183577)
			(xy 3.583641 -341.074537) (xy 3.583178 -341.019892) (xy 0.509016 -341.019892) (xy 0.509016 -362.51007)
			(xy 39.818063 -362.51007) (xy 39.82207 -362.394046) (xy 39.834072 -362.278574) (xy 39.854012 -362.164206)
			(xy 39.881795 -362.051486) (xy 39.917289 -361.940952) (xy 39.960324 -361.833129) (xy 40.010695 -361.728532)
			(xy 40.068162 -361.62766) (xy 40.132452 -361.530993) (xy 40.203257 -361.438992) (xy 40.280241 -361.352095)
			(xy 40.363037 -361.270716) (xy 40.45125 -361.195243) (xy 40.54446 -361.126036) (xy 40.642223 -361.063424)
			(xy 40.744072 -361.007707) (xy 40.849522 -360.959149) (xy 40.958071 -360.917981) (xy 41.069202 -360.884401)
			(xy 41.182385 -360.858568) (xy 41.29708 -360.840605) (xy 41.412742 -360.830597) (xy 41.528818 -360.828594)
			(xy 41.644756 -360.834603) (xy 41.760003 -360.848596) (xy 41.874009 -360.870507) (xy 41.986233 -360.900232)
			(xy 42.096139 -360.937628) (xy 42.203202 -360.982517) (xy 42.306914 -361.034686) (xy 42.406779 -361.093886)
			(xy 42.502322 -361.159835) (xy 42.593088 -361.232218) (xy 42.678643 -361.310691) (xy 42.758581 -361.394879)
			(xy 42.83252 -361.484381) (xy 42.900108 -361.578772) (xy 42.961022 -361.6776) (xy 43.014974 -361.780396)
			(xy 43.061704 -361.886669) (xy 43.100992 -361.995913) (xy 43.132649 -362.107606) (xy 43.156525 -362.221218)
			(xy 43.172506 -362.336206) (xy 43.180515 -362.452023) (xy 43.181016 -362.51007) (xy 43.180515 -362.568117)
			(xy 43.172506 -362.683934) (xy 43.156525 -362.798922) (xy 43.132649 -362.912534) (xy 43.100992 -363.024227)
			(xy 43.061704 -363.133471) (xy 43.014974 -363.239744) (xy 42.961022 -363.34254) (xy 42.900108 -363.441368)
			(xy 42.83252 -363.535759) (xy 42.758581 -363.625261) (xy 42.678643 -363.709449) (xy 42.593088 -363.787922)
			(xy 42.502604 -363.86008) (xy 93.154506 -363.86008) (xy 93.158522 -363.74381) (xy 93.170549 -363.628095)
			(xy 93.190531 -363.513485) (xy 93.218373 -363.400526) (xy 93.253942 -363.289758) (xy 93.297068 -363.181707)
			(xy 93.347545 -363.076889) (xy 93.405134 -362.975804) (xy 93.46956 -362.878932) (xy 93.540515 -362.786736)
			(xy 93.617662 -362.699655) (xy 93.700633 -362.618104) (xy 93.789033 -362.542472) (xy 93.88244 -362.473118)
			(xy 93.980409 -362.410375) (xy 94.082473 -362.354539) (xy 94.188147 -362.305878) (xy 94.296926 -362.264624)
			(xy 94.408291 -362.230973) (xy 94.521714 -362.205085) (xy 94.636651 -362.187084) (xy 94.752557 -362.177055)
			(xy 94.868879 -362.175047) (xy 94.985062 -362.181069) (xy 95.100553 -362.195092) (xy 95.214801 -362.21705)
			(xy 95.327262 -362.246837) (xy 95.4374 -362.284312) (xy 95.54469 -362.329297) (xy 95.648621 -362.381576)
			(xy 95.748697 -362.440901) (xy 95.844443 -362.506989) (xy 95.9354 -362.579525) (xy 96.021136 -362.658164)
			(xy 96.101243 -362.74253) (xy 96.175339 -362.832222) (xy 96.243069 -362.926812) (xy 96.304113 -363.02585)
			(xy 96.358178 -363.128863) (xy 96.405008 -363.23536) (xy 96.444379 -363.344835) (xy 96.476103 -363.456765)
			(xy 96.500029 -363.570617) (xy 96.516043 -363.685849) (xy 96.52407 -363.801911) (xy 96.524572 -363.86008)
			(xy 96.52407 -363.918249) (xy 96.516043 -364.034311) (xy 96.500029 -364.149543) (xy 96.476103 -364.263395)
			(xy 96.444379 -364.375325) (xy 96.405008 -364.4848) (xy 96.358178 -364.591297) (xy 96.304113 -364.69431)
			(xy 96.243069 -364.793348) (xy 96.175339 -364.887938) (xy 96.101243 -364.97763) (xy 96.021136 -365.061996)
			(xy 95.9354 -365.140635) (xy 95.844443 -365.213171) (xy 95.748697 -365.279259) (xy 95.648621 -365.338584)
			(xy 95.54469 -365.390863) (xy 95.4374 -365.435848) (xy 95.327262 -365.473323) (xy 95.214801 -365.50311)
			(xy 95.100553 -365.525068) (xy 94.985062 -365.539091) (xy 94.868879 -365.545113) (xy 94.752557 -365.543105)
			(xy 94.636651 -365.533076) (xy 94.521714 -365.515075) (xy 94.408291 -365.489187) (xy 94.296926 -365.455536)
			(xy 94.188147 -365.414282) (xy 94.082473 -365.365621) (xy 93.980409 -365.309785) (xy 93.88244 -365.247042)
			(xy 93.789033 -365.177688) (xy 93.700633 -365.102056) (xy 93.617662 -365.020505) (xy 93.540515 -364.933424)
			(xy 93.46956 -364.841228) (xy 93.405134 -364.744356) (xy 93.347545 -364.643271) (xy 93.297068 -364.538453)
			(xy 93.253942 -364.430402) (xy 93.218373 -364.319634) (xy 93.190531 -364.206675) (xy 93.170549 -364.092065)
			(xy 93.158522 -363.97635) (xy 93.154506 -363.86008) (xy 42.502604 -363.86008) (xy 42.502322 -363.860305)
			(xy 42.406779 -363.926254) (xy 42.306914 -363.985454) (xy 42.203202 -364.037623) (xy 42.096139 -364.082512)
			(xy 41.986233 -364.119908) (xy 41.874009 -364.149633) (xy 41.760003 -364.171544) (xy 41.644756 -364.185537)
			(xy 41.528818 -364.191546) (xy 41.412742 -364.189543) (xy 41.29708 -364.179535) (xy 41.182385 -364.161572)
			(xy 41.069202 -364.135739) (xy 40.958071 -364.102159) (xy 40.849522 -364.060991) (xy 40.744072 -364.012433)
			(xy 40.642223 -363.956716) (xy 40.54446 -363.894104) (xy 40.45125 -363.824897) (xy 40.363037 -363.749424)
			(xy 40.280241 -363.668045) (xy 40.203257 -363.581148) (xy 40.132452 -363.489147) (xy 40.068162 -363.39248)
			(xy 40.010695 -363.291608) (xy 39.960324 -363.187011) (xy 39.917289 -363.079188) (xy 39.881795 -362.968654)
			(xy 39.854012 -362.855934) (xy 39.834072 -362.741566) (xy 39.82207 -362.626094) (xy 39.818063 -362.51007)
			(xy 0.509016 -362.51007) (xy 0.509016 -375.61012) (xy 86.877404 -375.61012) (xy 86.881424 -375.419469)
			(xy 86.893478 -375.229156) (xy 86.913544 -375.039521) (xy 86.941587 -374.8509) (xy 86.977556 -374.66363)
			(xy 87.021388 -374.478042) (xy 87.073005 -374.294467) (xy 87.132315 -374.113231) (xy 87.199213 -373.934656)
			(xy 87.273579 -373.759061) (xy 87.355281 -373.586756) (xy 87.444175 -373.418049) (xy 87.540101 -373.253239)
			(xy 87.64289 -373.09262) (xy 87.752359 -372.936477) (xy 87.868313 -372.785088) (xy 87.990547 -372.638721)
			(xy 88.118841 -372.497637) (xy 88.252969 -372.362088) (xy 88.392693 -372.232313) (xy 88.537763 -372.108543)
			(xy 88.687921 -371.991) (xy 88.842902 -371.879891) (xy 89.002429 -371.775414) (xy 89.166218 -371.677755)
			(xy 89.333978 -371.587088) (xy 89.505412 -371.503574) (xy 89.680214 -371.427361) (xy 89.858073 -371.358585)
			(xy 90.038674 -371.297367) (xy 90.221694 -371.243818) (xy 90.40681 -371.198032) (xy 90.593691 -371.16009)
			(xy 90.782006 -371.130061) (xy 90.971419 -371.107996) (xy 91.161593 -371.093937) (xy 91.352192 -371.087907)
			(xy 91.542875 -371.089917) (xy 91.733304 -371.099964) (xy 91.92314 -371.11803) (xy 92.112046 -371.144083)
			(xy 92.299685 -371.178076) (xy 92.485725 -371.219949) (xy 92.669834 -371.269628) (xy 92.851685 -371.327024)
			(xy 93.030955 -371.392035) (xy 93.207325 -371.464546) (xy 93.380481 -371.544427) (xy 93.550116 -371.631537)
			(xy 93.715928 -371.725721) (xy 93.877622 -371.826812) (xy 94.03491 -371.934628) (xy 94.187513 -372.04898)
			(xy 94.335161 -372.169663) (xy 94.477589 -372.296464) (xy 94.614545 -372.429155) (xy 94.745786 -372.567503)
			(xy 94.871078 -372.71126) (xy 94.990198 -372.860171) (xy 95.102934 -373.013972) (xy 95.209087 -373.172388)
			(xy 95.308467 -373.335139) (xy 95.400897 -373.501934) (xy 95.486214 -373.672478) (xy 95.564266 -373.846466)
			(xy 95.634913 -374.023591) (xy 95.698031 -374.203536) (xy 95.753507 -374.385982) (xy 95.801242 -374.570605)
			(xy 95.841152 -374.757075) (xy 95.873165 -374.945063) (xy 95.897225 -375.134233) (xy 95.913288 -375.324249)
			(xy 95.921327 -375.514773) (xy 95.92183 -375.61012) (xy 95.921327 -375.705467) (xy 95.913288 -375.895991)
			(xy 95.897225 -376.086007) (xy 95.873165 -376.275177) (xy 95.841152 -376.463165) (xy 95.801242 -376.649635)
			(xy 95.753507 -376.834258) (xy 95.698031 -377.016704) (xy 95.634913 -377.196649) (xy 95.564266 -377.373774)
			(xy 95.486214 -377.547762) (xy 95.400897 -377.718306) (xy 95.308467 -377.885101) (xy 95.209087 -378.047852)
			(xy 95.102934 -378.206268) (xy 94.990198 -378.360069) (xy 94.871078 -378.50898) (xy 94.745786 -378.652737)
			(xy 94.614545 -378.791085) (xy 94.477589 -378.923776) (xy 94.335161 -379.050577) (xy 94.187513 -379.17126)
			(xy 94.03491 -379.285612) (xy 93.877622 -379.393428) (xy 93.715928 -379.494519) (xy 93.550116 -379.588703)
			(xy 93.380481 -379.675813) (xy 93.207325 -379.755694) (xy 93.030955 -379.828205) (xy 92.851685 -379.893216)
			(xy 92.669834 -379.950612) (xy 92.485725 -380.000291) (xy 92.299685 -380.042164) (xy 92.112046 -380.076157)
			(xy 91.92314 -380.10221) (xy 91.733304 -380.120276) (xy 91.542875 -380.130323) (xy 91.352192 -380.132333)
			(xy 91.161593 -380.126303) (xy 90.971419 -380.112244) (xy 90.782006 -380.090179) (xy 90.593691 -380.06015)
			(xy 90.40681 -380.022208) (xy 90.221694 -379.976422) (xy 90.038674 -379.922873) (xy 89.858073 -379.861655)
			(xy 89.680214 -379.792879) (xy 89.505412 -379.716666) (xy 89.333978 -379.633152) (xy 89.166218 -379.542485)
			(xy 89.002429 -379.444826) (xy 88.842902 -379.340349) (xy 88.687921 -379.22924) (xy 88.537763 -379.111697)
			(xy 88.392693 -378.987927) (xy 88.252969 -378.858152) (xy 88.118841 -378.722603) (xy 87.990547 -378.581519)
			(xy 87.868313 -378.435152) (xy 87.752359 -378.283763) (xy 87.64289 -378.12762) (xy 87.540101 -377.967001)
			(xy 87.444175 -377.802191) (xy 87.355281 -377.633484) (xy 87.273579 -377.461179) (xy 87.199213 -377.285584)
			(xy 87.132315 -377.107009) (xy 87.073005 -376.925773) (xy 87.021388 -376.742198) (xy 86.977556 -376.55661)
			(xy 86.941587 -376.36934) (xy 86.913544 -376.180719) (xy 86.893478 -375.991084) (xy 86.881424 -375.800771)
			(xy 86.877404 -375.61012) (xy 0.509016 -375.61012) (xy 0.509016 -384.79984) (xy 14.086591 -384.79984)
			(xy 14.090616 -384.657648) (xy 14.102679 -384.515912) (xy 14.122742 -384.375086) (xy 14.15074 -384.23562)
			(xy 14.186584 -384.097961) (xy 14.230158 -383.962551) (xy 14.281323 -383.829823) (xy 14.339916 -383.700202)
			(xy 14.405747 -383.574104) (xy 14.478608 -383.451932) (xy 14.558263 -383.334078) (xy 14.644459 -383.220919)
			(xy 14.736918 -383.112817) (xy 14.835346 -383.01012) (xy 14.939425 -382.913156) (xy 15.048824 -382.822236)
			(xy 15.163192 -382.73765) (xy 15.282161 -382.65967) (xy 15.405352 -382.588546) (xy 15.532369 -382.524505)
			(xy 15.662806 -382.467753) (xy 15.796245 -382.418471) (xy 15.932258 -382.376817) (xy 16.07041 -382.342925)
			(xy 16.210259 -382.316904) (xy 16.351355 -382.298836) (xy 16.493247 -382.288779) (xy 16.635482 -382.286766)
			(xy 16.777602 -382.292803) (xy 16.919153 -382.306871) (xy 17.059682 -382.328925) (xy 17.198737 -382.358894)
			(xy 17.335875 -382.396682) (xy 17.470655 -382.442168) (xy 17.602646 -382.495206) (xy 17.731425 -382.555627)
			(xy 17.856579 -382.623236) (xy 17.977707 -382.697818) (xy 18.094423 -382.779134) (xy 18.206351 -382.866922)
			(xy 18.313133 -382.960902) (xy 18.414427 -383.060772) (xy 18.509908 -383.166214) (xy 18.599272 -383.276888)
			(xy 18.68223 -383.392441) (xy 18.758519 -383.512502) (xy 18.827893 -383.636687) (xy 18.89013 -383.764598)
			(xy 18.945031 -383.895825) (xy 18.992419 -384.029948) (xy 19.032144 -384.166537) (xy 19.064077 -384.305155)
			(xy 19.088118 -384.445357) (xy 19.104187 -384.586695) (xy 19.112235 -384.728716) (xy 19.112738 -384.79984)
			(xy 19.112235 -384.870964) (xy 19.104187 -385.012985) (xy 19.088118 -385.154323) (xy 19.064077 -385.294525)
			(xy 19.032144 -385.433143) (xy 18.992419 -385.569732) (xy 18.945031 -385.703855) (xy 18.89013 -385.835082)
			(xy 18.827893 -385.962993) (xy 18.758519 -386.087178) (xy 18.68223 -386.207239) (xy 18.599272 -386.322792)
			(xy 18.509908 -386.433466) (xy 18.414427 -386.538908) (xy 18.313133 -386.638778) (xy 18.206351 -386.732758)
			(xy 18.094423 -386.820546) (xy 17.977707 -386.901862) (xy 17.856579 -386.976444) (xy 17.731425 -387.044053)
			(xy 17.602646 -387.104474) (xy 17.470655 -387.157512) (xy 17.335875 -387.202998) (xy 17.198737 -387.240786)
			(xy 17.059682 -387.270755) (xy 16.919153 -387.292809) (xy 16.777602 -387.306877) (xy 16.635482 -387.312914)
			(xy 16.493247 -387.310901) (xy 16.351355 -387.300844) (xy 16.210259 -387.282776) (xy 16.07041 -387.256755)
			(xy 15.932258 -387.222863) (xy 15.796245 -387.181209) (xy 15.662806 -387.131927) (xy 15.532369 -387.075175)
			(xy 15.405352 -387.011134) (xy 15.282161 -386.94001) (xy 15.163192 -386.86203) (xy 15.048824 -386.777444)
			(xy 14.939425 -386.686524) (xy 14.835346 -386.58956) (xy 14.736918 -386.486863) (xy 14.644459 -386.378761)
			(xy 14.558263 -386.265602) (xy 14.478608 -386.147748) (xy 14.405747 -386.025576) (xy 14.339916 -385.899478)
			(xy 14.281323 -385.769857) (xy 14.230158 -385.637129) (xy 14.186584 -385.501719) (xy 14.15074 -385.36406)
			(xy 14.122742 -385.224594) (xy 14.102679 -385.083768) (xy 14.090616 -384.942032) (xy 14.086591 -384.79984)
			(xy 0.509016 -384.79984) (xy 0.509016 -403.413036) (xy 1.547863 -403.413036) (xy 1.547863 -403.2869)
			(xy 1.555783 -403.161012) (xy 1.571593 -403.03587) (xy 1.595228 -402.911967) (xy 1.626597 -402.789794)
			(xy 1.665575 -402.669831) (xy 1.712009 -402.552552) (xy 1.765716 -402.43842) (xy 1.826483 -402.327885)
			(xy 1.89407 -402.221385) (xy 1.968211 -402.119338) (xy 2.048614 -402.022148) (xy 2.13496 -401.930198)
			(xy 2.22691 -401.843852) (xy 2.3241 -401.763449) (xy 2.426147 -401.689308) (xy 2.532647 -401.621721)
			(xy 2.643182 -401.560954) (xy 2.757314 -401.507247) (xy 2.874593 -401.460813) (xy 2.994556 -401.421835)
			(xy 3.116729 -401.390466) (xy 3.240632 -401.366831) (xy 3.365774 -401.351021) (xy 3.491662 -401.343101)
			(xy 3.617798 -401.343101) (xy 3.743686 -401.351021) (xy 3.868828 -401.366831) (xy 3.992731 -401.390466)
			(xy 4.114904 -401.421835) (xy 4.234867 -401.460813) (xy 4.352146 -401.507247) (xy 4.466278 -401.560954)
			(xy 4.576813 -401.621721) (xy 4.683313 -401.689308) (xy 4.78536 -401.763449) (xy 4.88255 -401.843852)
			(xy 4.9745 -401.930198) (xy 5.060846 -402.022148) (xy 5.141249 -402.119338) (xy 5.21539 -402.221385)
			(xy 5.282977 -402.327885) (xy 5.343744 -402.43842) (xy 5.397451 -402.552552) (xy 5.443885 -402.669831)
			(xy 5.482863 -402.789794) (xy 5.514232 -402.911967) (xy 5.537867 -403.03587) (xy 5.553677 -403.161012)
			(xy 5.561597 -403.2869) (xy 5.562092 -403.349968) (xy 5.561597 -403.413036) (xy 12.977863 -403.413036)
			(xy 12.977863 -403.2869) (xy 12.985783 -403.161012) (xy 13.001593 -403.03587) (xy 13.025228 -402.911967)
			(xy 13.056597 -402.789794) (xy 13.095575 -402.669831) (xy 13.142009 -402.552552) (xy 13.195716 -402.43842)
			(xy 13.256483 -402.327885) (xy 13.32407 -402.221385) (xy 13.398211 -402.119338) (xy 13.478614 -402.022148)
			(xy 13.56496 -401.930198) (xy 13.65691 -401.843852) (xy 13.7541 -401.763449) (xy 13.856147 -401.689308)
			(xy 13.962647 -401.621721) (xy 14.073182 -401.560954) (xy 14.187314 -401.507247) (xy 14.304593 -401.460813)
			(xy 14.424556 -401.421835) (xy 14.546729 -401.390466) (xy 14.670632 -401.366831) (xy 14.795774 -401.351021)
			(xy 14.921662 -401.343101) (xy 15.047798 -401.343101) (xy 15.173686 -401.351021) (xy 15.298828 -401.366831)
			(xy 15.422731 -401.390466) (xy 15.544904 -401.421835) (xy 15.664867 -401.460813) (xy 15.782146 -401.507247)
			(xy 15.896278 -401.560954) (xy 16.006813 -401.621721) (xy 16.113313 -401.689308) (xy 16.21536 -401.763449)
			(xy 16.31255 -401.843852) (xy 16.4045 -401.930198) (xy 16.490846 -402.022148) (xy 16.571249 -402.119338)
			(xy 16.64539 -402.221385) (xy 16.712977 -402.327885) (xy 16.773744 -402.43842) (xy 16.827451 -402.552552)
			(xy 16.873885 -402.669831) (xy 16.912863 -402.789794) (xy 16.944232 -402.911967) (xy 16.967867 -403.03587)
			(xy 16.983677 -403.161012) (xy 16.991597 -403.2869) (xy 16.992092 -403.349968) (xy 16.991597 -403.413036)
			(xy 16.983677 -403.538924) (xy 16.967867 -403.664066) (xy 16.944232 -403.787969) (xy 16.912863 -403.910142)
			(xy 16.873885 -404.030105) (xy 16.827451 -404.147384) (xy 16.773744 -404.261516) (xy 16.712977 -404.372051)
			(xy 16.64539 -404.478551) (xy 16.571249 -404.580598) (xy 16.490846 -404.677788) (xy 16.4045 -404.769738)
			(xy 16.31255 -404.856084) (xy 16.21536 -404.936487) (xy 16.113313 -405.010628) (xy 16.006813 -405.078215)
			(xy 15.896278 -405.138982) (xy 15.782146 -405.192689) (xy 15.664867 -405.239123) (xy 15.544904 -405.278101)
			(xy 15.422731 -405.30947) (xy 15.298828 -405.333105) (xy 15.173686 -405.348915) (xy 15.047798 -405.356835)
			(xy 14.921662 -405.356835) (xy 14.795774 -405.348915) (xy 14.670632 -405.333105) (xy 14.546729 -405.30947)
			(xy 14.424556 -405.278101) (xy 14.304593 -405.239123) (xy 14.187314 -405.192689) (xy 14.073182 -405.138982)
			(xy 13.962647 -405.078215) (xy 13.856147 -405.010628) (xy 13.7541 -404.936487) (xy 13.65691 -404.856084)
			(xy 13.56496 -404.769738) (xy 13.478614 -404.677788) (xy 13.398211 -404.580598) (xy 13.32407 -404.478551)
			(xy 13.256483 -404.372051) (xy 13.195716 -404.261516) (xy 13.142009 -404.147384) (xy 13.095575 -404.030105)
			(xy 13.056597 -403.910142) (xy 13.025228 -403.787969) (xy 13.001593 -403.664066) (xy 12.985783 -403.538924)
			(xy 12.977863 -403.413036) (xy 5.561597 -403.413036) (xy 5.553677 -403.538924) (xy 5.537867 -403.664066)
			(xy 5.514232 -403.787969) (xy 5.482863 -403.910142) (xy 5.443885 -404.030105) (xy 5.397451 -404.147384)
			(xy 5.343744 -404.261516) (xy 5.282977 -404.372051) (xy 5.21539 -404.478551) (xy 5.141249 -404.580598)
			(xy 5.060846 -404.677788) (xy 4.9745 -404.769738) (xy 4.88255 -404.856084) (xy 4.78536 -404.936487)
			(xy 4.683313 -405.010628) (xy 4.576813 -405.078215) (xy 4.466278 -405.138982) (xy 4.352146 -405.192689)
			(xy 4.234867 -405.239123) (xy 4.114904 -405.278101) (xy 3.992731 -405.30947) (xy 3.868828 -405.333105)
			(xy 3.743686 -405.348915) (xy 3.617798 -405.356835) (xy 3.491662 -405.356835) (xy 3.365774 -405.348915)
			(xy 3.240632 -405.333105) (xy 3.116729 -405.30947) (xy 2.994556 -405.278101) (xy 2.874593 -405.239123)
			(xy 2.757314 -405.192689) (xy 2.643182 -405.138982) (xy 2.532647 -405.078215) (xy 2.426147 -405.010628)
			(xy 2.3241 -404.936487) (xy 2.22691 -404.856084) (xy 2.13496 -404.769738) (xy 2.048614 -404.677788)
			(xy 1.968211 -404.580598) (xy 1.89407 -404.478551) (xy 1.826483 -404.372051) (xy 1.765716 -404.261516)
			(xy 1.712009 -404.147384) (xy 1.665575 -404.030105) (xy 1.626597 -403.910142) (xy 1.595228 -403.787969)
			(xy 1.571593 -403.664066) (xy 1.555783 -403.538924) (xy 1.547863 -403.413036) (xy 0.509016 -403.413036)
			(xy 0.509016 -406.96007) (xy 39.818063 -406.96007) (xy 39.82207 -406.844046) (xy 39.834072 -406.728574)
			(xy 39.854012 -406.614206) (xy 39.881795 -406.501486) (xy 39.917289 -406.390952) (xy 39.960324 -406.283129)
			(xy 40.010695 -406.178532) (xy 40.068162 -406.07766) (xy 40.132452 -405.980993) (xy 40.203257 -405.888992)
			(xy 40.280241 -405.802095) (xy 40.363037 -405.720716) (xy 40.45125 -405.645243) (xy 40.54446 -405.576036)
			(xy 40.642223 -405.513424) (xy 40.744072 -405.457707) (xy 40.849522 -405.409149) (xy 40.958071 -405.367981)
			(xy 41.069202 -405.334401) (xy 41.182385 -405.308568) (xy 41.29708 -405.290605) (xy 41.412742 -405.280597)
			(xy 41.528818 -405.278594) (xy 41.644756 -405.284603) (xy 41.760003 -405.298596) (xy 41.874009 -405.320507)
			(xy 41.986233 -405.350232) (xy 42.096139 -405.387628) (xy 42.203202 -405.432517) (xy 42.306914 -405.484686)
			(xy 42.406779 -405.543886) (xy 42.502322 -405.609835) (xy 42.593088 -405.682218) (xy 42.678643 -405.760691)
			(xy 42.758581 -405.844879) (xy 42.83252 -405.934381) (xy 42.900108 -406.028772) (xy 42.961022 -406.1276)
			(xy 43.014974 -406.230396) (xy 43.061704 -406.336669) (xy 43.100992 -406.445913) (xy 43.132649 -406.557606)
			(xy 43.156525 -406.671218) (xy 43.172506 -406.786206) (xy 43.180515 -406.902023) (xy 43.181016 -406.96007)
			(xy 43.180515 -407.018117) (xy 43.172506 -407.133934) (xy 43.156525 -407.248922) (xy 43.132649 -407.362534)
			(xy 43.100992 -407.474227) (xy 43.061704 -407.583471) (xy 43.014974 -407.689744) (xy 42.961022 -407.79254)
			(xy 42.900108 -407.891368) (xy 42.83252 -407.985759) (xy 42.758581 -408.075261) (xy 42.678643 -408.159449)
			(xy 42.593088 -408.237922) (xy 42.502604 -408.31008) (xy 93.154506 -408.31008) (xy 93.158522 -408.19381)
			(xy 93.170549 -408.078095) (xy 93.190531 -407.963485) (xy 93.218373 -407.850526) (xy 93.253942 -407.739758)
			(xy 93.297068 -407.631707) (xy 93.347545 -407.526889) (xy 93.405134 -407.425804) (xy 93.46956 -407.328932)
			(xy 93.540515 -407.236736) (xy 93.617662 -407.149655) (xy 93.700633 -407.068104) (xy 93.789033 -406.992472)
			(xy 93.88244 -406.923118) (xy 93.980409 -406.860375) (xy 94.082473 -406.804539) (xy 94.188147 -406.755878)
			(xy 94.296926 -406.714624) (xy 94.408291 -406.680973) (xy 94.521714 -406.655085) (xy 94.636651 -406.637084)
			(xy 94.752557 -406.627055) (xy 94.868879 -406.625047) (xy 94.985062 -406.631069) (xy 95.100553 -406.645092)
			(xy 95.214801 -406.66705) (xy 95.327262 -406.696837) (xy 95.4374 -406.734312) (xy 95.54469 -406.779297)
			(xy 95.648621 -406.831576) (xy 95.748697 -406.890901) (xy 95.844443 -406.956989) (xy 95.9354 -407.029525)
			(xy 96.021136 -407.108164) (xy 96.101243 -407.19253) (xy 96.175339 -407.282222) (xy 96.243069 -407.376812)
			(xy 96.304113 -407.47585) (xy 96.358178 -407.578863) (xy 96.405008 -407.68536) (xy 96.444379 -407.794835)
			(xy 96.476103 -407.906765) (xy 96.500029 -408.020617) (xy 96.516043 -408.135849) (xy 96.52407 -408.251911)
			(xy 96.524572 -408.31008) (xy 96.52407 -408.368249) (xy 96.516043 -408.484311) (xy 96.500029 -408.599543)
			(xy 96.476103 -408.713395) (xy 96.444379 -408.825325) (xy 96.405008 -408.9348) (xy 96.358178 -409.041297)
			(xy 96.304113 -409.14431) (xy 96.243069 -409.243348) (xy 96.175339 -409.337938) (xy 96.101243 -409.42763)
			(xy 96.021136 -409.511996) (xy 95.9354 -409.590635) (xy 95.844443 -409.663171) (xy 95.748697 -409.729259)
			(xy 95.648621 -409.788584) (xy 95.54469 -409.840863) (xy 95.4374 -409.885848) (xy 95.327262 -409.923323)
			(xy 95.214801 -409.95311) (xy 95.100553 -409.975068) (xy 94.985062 -409.989091) (xy 94.868879 -409.995113)
			(xy 94.752557 -409.993105) (xy 94.636651 -409.983076) (xy 94.521714 -409.965075) (xy 94.408291 -409.939187)
			(xy 94.296926 -409.905536) (xy 94.188147 -409.864282) (xy 94.082473 -409.815621) (xy 93.980409 -409.759785)
			(xy 93.88244 -409.697042) (xy 93.789033 -409.627688) (xy 93.700633 -409.552056) (xy 93.617662 -409.470505)
			(xy 93.540515 -409.383424) (xy 93.46956 -409.291228) (xy 93.405134 -409.194356) (xy 93.347545 -409.093271)
			(xy 93.297068 -408.988453) (xy 93.253942 -408.880402) (xy 93.218373 -408.769634) (xy 93.190531 -408.656675)
			(xy 93.170549 -408.542065) (xy 93.158522 -408.42635) (xy 93.154506 -408.31008) (xy 42.502604 -408.31008)
			(xy 42.502322 -408.310305) (xy 42.406779 -408.376254) (xy 42.306914 -408.435454) (xy 42.203202 -408.487623)
			(xy 42.096139 -408.532512) (xy 41.986233 -408.569908) (xy 41.874009 -408.599633) (xy 41.760003 -408.621544)
			(xy 41.644756 -408.635537) (xy 41.528818 -408.641546) (xy 41.412742 -408.639543) (xy 41.29708 -408.629535)
			(xy 41.182385 -408.611572) (xy 41.069202 -408.585739) (xy 40.958071 -408.552159) (xy 40.849522 -408.510991)
			(xy 40.744072 -408.462433) (xy 40.642223 -408.406716) (xy 40.54446 -408.344104) (xy 40.45125 -408.274897)
			(xy 40.363037 -408.199424) (xy 40.280241 -408.118045) (xy 40.203257 -408.031148) (xy 40.132452 -407.939147)
			(xy 40.068162 -407.84248) (xy 40.010695 -407.741608) (xy 39.960324 -407.637011) (xy 39.917289 -407.529188)
			(xy 39.881795 -407.418654) (xy 39.854012 -407.305934) (xy 39.834072 -407.191566) (xy 39.82207 -407.076094)
			(xy 39.818063 -406.96007) (xy 0.509016 -406.96007) (xy 0.509016 -420.06012) (xy 86.877404 -420.06012)
			(xy 86.881424 -419.869469) (xy 86.893478 -419.679156) (xy 86.913544 -419.489521) (xy 86.941587 -419.3009)
			(xy 86.977556 -419.11363) (xy 87.021388 -418.928042) (xy 87.073005 -418.744467) (xy 87.132315 -418.563231)
			(xy 87.199213 -418.384656) (xy 87.273579 -418.209061) (xy 87.355281 -418.036756) (xy 87.444175 -417.868049)
			(xy 87.540101 -417.703239) (xy 87.64289 -417.54262) (xy 87.752359 -417.386477) (xy 87.868313 -417.235088)
			(xy 87.990547 -417.088721) (xy 88.118841 -416.947637) (xy 88.252969 -416.812088) (xy 88.392693 -416.682313)
			(xy 88.537763 -416.558543) (xy 88.687921 -416.441) (xy 88.842902 -416.329891) (xy 89.002429 -416.225414)
			(xy 89.166218 -416.127755) (xy 89.333978 -416.037088) (xy 89.505412 -415.953574) (xy 89.680214 -415.877361)
			(xy 89.858073 -415.808585) (xy 90.038674 -415.747367) (xy 90.221694 -415.693818) (xy 90.40681 -415.648032)
			(xy 90.593691 -415.61009) (xy 90.782006 -415.580061) (xy 90.971419 -415.557996) (xy 91.161593 -415.543937)
			(xy 91.352192 -415.537907) (xy 91.542875 -415.539917) (xy 91.733304 -415.549964) (xy 91.92314 -415.56803)
			(xy 92.112046 -415.594083) (xy 92.299685 -415.628076) (xy 92.485725 -415.669949) (xy 92.669834 -415.719628)
			(xy 92.851685 -415.777024) (xy 93.030955 -415.842035) (xy 93.207325 -415.914546) (xy 93.380481 -415.994427)
			(xy 93.550116 -416.081537) (xy 93.715928 -416.175721) (xy 93.877622 -416.276812) (xy 94.03491 -416.384628)
			(xy 94.187513 -416.49898) (xy 94.335161 -416.619663) (xy 94.477589 -416.746464) (xy 94.614545 -416.879155)
			(xy 94.745786 -417.017503) (xy 94.871078 -417.16126) (xy 94.990198 -417.310171) (xy 95.102934 -417.463972)
			(xy 95.209087 -417.622388) (xy 95.308467 -417.785139) (xy 95.400897 -417.951934) (xy 95.486214 -418.122478)
			(xy 95.564266 -418.296466) (xy 95.634913 -418.473591) (xy 95.698031 -418.653536) (xy 95.753507 -418.835982)
			(xy 95.801242 -419.020605) (xy 95.841152 -419.207075) (xy 95.873165 -419.395063) (xy 95.897225 -419.584233)
			(xy 95.913288 -419.774249) (xy 95.921327 -419.964773) (xy 95.92183 -420.06012) (xy 95.921327 -420.155467)
			(xy 95.913288 -420.345991) (xy 95.897225 -420.536007) (xy 95.873165 -420.725177) (xy 95.841152 -420.913165)
			(xy 95.801242 -421.099635) (xy 95.753507 -421.284258) (xy 95.698031 -421.466704) (xy 95.634913 -421.646649)
			(xy 95.564266 -421.823774) (xy 95.486214 -421.997762) (xy 95.400897 -422.168306) (xy 95.308467 -422.335101)
			(xy 95.209087 -422.497852) (xy 95.102934 -422.656268) (xy 94.990198 -422.810069) (xy 94.871078 -422.95898)
			(xy 94.745786 -423.102737) (xy 94.614545 -423.241085) (xy 94.477589 -423.373776) (xy 94.335161 -423.500577)
			(xy 94.187513 -423.62126) (xy 94.03491 -423.735612) (xy 93.877622 -423.843428) (xy 93.715928 -423.944519)
			(xy 93.550116 -424.038703) (xy 93.380481 -424.125813) (xy 93.207325 -424.205694) (xy 93.030955 -424.278205)
			(xy 92.851685 -424.343216) (xy 92.669834 -424.400612) (xy 92.485725 -424.450291) (xy 92.299685 -424.492164)
			(xy 92.112046 -424.526157) (xy 91.92314 -424.55221) (xy 91.733304 -424.570276) (xy 91.542875 -424.580323)
			(xy 91.352192 -424.582333) (xy 91.161593 -424.576303) (xy 90.971419 -424.562244) (xy 90.782006 -424.540179)
			(xy 90.593691 -424.51015) (xy 90.40681 -424.472208) (xy 90.221694 -424.426422) (xy 90.038674 -424.372873)
			(xy 89.858073 -424.311655) (xy 89.680214 -424.242879) (xy 89.505412 -424.166666) (xy 89.333978 -424.083152)
			(xy 89.166218 -423.992485) (xy 89.002429 -423.894826) (xy 88.842902 -423.790349) (xy 88.687921 -423.67924)
			(xy 88.537763 -423.561697) (xy 88.392693 -423.437927) (xy 88.252969 -423.308152) (xy 88.118841 -423.172603)
			(xy 87.990547 -423.031519) (xy 87.868313 -422.885152) (xy 87.752359 -422.733763) (xy 87.64289 -422.57762)
			(xy 87.540101 -422.417001) (xy 87.444175 -422.252191) (xy 87.355281 -422.083484) (xy 87.273579 -421.911179)
			(xy 87.199213 -421.735584) (xy 87.132315 -421.557009) (xy 87.073005 -421.375773) (xy 87.021388 -421.192198)
			(xy 86.977556 -421.00661) (xy 86.941587 -420.81934) (xy 86.913544 -420.630719) (xy 86.893478 -420.441084)
			(xy 86.881424 -420.250771) (xy 86.877404 -420.06012) (xy 0.509016 -420.06012) (xy 0.509016 -430.150016)
			(xy 75.486519 -430.150016) (xy 75.490544 -430.007824) (xy 75.502607 -429.866088) (xy 75.52267 -429.725262)
			(xy 75.550668 -429.585796) (xy 75.586512 -429.448137) (xy 75.630086 -429.312727) (xy 75.681251 -429.179999)
			(xy 75.739844 -429.050378) (xy 75.805675 -428.92428) (xy 75.878536 -428.802108) (xy 75.958191 -428.684254)
			(xy 76.044387 -428.571095) (xy 76.136846 -428.462993) (xy 76.235274 -428.360296) (xy 76.339353 -428.263332)
			(xy 76.448752 -428.172412) (xy 76.56312 -428.087826) (xy 76.682089 -428.009846) (xy 76.80528 -427.938722)
			(xy 76.932297 -427.874681) (xy 77.062734 -427.817929) (xy 77.196173 -427.768647) (xy 77.332186 -427.726993)
			(xy 77.470338 -427.693101) (xy 77.610187 -427.66708) (xy 77.751283 -427.649012) (xy 77.893175 -427.638955)
			(xy 78.03541 -427.636942) (xy 78.17753 -427.642979) (xy 78.319081 -427.657047) (xy 78.45961 -427.679101)
			(xy 78.598665 -427.70907) (xy 78.735803 -427.746858) (xy 78.870583 -427.792344) (xy 79.002574 -427.845382)
			(xy 79.131353 -427.905803) (xy 79.256507 -427.973412) (xy 79.377635 -428.047994) (xy 79.494351 -428.12931)
			(xy 79.606279 -428.217098) (xy 79.713061 -428.311078) (xy 79.814355 -428.410948) (xy 79.909836 -428.51639)
			(xy 79.9992 -428.627064) (xy 80.082158 -428.742617) (xy 80.158447 -428.862678) (xy 80.227821 -428.986863)
			(xy 80.290058 -429.114774) (xy 80.344959 -429.246001) (xy 80.392347 -429.380124) (xy 80.432072 -429.516713)
			(xy 80.464005 -429.655331) (xy 80.488046 -429.795533) (xy 80.504115 -429.936871) (xy 80.512163 -430.078892)
			(xy 80.512666 -430.150016) (xy 80.512163 -430.22114) (xy 80.504115 -430.363161) (xy 80.488046 -430.504499)
			(xy 80.464005 -430.644701) (xy 80.432072 -430.783319) (xy 80.392347 -430.919908) (xy 80.344959 -431.054031)
			(xy 80.290058 -431.185258) (xy 80.227821 -431.313169) (xy 80.158447 -431.437354) (xy 80.082158 -431.557415)
			(xy 79.9992 -431.672968) (xy 79.909836 -431.783642) (xy 79.814355 -431.889084) (xy 79.713061 -431.988954)
			(xy 79.606279 -432.082934) (xy 79.494351 -432.170722) (xy 79.377635 -432.252038) (xy 79.256507 -432.32662)
			(xy 79.131353 -432.394229) (xy 79.002574 -432.45465) (xy 78.870583 -432.507688) (xy 78.735803 -432.553174)
			(xy 78.598665 -432.590962) (xy 78.45961 -432.620931) (xy 78.319081 -432.642985) (xy 78.17753 -432.657053)
			(xy 78.03541 -432.66309) (xy 77.893175 -432.661077) (xy 77.751283 -432.65102) (xy 77.610187 -432.632952)
			(xy 77.470338 -432.606931) (xy 77.332186 -432.573039) (xy 77.196173 -432.531385) (xy 77.062734 -432.482103)
			(xy 76.932297 -432.425351) (xy 76.80528 -432.36131) (xy 76.682089 -432.290186) (xy 76.56312 -432.212206)
			(xy 76.448752 -432.12762) (xy 76.339353 -432.0367) (xy 76.235274 -431.939736) (xy 76.136846 -431.837039)
			(xy 76.044387 -431.728937) (xy 75.958191 -431.615778) (xy 75.878536 -431.497924) (xy 75.805675 -431.375752)
			(xy 75.739844 -431.249654) (xy 75.681251 -431.120033) (xy 75.630086 -430.987305) (xy 75.586512 -430.851895)
			(xy 75.550668 -430.714236) (xy 75.52267 -430.57477) (xy 75.502607 -430.433944) (xy 75.490544 -430.292208)
			(xy 75.486519 -430.150016) (xy 0.509016 -430.150016) (xy 0.509016 -451.41007) (xy 39.818063 -451.41007)
			(xy 39.82207 -451.294046) (xy 39.834072 -451.178574) (xy 39.854012 -451.064206) (xy 39.881795 -450.951486)
			(xy 39.917289 -450.840952) (xy 39.960324 -450.733129) (xy 40.010695 -450.628532) (xy 40.068162 -450.52766)
			(xy 40.132452 -450.430993) (xy 40.203257 -450.338992) (xy 40.280241 -450.252095) (xy 40.363037 -450.170716)
			(xy 40.45125 -450.095243) (xy 40.54446 -450.026036) (xy 40.642223 -449.963424) (xy 40.744072 -449.907707)
			(xy 40.849522 -449.859149) (xy 40.958071 -449.817981) (xy 41.069202 -449.784401) (xy 41.182385 -449.758568)
			(xy 41.29708 -449.740605) (xy 41.412742 -449.730597) (xy 41.528818 -449.728594) (xy 41.644756 -449.734603)
			(xy 41.760003 -449.748596) (xy 41.874009 -449.770507) (xy 41.986233 -449.800232) (xy 42.096139 -449.837628)
			(xy 42.203202 -449.882517) (xy 42.306914 -449.934686) (xy 42.406779 -449.993886) (xy 42.502322 -450.059835)
			(xy 42.593088 -450.132218) (xy 42.678643 -450.210691) (xy 42.758581 -450.294879) (xy 42.83252 -450.384381)
			(xy 42.900108 -450.478772) (xy 42.961022 -450.5776) (xy 43.014974 -450.680396) (xy 43.061704 -450.786669)
			(xy 43.100992 -450.895913) (xy 43.132649 -451.007606) (xy 43.156525 -451.121218) (xy 43.172506 -451.236206)
			(xy 43.180515 -451.352023) (xy 43.181016 -451.41007) (xy 43.180515 -451.468117) (xy 43.172506 -451.583934)
			(xy 43.156525 -451.698922) (xy 43.132649 -451.812534) (xy 43.100992 -451.924227) (xy 43.061704 -452.033471)
			(xy 43.014974 -452.139744) (xy 42.961022 -452.24254) (xy 42.900108 -452.341368) (xy 42.83252 -452.435759)
			(xy 42.758581 -452.525261) (xy 42.678643 -452.609449) (xy 42.593088 -452.687922) (xy 42.502604 -452.76008)
			(xy 93.154506 -452.76008) (xy 93.158522 -452.64381) (xy 93.170549 -452.528095) (xy 93.190531 -452.413485)
			(xy 93.218373 -452.300526) (xy 93.253942 -452.189758) (xy 93.297068 -452.081707) (xy 93.347545 -451.976889)
			(xy 93.405134 -451.875804) (xy 93.46956 -451.778932) (xy 93.540515 -451.686736) (xy 93.617662 -451.599655)
			(xy 93.700633 -451.518104) (xy 93.789033 -451.442472) (xy 93.88244 -451.373118) (xy 93.980409 -451.310375)
			(xy 94.082473 -451.254539) (xy 94.188147 -451.205878) (xy 94.296926 -451.164624) (xy 94.408291 -451.130973)
			(xy 94.521714 -451.105085) (xy 94.636651 -451.087084) (xy 94.752557 -451.077055) (xy 94.868879 -451.075047)
			(xy 94.985062 -451.081069) (xy 95.100553 -451.095092) (xy 95.214801 -451.11705) (xy 95.327262 -451.146837)
			(xy 95.4374 -451.184312) (xy 95.54469 -451.229297) (xy 95.648621 -451.281576) (xy 95.748697 -451.340901)
			(xy 95.844443 -451.406989) (xy 95.9354 -451.479525) (xy 96.021136 -451.558164) (xy 96.101243 -451.64253)
			(xy 96.175339 -451.732222) (xy 96.243069 -451.826812) (xy 96.304113 -451.92585) (xy 96.358178 -452.028863)
			(xy 96.405008 -452.13536) (xy 96.444379 -452.244835) (xy 96.476103 -452.356765) (xy 96.500029 -452.470617)
			(xy 96.516043 -452.585849) (xy 96.52407 -452.701911) (xy 96.524572 -452.76008) (xy 96.52407 -452.818249)
			(xy 96.516043 -452.934311) (xy 96.500029 -453.049543) (xy 96.476103 -453.163395) (xy 96.444379 -453.275325)
			(xy 96.405008 -453.3848) (xy 96.358178 -453.491297) (xy 96.304113 -453.59431) (xy 96.243069 -453.693348)
			(xy 96.175339 -453.787938) (xy 96.101243 -453.87763) (xy 96.021136 -453.961996) (xy 95.9354 -454.040635)
			(xy 95.844443 -454.113171) (xy 95.748697 -454.179259) (xy 95.648621 -454.238584) (xy 95.54469 -454.290863)
			(xy 95.4374 -454.335848) (xy 95.327262 -454.373323) (xy 95.214801 -454.40311) (xy 95.100553 -454.425068)
			(xy 94.985062 -454.439091) (xy 94.868879 -454.445113) (xy 94.752557 -454.443105) (xy 94.636651 -454.433076)
			(xy 94.521714 -454.415075) (xy 94.408291 -454.389187) (xy 94.296926 -454.355536) (xy 94.188147 -454.314282)
			(xy 94.082473 -454.265621) (xy 93.980409 -454.209785) (xy 93.88244 -454.147042) (xy 93.789033 -454.077688)
			(xy 93.700633 -454.002056) (xy 93.617662 -453.920505) (xy 93.540515 -453.833424) (xy 93.46956 -453.741228)
			(xy 93.405134 -453.644356) (xy 93.347545 -453.543271) (xy 93.297068 -453.438453) (xy 93.253942 -453.330402)
			(xy 93.218373 -453.219634) (xy 93.190531 -453.106675) (xy 93.170549 -452.992065) (xy 93.158522 -452.87635)
			(xy 93.154506 -452.76008) (xy 42.502604 -452.76008) (xy 42.502322 -452.760305) (xy 42.406779 -452.826254)
			(xy 42.306914 -452.885454) (xy 42.203202 -452.937623) (xy 42.096139 -452.982512) (xy 41.986233 -453.019908)
			(xy 41.874009 -453.049633) (xy 41.760003 -453.071544) (xy 41.644756 -453.085537) (xy 41.528818 -453.091546)
			(xy 41.412742 -453.089543) (xy 41.29708 -453.079535) (xy 41.182385 -453.061572) (xy 41.069202 -453.035739)
			(xy 40.958071 -453.002159) (xy 40.849522 -452.960991) (xy 40.744072 -452.912433) (xy 40.642223 -452.856716)
			(xy 40.54446 -452.794104) (xy 40.45125 -452.724897) (xy 40.363037 -452.649424) (xy 40.280241 -452.568045)
			(xy 40.203257 -452.481148) (xy 40.132452 -452.389147) (xy 40.068162 -452.29248) (xy 40.010695 -452.191608)
			(xy 39.960324 -452.087011) (xy 39.917289 -451.979188) (xy 39.881795 -451.868654) (xy 39.854012 -451.755934)
			(xy 39.834072 -451.641566) (xy 39.82207 -451.526094) (xy 39.818063 -451.41007) (xy 0.509016 -451.41007)
			(xy 0.509016 -464.509866) (xy 86.877404 -464.509866) (xy 86.881424 -464.319215) (xy 86.893478 -464.128902)
			(xy 86.913544 -463.939267) (xy 86.941587 -463.750646) (xy 86.977556 -463.563376) (xy 87.021388 -463.377788)
			(xy 87.073005 -463.194213) (xy 87.132315 -463.012977) (xy 87.199213 -462.834402) (xy 87.273579 -462.658807)
			(xy 87.355281 -462.486502) (xy 87.444175 -462.317795) (xy 87.540101 -462.152985) (xy 87.64289 -461.992366)
			(xy 87.752359 -461.836223) (xy 87.868313 -461.684834) (xy 87.990547 -461.538467) (xy 88.118841 -461.397383)
			(xy 88.252969 -461.261834) (xy 88.392693 -461.132059) (xy 88.537763 -461.008289) (xy 88.687921 -460.890746)
			(xy 88.842902 -460.779637) (xy 89.002429 -460.67516) (xy 89.166218 -460.577501) (xy 89.333978 -460.486834)
			(xy 89.505412 -460.40332) (xy 89.680214 -460.327107) (xy 89.858073 -460.258331) (xy 90.038674 -460.197113)
			(xy 90.221694 -460.143564) (xy 90.40681 -460.097778) (xy 90.593691 -460.059836) (xy 90.782006 -460.029807)
			(xy 90.971419 -460.007742) (xy 91.161593 -459.993683) (xy 91.352192 -459.987653) (xy 91.542875 -459.989663)
			(xy 91.733304 -459.99971) (xy 91.92314 -460.017776) (xy 92.112046 -460.043829) (xy 92.299685 -460.077822)
			(xy 92.485725 -460.119695) (xy 92.669834 -460.169374) (xy 92.851685 -460.22677) (xy 93.030955 -460.291781)
			(xy 93.207325 -460.364292) (xy 93.380481 -460.444173) (xy 93.550116 -460.531283) (xy 93.715928 -460.625467)
			(xy 93.877622 -460.726558) (xy 94.03491 -460.834374) (xy 94.187513 -460.948726) (xy 94.335161 -461.069409)
			(xy 94.477589 -461.19621) (xy 94.614545 -461.328901) (xy 94.745786 -461.467249) (xy 94.871078 -461.611006)
			(xy 94.990198 -461.759917) (xy 95.102934 -461.913718) (xy 95.209087 -462.072134) (xy 95.308467 -462.234885)
			(xy 95.400897 -462.40168) (xy 95.486214 -462.572224) (xy 95.564266 -462.746212) (xy 95.634913 -462.923337)
			(xy 95.698031 -463.103282) (xy 95.753507 -463.285728) (xy 95.801242 -463.470351) (xy 95.841152 -463.656821)
			(xy 95.873165 -463.844809) (xy 95.897225 -464.033979) (xy 95.913288 -464.223995) (xy 95.921327 -464.414519)
			(xy 95.92183 -464.509866) (xy 95.921327 -464.605213) (xy 95.913288 -464.795737) (xy 95.897225 -464.985753)
			(xy 95.873165 -465.174923) (xy 95.841152 -465.362911) (xy 95.801242 -465.549381) (xy 95.753507 -465.734004)
			(xy 95.698031 -465.91645) (xy 95.634913 -466.096395) (xy 95.564266 -466.27352) (xy 95.486214 -466.447508)
			(xy 95.400897 -466.618052) (xy 95.308467 -466.784847) (xy 95.209087 -466.947598) (xy 95.102934 -467.106014)
			(xy 94.990198 -467.259815) (xy 94.871078 -467.408726) (xy 94.745786 -467.552483) (xy 94.614545 -467.690831)
			(xy 94.477589 -467.823522) (xy 94.335161 -467.950323) (xy 94.187513 -468.071006) (xy 94.03491 -468.185358)
			(xy 93.877622 -468.293174) (xy 93.715928 -468.394265) (xy 93.550116 -468.488449) (xy 93.380481 -468.575559)
			(xy 93.207325 -468.65544) (xy 93.030955 -468.727951) (xy 92.851685 -468.792962) (xy 92.669834 -468.850358)
			(xy 92.485725 -468.900037) (xy 92.299685 -468.94191) (xy 92.112046 -468.975903) (xy 91.92314 -469.001956)
			(xy 91.733304 -469.020022) (xy 91.542875 -469.030069) (xy 91.352192 -469.032079) (xy 91.161593 -469.026049)
			(xy 90.971419 -469.01199) (xy 90.782006 -468.989925) (xy 90.593691 -468.959896) (xy 90.40681 -468.921954)
			(xy 90.221694 -468.876168) (xy 90.038674 -468.822619) (xy 89.858073 -468.761401) (xy 89.680214 -468.692625)
			(xy 89.505412 -468.616412) (xy 89.333978 -468.532898) (xy 89.166218 -468.442231) (xy 89.002429 -468.344572)
			(xy 88.842902 -468.240095) (xy 88.687921 -468.128986) (xy 88.537763 -468.011443) (xy 88.392693 -467.887673)
			(xy 88.252969 -467.757898) (xy 88.118841 -467.622349) (xy 87.990547 -467.481265) (xy 87.868313 -467.334898)
			(xy 87.752359 -467.183509) (xy 87.64289 -467.027366) (xy 87.540101 -466.866747) (xy 87.444175 -466.701937)
			(xy 87.355281 -466.53323) (xy 87.273579 -466.360925) (xy 87.199213 -466.18533) (xy 87.132315 -466.006755)
			(xy 87.073005 -465.825519) (xy 87.021388 -465.641944) (xy 86.977556 -465.456356) (xy 86.941587 -465.269086)
			(xy 86.913544 -465.080465) (xy 86.893478 -464.89083) (xy 86.881424 -464.700517) (xy 86.877404 -464.509866)
			(xy 0.509016 -464.509866) (xy 0.509016 -473.69984) (xy 14.086591 -473.69984) (xy 14.090616 -473.557648)
			(xy 14.102679 -473.415912) (xy 14.122742 -473.275086) (xy 14.15074 -473.13562) (xy 14.186584 -472.997961)
			(xy 14.230158 -472.862551) (xy 14.281323 -472.729823) (xy 14.339916 -472.600202) (xy 14.405747 -472.474104)
			(xy 14.478608 -472.351932) (xy 14.558263 -472.234078) (xy 14.644459 -472.120919) (xy 14.736918 -472.012817)
			(xy 14.835346 -471.91012) (xy 14.939425 -471.813156) (xy 15.048824 -471.722236) (xy 15.163192 -471.63765)
			(xy 15.282161 -471.55967) (xy 15.405352 -471.488546) (xy 15.532369 -471.424505) (xy 15.662806 -471.367753)
			(xy 15.796245 -471.318471) (xy 15.932258 -471.276817) (xy 16.07041 -471.242925) (xy 16.210259 -471.216904)
			(xy 16.351355 -471.198836) (xy 16.493247 -471.188779) (xy 16.635482 -471.186766) (xy 16.777602 -471.192803)
			(xy 16.919153 -471.206871) (xy 17.059682 -471.228925) (xy 17.198737 -471.258894) (xy 17.335875 -471.296682)
			(xy 17.470655 -471.342168) (xy 17.602646 -471.395206) (xy 17.731425 -471.455627) (xy 17.856579 -471.523236)
			(xy 17.977707 -471.597818) (xy 18.094423 -471.679134) (xy 18.206351 -471.766922) (xy 18.313133 -471.860902)
			(xy 18.414427 -471.960772) (xy 18.509908 -472.066214) (xy 18.599272 -472.176888) (xy 18.68223 -472.292441)
			(xy 18.758519 -472.412502) (xy 18.827893 -472.536687) (xy 18.89013 -472.664598) (xy 18.945031 -472.795825)
			(xy 18.992419 -472.929948) (xy 19.032144 -473.066537) (xy 19.064077 -473.205155) (xy 19.088118 -473.345357)
			(xy 19.104187 -473.486695) (xy 19.112235 -473.628716) (xy 19.112738 -473.69984) (xy 19.112235 -473.770964)
			(xy 19.104187 -473.912985) (xy 19.088118 -474.054323) (xy 19.064077 -474.194525) (xy 19.032144 -474.333143)
			(xy 18.992419 -474.469732) (xy 18.945031 -474.603855) (xy 18.89013 -474.735082) (xy 18.827893 -474.862993)
			(xy 18.758519 -474.987178) (xy 18.68223 -475.107239) (xy 18.599272 -475.222792) (xy 18.509908 -475.333466)
			(xy 18.414427 -475.438908) (xy 18.313133 -475.538778) (xy 18.206351 -475.632758) (xy 18.094423 -475.720546)
			(xy 17.977707 -475.801862) (xy 17.856579 -475.876444) (xy 17.731425 -475.944053) (xy 17.602646 -476.004474)
			(xy 17.470655 -476.057512) (xy 17.335875 -476.102998) (xy 17.198737 -476.140786) (xy 17.059682 -476.170755)
			(xy 16.919153 -476.192809) (xy 16.777602 -476.206877) (xy 16.635482 -476.212914) (xy 16.493247 -476.210901)
			(xy 16.351355 -476.200844) (xy 16.210259 -476.182776) (xy 16.07041 -476.156755) (xy 15.932258 -476.122863)
			(xy 15.796245 -476.081209) (xy 15.662806 -476.031927) (xy 15.532369 -475.975175) (xy 15.405352 -475.911134)
			(xy 15.282161 -475.84001) (xy 15.163192 -475.76203) (xy 15.048824 -475.677444) (xy 14.939425 -475.586524)
			(xy 14.835346 -475.48956) (xy 14.736918 -475.386863) (xy 14.644459 -475.278761) (xy 14.558263 -475.165602)
			(xy 14.478608 -475.047748) (xy 14.405747 -474.925576) (xy 14.339916 -474.799478) (xy 14.281323 -474.669857)
			(xy 14.230158 -474.537129) (xy 14.186584 -474.401719) (xy 14.15074 -474.26406) (xy 14.122742 -474.124594)
			(xy 14.102679 -473.983768) (xy 14.090616 -473.842032) (xy 14.086591 -473.69984) (xy 0.509016 -473.69984)
			(xy 0.509016 -478.795334) (xy 74.887836 -478.795334) (xy 74.887836 -477.804734) (xy 74.888335 -477.725886)
			(xy 74.896323 -477.568392) (xy 74.912276 -477.411504) (xy 74.936156 -477.255626) (xy 74.9679 -477.101158)
			(xy 75.007427 -476.948495) (xy 75.054636 -476.798031) (xy 75.109405 -476.650151) (xy 75.171593 -476.505234)
			(xy 75.241042 -476.363653) (xy 75.317572 -476.225772) (xy 75.400988 -476.091944) (xy 75.491075 -475.962512)
			(xy 75.587602 -475.83781) (xy 75.690321 -475.718156) (xy 75.798969 -475.603859) (xy 75.913266 -475.495211)
			(xy 76.03292 -475.392492) (xy 76.157622 -475.295965) (xy 76.287054 -475.205878) (xy 76.420882 -475.122462)
			(xy 76.558763 -475.045932) (xy 76.700344 -474.976483) (xy 76.845261 -474.914295) (xy 76.993141 -474.859526)
			(xy 77.143605 -474.812317) (xy 77.296268 -474.77279) (xy 77.450736 -474.741046) (xy 77.606614 -474.717166)
			(xy 77.763502 -474.701213) (xy 77.920996 -474.693225) (xy 78.078692 -474.693225) (xy 78.236186 -474.701213)
			(xy 78.393074 -474.717166) (xy 78.548952 -474.741046) (xy 78.70342 -474.77279) (xy 78.856083 -474.812317)
			(xy 79.006547 -474.859526) (xy 79.154427 -474.914295) (xy 79.299344 -474.976483) (xy 79.440925 -475.045932)
			(xy 79.578806 -475.122462) (xy 79.712634 -475.205878) (xy 79.842066 -475.295965) (xy 79.966768 -475.392492)
			(xy 80.086422 -475.495211) (xy 80.200719 -475.603859) (xy 80.309367 -475.718156) (xy 80.412086 -475.83781)
			(xy 80.508613 -475.962512) (xy 80.5987 -476.091944) (xy 80.682116 -476.225772) (xy 80.758646 -476.363653)
			(xy 80.828095 -476.505234) (xy 80.890283 -476.650151) (xy 80.945052 -476.798031) (xy 80.992261 -476.948495)
			(xy 81.031788 -477.101158) (xy 81.063532 -477.255626) (xy 81.087412 -477.411504) (xy 81.103365 -477.568392)
			(xy 81.111353 -477.725886) (xy 81.111852 -477.804734) (xy 81.111852 -478.309432) (xy 91.266778 -478.309432)
			(xy 91.270798 -478.159746) (xy 91.282847 -478.010492) (xy 91.30289 -477.862099) (xy 91.330869 -477.714997)
			(xy 91.366704 -477.569608) (xy 91.410292 -477.426352) (xy 91.461506 -477.285643) (xy 91.520199 -477.147885)
			(xy 91.586202 -477.013477) (xy 91.659324 -476.882805) (xy 91.739355 -476.756246) (xy 91.826064 -476.634166)
			(xy 91.9192 -476.516916) (xy 92.018496 -476.404834) (xy 92.123665 -476.298243) (xy 92.234404 -476.197452)
			(xy 92.350393 -476.102749) (xy 92.471298 -476.014409) (xy 92.596771 -475.932687) (xy 92.72645 -475.857817)
			(xy 92.85996 -475.790015) (xy 92.996917 -475.729478) (xy 93.136926 -475.67638) (xy 93.279584 -475.630873)
			(xy 93.424478 -475.593089) (xy 93.571192 -475.563138) (xy 93.719302 -475.541104) (xy 93.868381 -475.527052)
			(xy 94.018 -475.521023) (xy 94.167726 -475.523033) (xy 94.317129 -475.533077) (xy 94.465777 -475.551126)
			(xy 94.613242 -475.577129) (xy 94.759098 -475.611009) (xy 94.902926 -475.652669) (xy 95.044311 -475.701989)
			(xy 95.182844 -475.758827) (xy 95.318126 -475.82302) (xy 95.449768 -475.894381) (xy 95.57739 -475.972706)
			(xy 95.700623 -476.057768) (xy 95.819113 -476.149322) (xy 95.932518 -476.247104) (xy 96.040511 -476.350832)
			(xy 96.14278 -476.460208) (xy 96.239031 -476.574915) (xy 96.328986 -476.694624) (xy 96.412386 -476.818988)
			(xy 96.48899 -476.94765) (xy 96.558578 -477.080238) (xy 96.620948 -477.21637) (xy 96.675922 -477.355654)
			(xy 96.72334 -477.497688) (xy 96.763065 -477.642062) (xy 96.794984 -477.78836) (xy 96.819004 -477.936161)
			(xy 96.835056 -478.085038) (xy 96.843093 -478.234562) (xy 96.843596 -478.309432) (xy 96.843093 -478.384302)
			(xy 96.835056 -478.533826) (xy 96.819004 -478.682703) (xy 96.794984 -478.830504) (xy 96.763065 -478.976802)
			(xy 96.72334 -479.121176) (xy 96.675922 -479.26321) (xy 96.620948 -479.402494) (xy 96.558578 -479.538626)
			(xy 96.48899 -479.671214) (xy 96.412386 -479.799876) (xy 96.328986 -479.92424) (xy 96.239031 -480.043949)
			(xy 96.14278 -480.158656) (xy 96.040511 -480.268032) (xy 95.932518 -480.37176) (xy 95.819113 -480.469542)
			(xy 95.700623 -480.561096) (xy 95.57739 -480.646158) (xy 95.449768 -480.724483) (xy 95.318126 -480.795844)
			(xy 95.182844 -480.860037) (xy 95.044311 -480.916875) (xy 94.902926 -480.966195) (xy 94.759098 -481.007855)
			(xy 94.613242 -481.041735) (xy 94.465777 -481.067738) (xy 94.317129 -481.085787) (xy 94.167726 -481.095831)
			(xy 94.018 -481.097841) (xy 93.868381 -481.091812) (xy 93.719302 -481.07776) (xy 93.571192 -481.055726)
			(xy 93.424478 -481.025775) (xy 93.279584 -480.987991) (xy 93.136926 -480.942484) (xy 92.996917 -480.889386)
			(xy 92.85996 -480.828849) (xy 92.72645 -480.761047) (xy 92.596771 -480.686177) (xy 92.471298 -480.604455)
			(xy 92.350393 -480.516115) (xy 92.234404 -480.421412) (xy 92.123665 -480.320621) (xy 92.018496 -480.21403)
			(xy 91.9192 -480.101948) (xy 91.826064 -479.984698) (xy 91.739355 -479.862618) (xy 91.659324 -479.736059)
			(xy 91.586202 -479.605387) (xy 91.520199 -479.470979) (xy 91.461506 -479.333221) (xy 91.410292 -479.192512)
			(xy 91.366704 -479.049256) (xy 91.330869 -478.903867) (xy 91.30289 -478.756765) (xy 91.282847 -478.608372)
			(xy 91.270798 -478.459118) (xy 91.266778 -478.309432) (xy 81.111852 -478.309432) (xy 81.111852 -478.795334)
			(xy 81.111353 -478.874182) (xy 81.103365 -479.031676) (xy 81.087412 -479.188564) (xy 81.063532 -479.344442)
			(xy 81.031788 -479.49891) (xy 80.992261 -479.651573) (xy 80.945052 -479.802037) (xy 80.890283 -479.949917)
			(xy 80.828095 -480.094834) (xy 80.758646 -480.236415) (xy 80.682116 -480.374296) (xy 80.5987 -480.508124)
			(xy 80.508613 -480.637556) (xy 80.412086 -480.762258) (xy 80.309367 -480.881912) (xy 80.200719 -480.996209)
			(xy 80.086422 -481.104857) (xy 79.966768 -481.207576) (xy 79.842066 -481.304103) (xy 79.712634 -481.39419)
			(xy 79.578806 -481.477606) (xy 79.440925 -481.554136) (xy 79.299344 -481.623585) (xy 79.154427 -481.685773)
			(xy 79.006547 -481.740542) (xy 78.856083 -481.787751) (xy 78.70342 -481.827278) (xy 78.548952 -481.859022)
			(xy 78.393074 -481.882902) (xy 78.236186 -481.898855) (xy 78.078692 -481.906843) (xy 77.920996 -481.906843)
			(xy 77.763502 -481.898855) (xy 77.606614 -481.882902) (xy 77.450736 -481.859022) (xy 77.296268 -481.827278)
			(xy 77.143605 -481.787751) (xy 76.993141 -481.740542) (xy 76.845261 -481.685773) (xy 76.700344 -481.623585)
			(xy 76.558763 -481.554136) (xy 76.420882 -481.477606) (xy 76.287054 -481.39419) (xy 76.157622 -481.304103)
			(xy 76.03292 -481.207576) (xy 75.913266 -481.104857) (xy 75.798969 -480.996209) (xy 75.690321 -480.881912)
			(xy 75.587602 -480.762258) (xy 75.491075 -480.637556) (xy 75.400988 -480.508124) (xy 75.317572 -480.374296)
			(xy 75.241042 -480.236415) (xy 75.171593 -480.094834) (xy 75.109405 -479.949917) (xy 75.054636 -479.802037)
			(xy 75.007427 -479.651573) (xy 74.9679 -479.49891) (xy 74.936156 -479.344442) (xy 74.912276 -479.188564)
			(xy 74.896323 -479.031676) (xy 74.888335 -478.874182) (xy 74.887836 -478.795334) (xy 0.509016 -478.795334)
			(xy 0.509016 -488.261914) (xy 1.150624 -488.261914) (xy 1.154655 -488.132348) (xy 1.166734 -488.003284)
			(xy 1.186813 -487.87522) (xy 1.214815 -487.748653) (xy 1.250632 -487.62407) (xy 1.294124 -487.501956)
			(xy 1.345124 -487.382782) (xy 1.403435 -487.267009) (xy 1.46883 -487.155085) (xy 1.541057 -487.047443)
			(xy 1.619837 -486.9445) (xy 1.704864 -486.846654) (xy 1.795809 -486.754282) (xy 1.892321 -486.667744)
			(xy 1.994027 -486.587373) (xy 2.100533 -486.513481) (xy 2.211426 -486.446353) (xy 2.326278 -486.386249)
			(xy 2.444645 -486.333402) (xy 2.566068 -486.288015) (xy 2.690078 -486.250266) (xy 2.816195 -486.220299)
			(xy 2.943931 -486.19823) (xy 3.072792 -486.184146) (xy 3.202279 -486.1781) (xy 3.331892 -486.180116)
			(xy 3.461128 -486.190186) (xy 3.589489 -486.208271) (xy 3.716477 -486.234301) (xy 3.841601 -486.268176)
			(xy 3.964377 -486.309764) (xy 4.08433 -486.358905) (xy 4.200995 -486.415408) (xy 4.313923 -486.479055)
			(xy 4.422675 -486.549599) (xy 4.526831 -486.626768) (xy 4.625988 -486.710263) (xy 4.719762 -486.799761)
			(xy 4.807791 -486.894916) (xy 4.889734 -486.995359) (xy 4.965273 -487.100702) (xy 5.034118 -487.210538)
			(xy 5.096001 -487.324442) (xy 5.150682 -487.441972) (xy 5.197952 -487.562675) (xy 5.237625 -487.686083)
			(xy 5.26955 -487.811719) (xy 5.293602 -487.939096) (xy 5.309689 -488.067722) (xy 5.317748 -488.1971)
			(xy 5.318252 -488.261914) (xy 12.580624 -488.261914) (xy 12.584655 -488.132348) (xy 12.596734 -488.003284)
			(xy 12.616813 -487.87522) (xy 12.644815 -487.748653) (xy 12.680632 -487.62407) (xy 12.724124 -487.501956)
			(xy 12.775124 -487.382782) (xy 12.833435 -487.267009) (xy 12.89883 -487.155085) (xy 12.971057 -487.047443)
			(xy 13.049837 -486.9445) (xy 13.134864 -486.846654) (xy 13.225809 -486.754282) (xy 13.322321 -486.667744)
			(xy 13.424027 -486.587373) (xy 13.530533 -486.513481) (xy 13.641426 -486.446353) (xy 13.756278 -486.386249)
			(xy 13.874645 -486.333402) (xy 13.996068 -486.288015) (xy 14.120078 -486.250266) (xy 14.246195 -486.220299)
			(xy 14.373931 -486.19823) (xy 14.502792 -486.184146) (xy 14.632279 -486.1781) (xy 14.761892 -486.180116)
			(xy 14.891128 -486.190186) (xy 15.019489 -486.208271) (xy 15.146477 -486.234301) (xy 15.271601 -486.268176)
			(xy 15.394377 -486.309764) (xy 15.51433 -486.358905) (xy 15.630995 -486.415408) (xy 15.743923 -486.479055)
			(xy 15.852675 -486.549599) (xy 15.956831 -486.626768) (xy 16.055988 -486.710263) (xy 16.149762 -486.799761)
			(xy 16.237791 -486.894916) (xy 16.319734 -486.995359) (xy 16.395273 -487.100702) (xy 16.464118 -487.210538)
			(xy 16.526001 -487.324442) (xy 16.580682 -487.441972) (xy 16.627952 -487.562675) (xy 16.667625 -487.686083)
			(xy 16.69955 -487.811719) (xy 16.723602 -487.939096) (xy 16.739689 -488.067722) (xy 16.747748 -488.1971)
			(xy 16.748252 -488.261914) (xy 16.747748 -488.326728) (xy 16.739689 -488.456106) (xy 16.723602 -488.584732)
			(xy 16.69955 -488.712109) (xy 16.667625 -488.837745) (xy 16.627952 -488.961153) (xy 16.580682 -489.081856)
			(xy 16.526001 -489.199386) (xy 16.464118 -489.31329) (xy 16.395273 -489.423126) (xy 16.319734 -489.528469)
			(xy 16.237791 -489.628912) (xy 16.149762 -489.724067) (xy 16.055988 -489.813565) (xy 15.956831 -489.89706)
			(xy 15.852675 -489.974229) (xy 15.743923 -490.044773) (xy 15.630995 -490.10842) (xy 15.51433 -490.164923)
			(xy 15.394377 -490.214064) (xy 15.271601 -490.255652) (xy 15.146477 -490.289527) (xy 15.019489 -490.315557)
			(xy 14.891128 -490.333642) (xy 14.761892 -490.343712) (xy 14.632279 -490.345728) (xy 14.502792 -490.339682)
			(xy 14.373931 -490.325598) (xy 14.246195 -490.303529) (xy 14.120078 -490.273562) (xy 13.996068 -490.235813)
			(xy 13.874645 -490.190426) (xy 13.756278 -490.137579) (xy 13.641426 -490.077475) (xy 13.530533 -490.010347)
			(xy 13.424027 -489.936455) (xy 13.322321 -489.856084) (xy 13.225809 -489.769546) (xy 13.134864 -489.677174)
			(xy 13.049837 -489.579328) (xy 12.971057 -489.476385) (xy 12.89883 -489.368743) (xy 12.833435 -489.256819)
			(xy 12.775124 -489.141046) (xy 12.724124 -489.021872) (xy 12.680632 -488.899758) (xy 12.644815 -488.775175)
			(xy 12.616813 -488.648608) (xy 12.596734 -488.520544) (xy 12.584655 -488.39148) (xy 12.580624 -488.261914)
			(xy 5.318252 -488.261914) (xy 5.317748 -488.326728) (xy 5.309689 -488.456106) (xy 5.293602 -488.584732)
			(xy 5.26955 -488.712109) (xy 5.237625 -488.837745) (xy 5.197952 -488.961153) (xy 5.150682 -489.081856)
			(xy 5.096001 -489.199386) (xy 5.034118 -489.31329) (xy 4.965273 -489.423126) (xy 4.889734 -489.528469)
			(xy 4.807791 -489.628912) (xy 4.719762 -489.724067) (xy 4.625988 -489.813565) (xy 4.526831 -489.89706)
			(xy 4.422675 -489.974229) (xy 4.313923 -490.044773) (xy 4.200995 -490.10842) (xy 4.08433 -490.164923)
			(xy 3.964377 -490.214064) (xy 3.841601 -490.255652) (xy 3.716477 -490.289527) (xy 3.589489 -490.315557)
			(xy 3.461128 -490.333642) (xy 3.331892 -490.343712) (xy 3.202279 -490.345728) (xy 3.072792 -490.339682)
			(xy 2.943931 -490.325598) (xy 2.816195 -490.303529) (xy 2.690078 -490.273562) (xy 2.566068 -490.235813)
			(xy 2.444645 -490.190426) (xy 2.326278 -490.137579) (xy 2.211426 -490.077475) (xy 2.100533 -490.010347)
			(xy 1.994027 -489.936455) (xy 1.892321 -489.856084) (xy 1.795809 -489.769546) (xy 1.704864 -489.677174)
			(xy 1.619837 -489.579328) (xy 1.541057 -489.476385) (xy 1.46883 -489.368743) (xy 1.403435 -489.256819)
			(xy 1.345124 -489.141046) (xy 1.294124 -489.021872) (xy 1.250632 -488.899758) (xy 1.214815 -488.775175)
			(xy 1.186813 -488.648608) (xy 1.166734 -488.520544) (xy 1.154655 -488.39148) (xy 1.150624 -488.261914)
			(xy 0.509016 -488.261914) (xy 0.509016 -495.86007) (xy 39.818063 -495.86007) (xy 39.82207 -495.744046)
			(xy 39.834072 -495.628574) (xy 39.854012 -495.514206) (xy 39.881795 -495.401486) (xy 39.917289 -495.290952)
			(xy 39.960324 -495.183129) (xy 40.010695 -495.078532) (xy 40.068162 -494.97766) (xy 40.132452 -494.880993)
			(xy 40.203257 -494.788992) (xy 40.280241 -494.702095) (xy 40.363037 -494.620716) (xy 40.45125 -494.545243)
			(xy 40.54446 -494.476036) (xy 40.642223 -494.413424) (xy 40.744072 -494.357707) (xy 40.849522 -494.309149)
			(xy 40.958071 -494.267981) (xy 41.069202 -494.234401) (xy 41.182385 -494.208568) (xy 41.29708 -494.190605)
			(xy 41.412742 -494.180597) (xy 41.528818 -494.178594) (xy 41.644756 -494.184603) (xy 41.760003 -494.198596)
			(xy 41.874009 -494.220507) (xy 41.986233 -494.250232) (xy 42.096139 -494.287628) (xy 42.203202 -494.332517)
			(xy 42.306914 -494.384686) (xy 42.406779 -494.443886) (xy 42.502322 -494.509835) (xy 42.593088 -494.582218)
			(xy 42.678643 -494.660691) (xy 42.758581 -494.744879) (xy 42.83252 -494.834381) (xy 42.900108 -494.928772)
			(xy 42.961022 -495.0276) (xy 43.014974 -495.130396) (xy 43.061704 -495.236669) (xy 43.100992 -495.345913)
			(xy 43.132649 -495.457606) (xy 43.156525 -495.571218) (xy 43.172506 -495.686206) (xy 43.180515 -495.802023)
			(xy 43.181016 -495.86007) (xy 43.180515 -495.918117) (xy 43.172506 -496.033934) (xy 43.156525 -496.148922)
			(xy 43.132649 -496.262534) (xy 43.100992 -496.374227) (xy 43.061704 -496.483471) (xy 43.014974 -496.589744)
			(xy 42.961022 -496.69254) (xy 42.900108 -496.791368) (xy 42.83252 -496.885759) (xy 42.758581 -496.975261)
			(xy 42.678643 -497.059449) (xy 42.593088 -497.137922) (xy 42.502604 -497.21008) (xy 93.154506 -497.21008)
			(xy 93.158522 -497.09381) (xy 93.170549 -496.978095) (xy 93.190531 -496.863485) (xy 93.218373 -496.750526)
			(xy 93.253942 -496.639758) (xy 93.297068 -496.531707) (xy 93.347545 -496.426889) (xy 93.405134 -496.325804)
			(xy 93.46956 -496.228932) (xy 93.540515 -496.136736) (xy 93.617662 -496.049655) (xy 93.700633 -495.968104)
			(xy 93.789033 -495.892472) (xy 93.88244 -495.823118) (xy 93.980409 -495.760375) (xy 94.082473 -495.704539)
			(xy 94.188147 -495.655878) (xy 94.296926 -495.614624) (xy 94.408291 -495.580973) (xy 94.521714 -495.555085)
			(xy 94.636651 -495.537084) (xy 94.752557 -495.527055) (xy 94.868879 -495.525047) (xy 94.985062 -495.531069)
			(xy 95.100553 -495.545092) (xy 95.214801 -495.56705) (xy 95.327262 -495.596837) (xy 95.4374 -495.634312)
			(xy 95.54469 -495.679297) (xy 95.648621 -495.731576) (xy 95.748697 -495.790901) (xy 95.844443 -495.856989)
			(xy 95.9354 -495.929525) (xy 96.021136 -496.008164) (xy 96.101243 -496.09253) (xy 96.175339 -496.182222)
			(xy 96.243069 -496.276812) (xy 96.304113 -496.37585) (xy 96.358178 -496.478863) (xy 96.405008 -496.58536)
			(xy 96.444379 -496.694835) (xy 96.476103 -496.806765) (xy 96.500029 -496.920617) (xy 96.516043 -497.035849)
			(xy 96.52407 -497.151911) (xy 96.524572 -497.21008) (xy 96.52407 -497.268249) (xy 96.516043 -497.384311)
			(xy 96.500029 -497.499543) (xy 96.476103 -497.613395) (xy 96.444379 -497.725325) (xy 96.405008 -497.8348)
			(xy 96.358178 -497.941297) (xy 96.304113 -498.04431) (xy 96.243069 -498.143348) (xy 96.175339 -498.237938)
			(xy 96.101243 -498.32763) (xy 96.021136 -498.411996) (xy 95.9354 -498.490635) (xy 95.844443 -498.563171)
			(xy 95.748697 -498.629259) (xy 95.648621 -498.688584) (xy 95.54469 -498.740863) (xy 95.4374 -498.785848)
			(xy 95.327262 -498.823323) (xy 95.214801 -498.85311) (xy 95.100553 -498.875068) (xy 94.985062 -498.889091)
			(xy 94.868879 -498.895113) (xy 94.752557 -498.893105) (xy 94.636651 -498.883076) (xy 94.521714 -498.865075)
			(xy 94.408291 -498.839187) (xy 94.296926 -498.805536) (xy 94.188147 -498.764282) (xy 94.082473 -498.715621)
			(xy 93.980409 -498.659785) (xy 93.88244 -498.597042) (xy 93.789033 -498.527688) (xy 93.700633 -498.452056)
			(xy 93.617662 -498.370505) (xy 93.540515 -498.283424) (xy 93.46956 -498.191228) (xy 93.405134 -498.094356)
			(xy 93.347545 -497.993271) (xy 93.297068 -497.888453) (xy 93.253942 -497.780402) (xy 93.218373 -497.669634)
			(xy 93.190531 -497.556675) (xy 93.170549 -497.442065) (xy 93.158522 -497.32635) (xy 93.154506 -497.21008)
			(xy 42.502604 -497.21008) (xy 42.502322 -497.210305) (xy 42.406779 -497.276254) (xy 42.306914 -497.335454)
			(xy 42.203202 -497.387623) (xy 42.096139 -497.432512) (xy 41.986233 -497.469908) (xy 41.874009 -497.499633)
			(xy 41.760003 -497.521544) (xy 41.644756 -497.535537) (xy 41.528818 -497.541546) (xy 41.412742 -497.539543)
			(xy 41.29708 -497.529535) (xy 41.182385 -497.511572) (xy 41.069202 -497.485739) (xy 40.958071 -497.452159)
			(xy 40.849522 -497.410991) (xy 40.744072 -497.362433) (xy 40.642223 -497.306716) (xy 40.54446 -497.244104)
			(xy 40.45125 -497.174897) (xy 40.363037 -497.099424) (xy 40.280241 -497.018045) (xy 40.203257 -496.931148)
			(xy 40.132452 -496.839147) (xy 40.068162 -496.74248) (xy 40.010695 -496.641608) (xy 39.960324 -496.537011)
			(xy 39.917289 -496.429188) (xy 39.881795 -496.318654) (xy 39.854012 -496.205934) (xy 39.834072 -496.091566)
			(xy 39.82207 -495.976094) (xy 39.818063 -495.86007) (xy 0.509016 -495.86007) (xy 0.509016 -508.96012)
			(xy 86.877404 -508.96012) (xy 86.881424 -508.769469) (xy 86.893478 -508.579156) (xy 86.913544 -508.389521)
			(xy 86.941587 -508.2009) (xy 86.977556 -508.01363) (xy 87.021388 -507.828042) (xy 87.073005 -507.644467)
			(xy 87.132315 -507.463231) (xy 87.199213 -507.284656) (xy 87.273579 -507.109061) (xy 87.355281 -506.936756)
			(xy 87.444175 -506.768049) (xy 87.540101 -506.603239) (xy 87.64289 -506.44262) (xy 87.752359 -506.286477)
			(xy 87.868313 -506.135088) (xy 87.990547 -505.988721) (xy 88.118841 -505.847637) (xy 88.252969 -505.712088)
			(xy 88.392693 -505.582313) (xy 88.537763 -505.458543) (xy 88.687921 -505.341) (xy 88.842902 -505.229891)
			(xy 89.002429 -505.125414) (xy 89.166218 -505.027755) (xy 89.333978 -504.937088) (xy 89.505412 -504.853574)
			(xy 89.680214 -504.777361) (xy 89.858073 -504.708585) (xy 90.038674 -504.647367) (xy 90.221694 -504.593818)
			(xy 90.40681 -504.548032) (xy 90.593691 -504.51009) (xy 90.782006 -504.480061) (xy 90.971419 -504.457996)
			(xy 91.161593 -504.443937) (xy 91.352192 -504.437907) (xy 91.542875 -504.439917) (xy 91.733304 -504.449964)
			(xy 91.92314 -504.46803) (xy 92.112046 -504.494083) (xy 92.299685 -504.528076) (xy 92.485725 -504.569949)
			(xy 92.669834 -504.619628) (xy 92.851685 -504.677024) (xy 93.030955 -504.742035) (xy 93.207325 -504.814546)
			(xy 93.380481 -504.894427) (xy 93.550116 -504.981537) (xy 93.715928 -505.075721) (xy 93.877622 -505.176812)
			(xy 94.03491 -505.284628) (xy 94.187513 -505.39898) (xy 94.335161 -505.519663) (xy 94.477589 -505.646464)
			(xy 94.614545 -505.779155) (xy 94.745786 -505.917503) (xy 94.871078 -506.06126) (xy 94.990198 -506.210171)
			(xy 95.102934 -506.363972) (xy 95.209087 -506.522388) (xy 95.308467 -506.685139) (xy 95.400897 -506.851934)
			(xy 95.486214 -507.022478) (xy 95.564266 -507.196466) (xy 95.634913 -507.373591) (xy 95.698031 -507.553536)
			(xy 95.753507 -507.735982) (xy 95.801242 -507.920605) (xy 95.841152 -508.107075) (xy 95.873165 -508.295063)
			(xy 95.897225 -508.484233) (xy 95.913288 -508.674249) (xy 95.921327 -508.864773) (xy 95.92183 -508.96012)
			(xy 95.921327 -509.055467) (xy 95.913288 -509.245991) (xy 95.897225 -509.436007) (xy 95.873165 -509.625177)
			(xy 95.841152 -509.813165) (xy 95.801242 -509.999635) (xy 95.753507 -510.184258) (xy 95.698031 -510.366704)
			(xy 95.634913 -510.546649) (xy 95.564266 -510.723774) (xy 95.486214 -510.897762) (xy 95.400897 -511.068306)
			(xy 95.308467 -511.235101) (xy 95.209087 -511.397852) (xy 95.102934 -511.556268) (xy 94.990198 -511.710069)
			(xy 94.871078 -511.85898) (xy 94.745786 -512.002737) (xy 94.614545 -512.141085) (xy 94.477589 -512.273776)
			(xy 94.335161 -512.400577) (xy 94.187513 -512.52126) (xy 94.03491 -512.635612) (xy 93.877622 -512.743428)
			(xy 93.715928 -512.844519) (xy 93.550116 -512.938703) (xy 93.380481 -513.025813) (xy 93.207325 -513.105694)
			(xy 93.030955 -513.178205) (xy 92.851685 -513.243216) (xy 92.669834 -513.300612) (xy 92.485725 -513.350291)
			(xy 92.299685 -513.392164) (xy 92.112046 -513.426157) (xy 91.92314 -513.45221) (xy 91.733304 -513.470276)
			(xy 91.542875 -513.480323) (xy 91.352192 -513.482333) (xy 91.161593 -513.476303) (xy 90.971419 -513.462244)
			(xy 90.782006 -513.440179) (xy 90.593691 -513.41015) (xy 90.40681 -513.372208) (xy 90.221694 -513.326422)
			(xy 90.038674 -513.272873) (xy 89.858073 -513.211655) (xy 89.680214 -513.142879) (xy 89.505412 -513.066666)
			(xy 89.333978 -512.983152) (xy 89.166218 -512.892485) (xy 89.002429 -512.794826) (xy 88.842902 -512.690349)
			(xy 88.687921 -512.57924) (xy 88.537763 -512.461697) (xy 88.392693 -512.337927) (xy 88.252969 -512.208152)
			(xy 88.118841 -512.072603) (xy 87.990547 -511.931519) (xy 87.868313 -511.785152) (xy 87.752359 -511.633763)
			(xy 87.64289 -511.47762) (xy 87.540101 -511.317001) (xy 87.444175 -511.152191) (xy 87.355281 -510.983484)
			(xy 87.273579 -510.811179) (xy 87.199213 -510.635584) (xy 87.132315 -510.457009) (xy 87.073005 -510.275773)
			(xy 87.021388 -510.092198) (xy 86.977556 -509.90661) (xy 86.941587 -509.71934) (xy 86.913544 -509.530719)
			(xy 86.893478 -509.341084) (xy 86.881424 -509.150771) (xy 86.877404 -508.96012) (xy 0.509016 -508.96012)
			(xy 0.509016 -514.771894) (xy 1.150624 -514.771894) (xy 1.154655 -514.642328) (xy 1.166734 -514.513264)
			(xy 1.186813 -514.3852) (xy 1.214815 -514.258633) (xy 1.250632 -514.13405) (xy 1.294124 -514.011936)
			(xy 1.345124 -513.892762) (xy 1.403435 -513.776989) (xy 1.46883 -513.665065) (xy 1.541057 -513.557423)
			(xy 1.619837 -513.45448) (xy 1.704864 -513.356634) (xy 1.795809 -513.264262) (xy 1.892321 -513.177724)
			(xy 1.994027 -513.097353) (xy 2.100533 -513.023461) (xy 2.211426 -512.956333) (xy 2.326278 -512.896229)
			(xy 2.444645 -512.843382) (xy 2.566068 -512.797995) (xy 2.690078 -512.760246) (xy 2.816195 -512.730279)
			(xy 2.943931 -512.70821) (xy 3.072792 -512.694126) (xy 3.202279 -512.68808) (xy 3.331892 -512.690096)
			(xy 3.461128 -512.700166) (xy 3.589489 -512.718251) (xy 3.716477 -512.744281) (xy 3.841601 -512.778156)
			(xy 3.964377 -512.819744) (xy 4.08433 -512.868885) (xy 4.200995 -512.925388) (xy 4.313923 -512.989035)
			(xy 4.422675 -513.059579) (xy 4.526831 -513.136748) (xy 4.625988 -513.220243) (xy 4.719762 -513.309741)
			(xy 4.807791 -513.404896) (xy 4.889734 -513.505339) (xy 4.965273 -513.610682) (xy 5.034118 -513.720518)
			(xy 5.096001 -513.834422) (xy 5.150682 -513.951952) (xy 5.197952 -514.072655) (xy 5.237625 -514.196063)
			(xy 5.26955 -514.321699) (xy 5.293602 -514.449076) (xy 5.309689 -514.577702) (xy 5.317748 -514.70708)
			(xy 5.318252 -514.771894) (xy 12.580624 -514.771894) (xy 12.584655 -514.642328) (xy 12.596734 -514.513264)
			(xy 12.616813 -514.3852) (xy 12.644815 -514.258633) (xy 12.680632 -514.13405) (xy 12.724124 -514.011936)
			(xy 12.775124 -513.892762) (xy 12.833435 -513.776989) (xy 12.89883 -513.665065) (xy 12.971057 -513.557423)
			(xy 13.049837 -513.45448) (xy 13.134864 -513.356634) (xy 13.225809 -513.264262) (xy 13.322321 -513.177724)
			(xy 13.424027 -513.097353) (xy 13.530533 -513.023461) (xy 13.641426 -512.956333) (xy 13.756278 -512.896229)
			(xy 13.874645 -512.843382) (xy 13.996068 -512.797995) (xy 14.120078 -512.760246) (xy 14.246195 -512.730279)
			(xy 14.373931 -512.70821) (xy 14.502792 -512.694126) (xy 14.632279 -512.68808) (xy 14.761892 -512.690096)
			(xy 14.891128 -512.700166) (xy 15.019489 -512.718251) (xy 15.146477 -512.744281) (xy 15.271601 -512.778156)
			(xy 15.394377 -512.819744) (xy 15.51433 -512.868885) (xy 15.630995 -512.925388) (xy 15.743923 -512.989035)
			(xy 15.852675 -513.059579) (xy 15.956831 -513.136748) (xy 16.055988 -513.220243) (xy 16.149762 -513.309741)
			(xy 16.237791 -513.404896) (xy 16.319734 -513.505339) (xy 16.395273 -513.610682) (xy 16.464118 -513.720518)
			(xy 16.526001 -513.834422) (xy 16.580682 -513.951952) (xy 16.627952 -514.072655) (xy 16.667625 -514.196063)
			(xy 16.69955 -514.321699) (xy 16.723602 -514.449076) (xy 16.739689 -514.577702) (xy 16.747748 -514.70708)
			(xy 16.748252 -514.771894) (xy 16.747748 -514.836708) (xy 16.739689 -514.966086) (xy 16.723602 -515.094712)
			(xy 16.69955 -515.222089) (xy 16.667625 -515.347725) (xy 16.627952 -515.471133) (xy 16.580682 -515.591836)
			(xy 16.526001 -515.709366) (xy 16.464118 -515.82327) (xy 16.395273 -515.933106) (xy 16.319734 -516.038449)
			(xy 16.237791 -516.138892) (xy 16.149762 -516.234047) (xy 16.055988 -516.323545) (xy 15.956831 -516.40704)
			(xy 15.852675 -516.484209) (xy 15.743923 -516.554753) (xy 15.630995 -516.6184) (xy 15.51433 -516.674903)
			(xy 15.394377 -516.724044) (xy 15.271601 -516.765632) (xy 15.146477 -516.799507) (xy 15.019489 -516.825537)
			(xy 14.891128 -516.843622) (xy 14.761892 -516.853692) (xy 14.632279 -516.855708) (xy 14.502792 -516.849662)
			(xy 14.373931 -516.835578) (xy 14.246195 -516.813509) (xy 14.120078 -516.783542) (xy 13.996068 -516.745793)
			(xy 13.874645 -516.700406) (xy 13.756278 -516.647559) (xy 13.641426 -516.587455) (xy 13.530533 -516.520327)
			(xy 13.424027 -516.446435) (xy 13.322321 -516.366064) (xy 13.225809 -516.279526) (xy 13.134864 -516.187154)
			(xy 13.049837 -516.089308) (xy 12.971057 -515.986365) (xy 12.89883 -515.878723) (xy 12.833435 -515.766799)
			(xy 12.775124 -515.651026) (xy 12.724124 -515.531852) (xy 12.680632 -515.409738) (xy 12.644815 -515.285155)
			(xy 12.616813 -515.158588) (xy 12.596734 -515.030524) (xy 12.584655 -514.90146) (xy 12.580624 -514.771894)
			(xy 5.318252 -514.771894) (xy 5.317748 -514.836708) (xy 5.309689 -514.966086) (xy 5.293602 -515.094712)
			(xy 5.26955 -515.222089) (xy 5.237625 -515.347725) (xy 5.197952 -515.471133) (xy 5.150682 -515.591836)
			(xy 5.096001 -515.709366) (xy 5.034118 -515.82327) (xy 4.965273 -515.933106) (xy 4.889734 -516.038449)
			(xy 4.807791 -516.138892) (xy 4.719762 -516.234047) (xy 4.625988 -516.323545) (xy 4.526831 -516.40704)
			(xy 4.422675 -516.484209) (xy 4.313923 -516.554753) (xy 4.200995 -516.6184) (xy 4.08433 -516.674903)
			(xy 3.964377 -516.724044) (xy 3.841601 -516.765632) (xy 3.716477 -516.799507) (xy 3.589489 -516.825537)
			(xy 3.461128 -516.843622) (xy 3.331892 -516.853692) (xy 3.202279 -516.855708) (xy 3.072792 -516.849662)
			(xy 2.943931 -516.835578) (xy 2.816195 -516.813509) (xy 2.690078 -516.783542) (xy 2.566068 -516.745793)
			(xy 2.444645 -516.700406) (xy 2.326278 -516.647559) (xy 2.211426 -516.587455) (xy 2.100533 -516.520327)
			(xy 1.994027 -516.446435) (xy 1.892321 -516.366064) (xy 1.795809 -516.279526) (xy 1.704864 -516.187154)
			(xy 1.619837 -516.089308) (xy 1.541057 -515.986365) (xy 1.46883 -515.878723) (xy 1.403435 -515.766799)
			(xy 1.345124 -515.651026) (xy 1.294124 -515.531852) (xy 1.250632 -515.409738) (xy 1.214815 -515.285155)
			(xy 1.186813 -515.158588) (xy 1.166734 -515.030524) (xy 1.154655 -514.90146) (xy 1.150624 -514.771894)
			(xy 0.509016 -514.771894) (xy 0.509016 -519.049762) (xy 75.486773 -519.049762) (xy 75.490798 -518.90757)
			(xy 75.502861 -518.765834) (xy 75.522924 -518.625008) (xy 75.550922 -518.485542) (xy 75.586766 -518.347883)
			(xy 75.63034 -518.212473) (xy 75.681505 -518.079745) (xy 75.740098 -517.950124) (xy 75.805929 -517.824026)
			(xy 75.87879 -517.701854) (xy 75.958445 -517.584) (xy 76.044641 -517.470841) (xy 76.1371 -517.362739)
			(xy 76.235528 -517.260042) (xy 76.339607 -517.163078) (xy 76.449006 -517.072158) (xy 76.563374 -516.987572)
			(xy 76.682343 -516.909592) (xy 76.805534 -516.838468) (xy 76.932551 -516.774427) (xy 77.062988 -516.717675)
			(xy 77.196427 -516.668393) (xy 77.33244 -516.626739) (xy 77.470592 -516.592847) (xy 77.610441 -516.566826)
			(xy 77.751537 -516.548758) (xy 77.893429 -516.538701) (xy 78.035664 -516.536688) (xy 78.177784 -516.542725)
			(xy 78.319335 -516.556793) (xy 78.459864 -516.578847) (xy 78.598919 -516.608816) (xy 78.736057 -516.646604)
			(xy 78.870837 -516.69209) (xy 79.002828 -516.745128) (xy 79.131607 -516.805549) (xy 79.256761 -516.873158)
			(xy 79.377889 -516.94774) (xy 79.494605 -517.029056) (xy 79.606533 -517.116844) (xy 79.713315 -517.210824)
			(xy 79.814609 -517.310694) (xy 79.91009 -517.416136) (xy 79.999454 -517.52681) (xy 80.082412 -517.642363)
			(xy 80.158701 -517.762424) (xy 80.228075 -517.886609) (xy 80.290312 -518.01452) (xy 80.345213 -518.145747)
			(xy 80.392601 -518.27987) (xy 80.432326 -518.416459) (xy 80.464259 -518.555077) (xy 80.4883 -518.695279)
			(xy 80.504369 -518.836617) (xy 80.512417 -518.978638) (xy 80.51292 -519.049762) (xy 80.512417 -519.120886)
			(xy 80.504369 -519.262907) (xy 80.4883 -519.404245) (xy 80.464259 -519.544447) (xy 80.432326 -519.683065)
			(xy 80.392601 -519.819654) (xy 80.345213 -519.953777) (xy 80.290312 -520.085004) (xy 80.228075 -520.212915)
			(xy 80.158701 -520.3371) (xy 80.082412 -520.457161) (xy 79.999454 -520.572714) (xy 79.91009 -520.683388)
			(xy 79.814609 -520.78883) (xy 79.713315 -520.8887) (xy 79.606533 -520.98268) (xy 79.494605 -521.070468)
			(xy 79.377889 -521.151784) (xy 79.256761 -521.226366) (xy 79.131607 -521.293975) (xy 79.002828 -521.354396)
			(xy 78.870837 -521.407434) (xy 78.736057 -521.45292) (xy 78.598919 -521.490708) (xy 78.459864 -521.520677)
			(xy 78.319335 -521.542731) (xy 78.177784 -521.556799) (xy 78.035664 -521.562836) (xy 77.893429 -521.560823)
			(xy 77.751537 -521.550766) (xy 77.610441 -521.532698) (xy 77.470592 -521.506677) (xy 77.33244 -521.472785)
			(xy 77.196427 -521.431131) (xy 77.062988 -521.381849) (xy 76.932551 -521.325097) (xy 76.805534 -521.261056)
			(xy 76.682343 -521.189932) (xy 76.563374 -521.111952) (xy 76.449006 -521.027366) (xy 76.339607 -520.936446)
			(xy 76.235528 -520.839482) (xy 76.1371 -520.736785) (xy 76.044641 -520.628683) (xy 75.958445 -520.515524)
			(xy 75.87879 -520.39767) (xy 75.805929 -520.275498) (xy 75.740098 -520.1494) (xy 75.681505 -520.019779)
			(xy 75.63034 -519.887051) (xy 75.586766 -519.751641) (xy 75.550922 -519.613982) (xy 75.522924 -519.474516)
			(xy 75.502861 -519.33369) (xy 75.490798 -519.191954) (xy 75.486773 -519.049762) (xy 0.509016 -519.049762)
			(xy 0.509016 -524.500094) (xy 0.509529 -524.54588) (xy 0.517978 -524.637062) (xy 0.534804 -524.727075)
			(xy 0.559864 -524.815152) (xy 0.592944 -524.900541) (xy 0.633761 -524.982513) (xy 0.681968 -525.06037)
			(xy 0.737153 -525.133446) (xy 0.798845 -525.201119) (xy 0.866518 -525.262811) (xy 0.939594 -525.317996)
			(xy 1.017451 -525.366203) (xy 1.099423 -525.40702) (xy 1.184812 -525.4401) (xy 1.272889 -525.46516)
			(xy 1.362902 -525.481986) (xy 1.454084 -525.490435) (xy 1.49987 -525.490948) (xy 23.50008 -525.490948)
			(xy 23.563202 -525.491433) (xy 23.689196 -525.499359) (xy 23.814444 -525.515182) (xy 23.93845 -525.538839)
			(xy 24.060727 -525.570236) (xy 24.180791 -525.60925) (xy 24.298167 -525.655726) (xy 24.412394 -525.709482)
			(xy 24.523019 -525.770304) (xy 24.629607 -525.837954) (xy 24.731736 -525.912163) (xy 24.829004 -525.992639)
			(xy 24.921025 -526.079064) (xy 25.007438 -526.171097) (xy 25.087902 -526.268376) (xy 25.162097 -526.370515)
			(xy 25.229732 -526.477111) (xy 25.29054 -526.587745) (xy 25.34428 -526.701979) (xy 25.390741 -526.819362)
			(xy 25.429739 -526.93943) (xy 25.46112 -527.061711) (xy 25.48476 -527.185721) (xy 25.500566 -527.310971)
			(xy 25.508475 -527.436966) (xy 25.508966 -527.500088) (xy 25.508966 -528.500086) (xy 25.509507 -528.545875)
			(xy 25.517982 -528.637061) (xy 25.534832 -528.727076) (xy 25.559914 -528.815153) (xy 25.593014 -528.90054)
			(xy 25.633851 -528.98251) (xy 25.682074 -529.060363) (xy 25.737274 -529.133435) (xy 25.79898 -529.201104)
			(xy 25.866665 -529.262792) (xy 25.939752 -529.317973) (xy 26.017618 -529.366176) (xy 26.099598 -529.406991)
			(xy 26.184994 -529.440069) (xy 26.273077 -529.465128) (xy 26.363097 -529.481954) (xy 26.454285 -529.490405)
			(xy 26.500074 -529.49094)
		)
		(stroke
			(width 0)
			(type solid)
		)
		(fill yes)
		(layer "In6.Cu")
		(net "GND")
	)
	(gr_arc
		(start 1.500124 -3.999992)
		(mid 0.439376 -4.439368)
		(end 0 -5.500116)
		(stroke
			(width 1.016)
			(type default)
		)
		(layer "In6.Cu")
	)
	(gr_line
		(start 1.500124 -3.999992)
		(end 23.50008 -3.999992)
		(stroke
			(width 1.016)
			(type default)
		)
		(layer "In6.Cu")
	)
	(gr_line
		(start 23.50008 -525.999964)
		(end 1.500124 -525.999964)
		(stroke
			(width 1.016)
			(type default)
		)
		(layer "In6.Cu")
	)
	(gr_arc
		(start 23.50008 -3.999992)
		(mid 24.560648 -3.56069)
		(end 24.99995 -2.500122)
		(stroke
			(width 1.016)
			(type default)
		)
		(layer "In6.Cu")
	)
	(gr_line
		(start 24.99995 -528.500086)
		(end 24.99995 -527.500088)
		(stroke
			(width 1.016)
			(type default)
		)
		(layer "In6.Cu")
	)
	(gr_arc
		(start 24.99995 -528.500086)
		(mid 25.439426 -529.560658)
		(end 26.500074 -529.999956)
		(stroke
			(width 1.016)
			(type default)
		)
		(layer "In6.Cu")
	)
	(gr_arc
		(start 24.99995 -527.500088)
		(mid 24.560738 -526.439356)
		(end 23.50008 -525.999964)
		(stroke
			(width 1.016)
			(type default)
		)
		(layer "In6.Cu")
	)
	(gr_line
		(start 24.99995 -2.500122)
		(end 24.99995 -1.500124)
		(stroke
			(width 1.016)
			(type default)
		)
		(layer "In6.Cu")
	)
	(gr_arc
		(start 26.500074 0)
		(mid 25.439325 -0.439375)
		(end 24.99995 -1.500124)
		(stroke
			(width 1.016)
			(type default)
		)
		(layer "In6.Cu")
	)
	(gr_line
		(start 26.500074 0)
		(end 101.000052 0)
		(stroke
			(width 1.016)
			(type default)
		)
		(layer "In6.Cu")
	)
	(gr_line
		(start 93.918024 -78.298802)
		(end 93.980762 -78.298802)
		(stroke
			(width 0.508)
			(type default)
		)
		(layer "In6.Cu")
	)
	(gr_line
		(start 93.940884 -78.321662)
		(end 93.918024 -78.298802)
		(stroke
			(width 0.508)
			(type default)
		)
		(layer "In6.Cu")
	)
	(gr_circle
		(center 93.957902 -78.321662)
		(end 94.40164 -78.321662)
		(stroke
			(width 0.508)
			(type default)
		)
		(fill no)
		(layer "In6.Cu")
	)
	(gr_circle
		(center 93.963744 -78.367128)
		(end 95.62973 -78.367128)
		(stroke
			(width 1.27)
			(type default)
		)
		(fill no)
		(layer "In6.Cu")
	)
	(gr_circle
		(center 93.97492 -78.338426)
		(end 94.87662 -78.338426)
		(stroke
			(width 0.508)
			(type default)
		)
		(fill no)
		(layer "In6.Cu")
	)
	(gr_line
		(start 93.980762 -78.298802)
		(end 94.003622 -78.321662)
		(stroke
			(width 0.508)
			(type default)
		)
		(layer "In6.Cu")
	)
	(gr_circle
		(center 93.999812 -78.300072)
		(end 96.60001 -78.300072)
		(stroke
			(width 1.016)
			(type default)
		)
		(fill no)
		(layer "In6.Cu")
	)
	(gr_line
		(start 94.003622 -78.321662)
		(end 93.940884 -78.321662)
		(stroke
			(width 0.508)
			(type default)
		)
		(layer "In6.Cu")
	)
	(gr_circle
		(center 94.055438 -478.309432)
		(end 96.208596 -478.309432)
		(stroke
			(width 1.27)
			(type default)
		)
		(fill no)
		(layer "In6.Cu")
	)
	(gr_circle
		(center 94.101158 -478.241106)
		(end 95.238062 -478.241106)
		(stroke
			(width 1.27)
			(type default)
		)
		(fill no)
		(layer "In6.Cu")
	)
	(gr_line
		(start 94.169484 -478.332292)
		(end 94.169484 -478.286826)
		(stroke
			(width 1.27)
			(type default)
		)
		(layer "In6.Cu")
	)
	(gr_line
		(start 94.169484 -478.286826)
		(end 94.032578 -478.14992)
		(stroke
			(width 1.27)
			(type default)
		)
		(layer "In6.Cu")
	)
	(gr_line
		(start 101.000052 -529.999956)
		(end 26.500074 -529.999956)
		(stroke
			(width 1.016)
			(type default)
		)
		(layer "In6.Cu")
	)
	(gr_arc
		(start 101.000052 -529.999956)
		(mid 102.41428 -529.414185)
		(end 103.000048 -527.99996)
		(stroke
			(width 1.016)
			(type default)
		)
		(layer "In6.Cu")
	)
	(gr_arc
		(start 103.000048 -1.999996)
		(mid 102.414258 -0.585805)
		(end 101.000052 0)
		(stroke
			(width 1.016)
			(type default)
		)
		(layer "In6.Cu")
	)
	(gr_line
		(start 103.000048 -1.999996)
		(end 103.000048 -527.99996)
		(stroke
			(width 1.016)
			(type default)
		)
		(layer "In6.Cu")
	)
	(gr_line
		(start 0 -524.500094)
		(end 0 -5.500116)
		(stroke
			(width 0.05)
			(type default)
		)
		(layer "Edge.Cuts")
	)
	(gr_arc
		(start 0 -524.500094)
		(mid 0.439393 -525.560749)
		(end 1.500124 -525.999964)
		(stroke
			(width 0.05)
			(type default)
		)
		(layer "Edge.Cuts")
	)
	(gr_arc
		(start 1.500124 -3.999992)
		(mid 0.439376 -4.439368)
		(end 0 -5.500116)
		(stroke
			(width 0.05)
			(type default)
		)
		(layer "Edge.Cuts")
	)
	(gr_line
		(start 1.500124 -3.999992)
		(end 23.50008 -3.999992)
		(stroke
			(width 0.05)
			(type default)
		)
		(layer "Edge.Cuts")
	)
	(gr_line
		(start 23.50008 -525.999964)
		(end 1.500124 -525.999964)
		(stroke
			(width 0.05)
			(type default)
		)
		(layer "Edge.Cuts")
	)
	(gr_arc
		(start 23.50008 -3.999992)
		(mid 24.560648 -3.56069)
		(end 24.99995 -2.500122)
		(stroke
			(width 0.05)
			(type default)
		)
		(layer "Edge.Cuts")
	)
	(gr_line
		(start 24.99995 -528.500086)
		(end 24.99995 -527.500088)
		(stroke
			(width 0.05)
			(type default)
		)
		(layer "Edge.Cuts")
	)
	(gr_arc
		(start 24.99995 -528.500086)
		(mid 25.439426 -529.560658)
		(end 26.500074 -529.999956)
		(stroke
			(width 0.05)
			(type default)
		)
		(layer "Edge.Cuts")
	)
	(gr_arc
		(start 24.99995 -527.500088)
		(mid 24.560738 -526.439356)
		(end 23.50008 -525.999964)
		(stroke
			(width 0.05)
			(type default)
		)
		(layer "Edge.Cuts")
	)
	(gr_line
		(start 24.99995 -2.500122)
		(end 24.99995 -1.500124)
		(stroke
			(width 0.05)
			(type default)
		)
		(layer "Edge.Cuts")
	)
	(gr_arc
		(start 26.500074 0)
		(mid 25.439325 -0.439375)
		(end 24.99995 -1.500124)
		(stroke
			(width 0.05)
			(type default)
		)
		(layer "Edge.Cuts")
	)
	(gr_line
		(start 26.500074 0)
		(end 101.000052 0)
		(stroke
			(width 0.05)
			(type default)
		)
		(layer "Edge.Cuts")
	)
	(gr_arc
		(start 75.3999 -478.799906)
		(mid 78.000098 -481.400104)
		(end 80.600042 -478.799906)
		(stroke
			(width 0.05)
			(type default)
		)
		(layer "Edge.Cuts")
	)
	(gr_line
		(start 75.3999 -477.799908)
		(end 75.3999 -478.799906)
		(stroke
			(width 0.05)
			(type default)
		)
		(layer "Edge.Cuts")
	)
	(gr_line
		(start 80.600042 -478.799906)
		(end 80.600042 -477.799908)
		(stroke
			(width 0.05)
			(type default)
		)
		(layer "Edge.Cuts")
	)
	(gr_arc
		(start 80.600042 -477.799908)
		(mid 78.000098 -475.199964)
		(end 75.3999 -477.799908)
		(stroke
			(width 0.05)
			(type default)
		)
		(layer "Edge.Cuts")
	)
	(gr_line
		(start 101.000052 -529.999956)
		(end 26.500074 -529.999956)
		(stroke
			(width 0.05)
			(type default)
		)
		(layer "Edge.Cuts")
	)
	(gr_arc
		(start 101.000052 -529.999956)
		(mid 102.41428 -529.414185)
		(end 103.000048 -527.99996)
		(stroke
			(width 0.05)
			(type default)
		)
		(layer "Edge.Cuts")
	)
	(gr_arc
		(start 103.000048 -1.999996)
		(mid 102.414258 -0.585805)
		(end 101.000052 0)
		(stroke
			(width 0.05)
			(type default)
		)
		(layer "Edge.Cuts")
	)
	(gr_line
		(start 103.000048 -1.999996)
		(end 103.000048 -527.99996)
		(stroke
			(width 0.05)
			(type default)
		)
		(layer "Edge.Cuts")
	)
	(segment
		(start 2.81559 -397.434054)
		(end 2.969768 -397.588232)
		(width 0.1524)
		(layer "F.Cu")
		(net "N42132933")
	)
	(segment
		(start 2.81559 -395.844014)
		(end 2.81559 -397.434054)
		(width 0.1524)
		(layer "F.Cu")
		(net "N42132933")
	)
	(segment
		(start 2.969768 -397.588232)
		(end 2.969768 -399.239994)
		(width 0.1524)
		(layer "F.Cu")
		(net "N42132933")
	)
	(segment
		(start 15.56512 -396.021052)
		(end 15.56512 -399.235422)
		(width 0.1524)
		(layer "F.Cu")
		(net "N42132358")
	)
	(segment
		(start 15.56512 -399.235422)
		(end 15.569692 -399.239994)
		(width 0.1524)
		(layer "F.Cu")
		(net "N42132358")
	)
	(segment
		(start 4.186936 -395.810486)
		(end 4.186936 -397.9672)
		(width 0.1524)
		(layer "F.Cu")
		(net "N42132545")
	)
	(segment
		(start 4.186936 -397.9672)
		(end 5.45973 -399.239994)
		(width 0.1524)
		(layer "F.Cu")
		(net "N42132545")
	)
	(segment
		(start 2.965958 -142.213838)
		(end 2.969768 -142.210028)
		(width 0.1524)
		(layer "F.Cu")
		(net "N42130542")
	)
	(segment
		(start 2.965958 -145.494248)
		(end 2.965958 -142.213838)
		(width 0.1524)
		(layer "F.Cu")
		(net "N42130542")
	)
	(segment
		(start 14.9225 -145.761964)
		(end 13.07973 -143.919194)
		(width 0.1524)
		(layer "F.Cu")
		(net "N42126673")
	)
	(segment
		(start 13.07973 -143.919194)
		(end 13.07973 -142.210028)
		(width 0.1524)
		(layer "F.Cu")
		(net "N42126673")
	)
	(segment
		(start 15.569692 -145.13814)
		(end 15.569692 -142.210028)
		(width 0.1524)
		(layer "F.Cu")
		(net "N42126764")
	)
	(segment
		(start 16.21028 -145.778728)
		(end 15.569692 -145.13814)
		(width 0.1524)
		(layer "F.Cu")
		(net "N42126764")
	)
	(segment
		(start 5.980938 -103.629714)
		(end 9.501124 -100.109528)
		(width 0.127)
		(layer "In5.Cu")
		(net "UART_DSR_P5_L_N")
	)
	(segment
		(start 8.03148 -193.540634)
		(end 9.234678 -193.540634)
		(width 0.127)
		(layer "In5.Cu")
		(net "UART_DSR_P5_L_N")
	)
	(segment
		(start 11.609832 -191.16548)
		(end 11.609832 -171.71416)
		(width 0.127)
		(layer "In5.Cu")
		(net "UART_DSR_P5_L_N")
	)
	(segment
		(start 3.948938 -207.670654)
		(end 5.383784 -206.235808)
		(width 0.127)
		(layer "In5.Cu")
		(net "UART_DSR_P5_L_N")
	)
	(segment
		(start 8.590026 -114.99596)
		(end 3.099054 -109.504988)
		(width 0.127)
		(layer "In5.Cu")
		(net "UART_DSR_P5_L_N")
	)
	(segment
		(start 17.634458 -129.129028)
		(end 16.49349 -129.129028)
		(width 0.127)
		(layer "In5.Cu")
		(net "UART_DSR_P5_L_N")
	)
	(segment
		(start 8.590026 -121.225564)
		(end 8.590026 -114.99596)
		(width 0.127)
		(layer "In5.Cu")
		(net "UART_DSR_P5_L_N")
	)
	(segment
		(start 9.501124 -64.784732)
		(end 12.12469 -62.161166)
		(width 0.127)
		(layer "In5.Cu")
		(net "UART_DSR_P5_L_N")
	)
	(segment
		(start 11.609832 -171.71416)
		(end 12.290552 -171.03344)
		(width 0.127)
		(layer "In5.Cu")
		(net "UART_DSR_P5_L_N")
	)
	(segment
		(start 16.49349 -129.129028)
		(end 8.590026 -121.225564)
		(width 0.127)
		(layer "In5.Cu")
		(net "UART_DSR_P5_L_N")
	)
	(segment
		(start 7.154418 -194.417696)
		(end 8.03148 -193.540634)
		(width 0.127)
		(layer "In5.Cu")
		(net "UART_DSR_P5_L_N")
	)
	(segment
		(start 12.290552 -171.03344)
		(end 21.074888 -162.24885)
		(width 0.127)
		(layer "In5.Cu")
		(net "UART_DSR_P5_L_N")
	)
	(segment
		(start 12.12469 -62.161166)
		(end 12.12469 -59.387994)
		(width 0.127)
		(layer "In5.Cu")
		(net "UART_DSR_P5_L_N")
	)
	(segment
		(start 3.099054 -104.957372)
		(end 4.426712 -103.629714)
		(width 0.127)
		(layer "In5.Cu")
		(net "UART_DSR_P5_L_N")
	)
	(segment
		(start 6.12648 -194.417696)
		(end 7.154418 -194.417696)
		(width 0.127)
		(layer "In5.Cu")
		(net "UART_DSR_P5_L_N")
	)
	(segment
		(start 9.501124 -100.109528)
		(end 9.501124 -64.784732)
		(width 0.127)
		(layer "In5.Cu")
		(net "UART_DSR_P5_L_N")
	)
	(segment
		(start 4.426712 -103.629714)
		(end 5.980938 -103.629714)
		(width 0.127)
		(layer "In5.Cu")
		(net "UART_DSR_P5_L_N")
	)
	(segment
		(start 3.099054 -109.504988)
		(end 3.099054 -104.957372)
		(width 0.127)
		(layer "In5.Cu")
		(net "UART_DSR_P5_L_N")
	)
	(segment
		(start 5.383784 -206.235808)
		(end 5.383784 -195.160392)
		(width 0.127)
		(layer "In5.Cu")
		(net "UART_DSR_P5_L_N")
	)
	(segment
		(start 5.383784 -195.160392)
		(end 6.12648 -194.417696)
		(width 0.127)
		(layer "In5.Cu")
		(net "UART_DSR_P5_L_N")
	)
	(segment
		(start 21.074888 -162.24885)
		(end 21.074888 -132.569458)
		(width 0.127)
		(layer "In5.Cu")
		(net "UART_DSR_P5_L_N")
	)
	(segment
		(start 9.234678 -193.540634)
		(end 11.609832 -191.16548)
		(width 0.127)
		(layer "In5.Cu")
		(net "UART_DSR_P5_L_N")
	)
	(segment
		(start 21.074888 -132.569458)
		(end 17.634458 -129.129028)
		(width 0.127)
		(layer "In5.Cu")
		(net "UART_DSR_P5_L_N")
	)
	(segment
		(start 7.526528 -103.561896)
		(end 5.77469 -105.313734)
		(width 0.1524)
		(layer "B.Cu")
		(net "UART_DSR_P6_L_N")
	)
	(segment
		(start 13.331698 -103.561896)
		(end 7.526528 -103.561896)
		(width 0.1524)
		(layer "B.Cu")
		(net "UART_DSR_P6_L_N")
	)
	(segment
		(start 8.496046 -115.494054)
		(end 14.837156 -109.152944)
		(width 0.1524)
		(layer "B.Cu")
		(net "UART_DSR_P6_L_N")
	)
	(segment
		(start 14.837156 -109.152944)
		(end 14.837156 -105.067354)
		(width 0.1524)
		(layer "B.Cu")
		(net "UART_DSR_P6_L_N")
	)
	(segment
		(start 19.233388 -194.521836)
		(end 19.233388 -142.848584)
		(width 0.1524)
		(layer "B.Cu")
		(net "UART_DSR_P6_L_N")
	)
	(segment
		(start 5.77469 -105.313734)
		(end 5.77469 -108.161836)
		(width 0.1524)
		(layer "B.Cu")
		(net "UART_DSR_P6_L_N")
	)
	(segment
		(start 8.496046 -120.38965)
		(end 8.496046 -115.494054)
		(width 0.1524)
		(layer "B.Cu")
		(net "UART_DSR_P6_L_N")
	)
	(segment
		(start 10.621518 -203.133706)
		(end 19.233388 -194.521836)
		(width 0.1524)
		(layer "B.Cu")
		(net "UART_DSR_P6_L_N")
	)
	(segment
		(start 6.448806 -207.670654)
		(end 8.67918 -207.670654)
		(width 0.1524)
		(layer "B.Cu")
		(net "UART_DSR_P6_L_N")
	)
	(segment
		(start 19.233388 -142.848584)
		(end 21.052028 -141.029944)
		(width 0.1524)
		(layer "B.Cu")
		(net "UART_DSR_P6_L_N")
	)
	(segment
		(start 21.052028 -132.945632)
		(end 8.496046 -120.38965)
		(width 0.1524)
		(layer "B.Cu")
		(net "UART_DSR_P6_L_N")
	)
	(segment
		(start 10.621518 -205.728316)
		(end 10.621518 -203.133706)
		(width 0.1524)
		(layer "B.Cu")
		(net "UART_DSR_P6_L_N")
	)
	(segment
		(start 21.052028 -141.029944)
		(end 21.052028 -132.945632)
		(width 0.1524)
		(layer "B.Cu")
		(net "UART_DSR_P6_L_N")
	)
	(segment
		(start 14.837156 -105.067354)
		(end 13.331698 -103.561896)
		(width 0.1524)
		(layer "B.Cu")
		(net "UART_DSR_P6_L_N")
	)
	(segment
		(start 8.67918 -207.670654)
		(end 10.621518 -205.728316)
		(width 0.1524)
		(layer "B.Cu")
		(net "UART_DSR_P6_L_N")
	)
	(segment
		(start 13.853922 -330.880974)
		(end 13.853922 -332.48473)
		(width 0.1524)
		(layer "F.Cu")
		(net "FRU_A0")
	)
	(segment
		(start 13.853922 -332.48473)
		(end 14.443964 -333.074772)
		(width 0.1524)
		(layer "F.Cu")
		(net "FRU_A0")
	)
	(segment
		(start 13.853922 -330.880974)
		(end 12.784328 -330.880974)
		(width 0.1524)
		(layer "F.Cu")
		(net "FRU_A0")
	)
	(segment
		(start 14.443964 -333.074772)
		(end 14.443964 -334.086962)
		(width 0.1524)
		(layer "F.Cu")
		(net "FRU_A0")
	)
	(segment
		(start 12.784328 -330.880974)
		(end 12.784074 -330.88072)
		(width 0.1524)
		(layer "F.Cu")
		(net "FRU_A0")
	)
	(via
		(at 13.853922 -332.48473)
		(size 0.508)
		(drill 0.254)
		(layers "F.Cu" "B.Cu")
		(net "FRU_A0")
	)
	(segment
		(start 17.162272 -332.188566)
		(end 16.983964 -332.366874)
		(width 0.1524)
		(layer "F.Cu")
		(net "FRU_A2")
	)
	(segment
		(start 16.983964 -332.366874)
		(end 16.983964 -334.086962)
		(width 0.1524)
		(layer "F.Cu")
		(net "FRU_A2")
	)
	(segment
		(start 17.162526 -330.85532)
		(end 17.162272 -330.855574)
		(width 0.1524)
		(layer "F.Cu")
		(net "FRU_A2")
	)
	(segment
		(start 17.162272 -330.855574)
		(end 17.162272 -332.188566)
		(width 0.1524)
		(layer "F.Cu")
		(net "FRU_A2")
	)
	(segment
		(start 18.264886 -330.85532)
		(end 17.162526 -330.85532)
		(width 0.1524)
		(layer "F.Cu")
		(net "FRU_A2")
	)
	(via
		(at 17.162272 -332.188566)
		(size 0.508)
		(drill 0.254)
		(layers "F.Cu" "B.Cu")
		(net "FRU_A2")
	)
	(segment
		(start 14.181074 -340.894416)
		(end 13.451332 -340.164674)
		(width 0.1524)
		(layer "F.Cu")
		(net "FRU_WP")
	)
	(segment
		(start 15.713964 -339.370162)
		(end 15.713964 -340.894416)
		(width 0.1524)
		(layer "F.Cu")
		(net "FRU_WP")
	)
	(segment
		(start 15.713964 -340.894416)
		(end 14.181074 -340.894416)
		(width 0.1524)
		(layer "F.Cu")
		(net "FRU_WP")
	)
	(via
		(at 15.713964 -340.894416)
		(size 0.508)
		(drill 0.254)
		(layers "F.Cu" "B.Cu")
		(net "FRU_WP")
	)
	(segment
		(start 15.713964 -332.53426)
		(end 16.017494 -332.23073)
		(width 0.1524)
		(layer "F.Cu")
		(net "FRU_A1")
	)
	(segment
		(start 16.017494 -332.23073)
		(end 16.017494 -330.897484)
		(width 0.1524)
		(layer "F.Cu")
		(net "FRU_A1")
	)
	(segment
		(start 16.017494 -330.897484)
		(end 14.923008 -330.897484)
		(width 0.1524)
		(layer "F.Cu")
		(net "FRU_A1")
	)
	(segment
		(start 15.713964 -334.086962)
		(end 15.713964 -332.53426)
		(width 0.1524)
		(layer "F.Cu")
		(net "FRU_A1")
	)
	(via
		(at 15.713964 -332.53426)
		(size 0.508)
		(drill 0.254)
		(layers "F.Cu" "B.Cu")
		(net "FRU_A1")
	)
	(segment
		(start 9.637776 -61.635386)
		(end 9.637776 -63.120016)
		(width 0.127)
		(layer "In5.Cu")
		(net "UART_CTS_P5_L_N")
	)
	(segment
		(start 4.711954 -193.601594)
		(end 4.711954 -202.907646)
		(width 0.127)
		(layer "In5.Cu")
		(net "UART_CTS_P5_L_N")
	)
	(segment
		(start 20.363688 -161.95421)
		(end 11.787632 -170.53052)
		(width 0.127)
		(layer "In5.Cu")
		(net "UART_CTS_P5_L_N")
	)
	(segment
		(start 7.929626 -115.3414)
		(end 7.929626 -121.499376)
		(width 0.127)
		(layer "In5.Cu")
		(net "UART_CTS_P5_L_N")
	)
	(segment
		(start 7.02056 -192.47104)
		(end 5.842508 -192.47104)
		(width 0.127)
		(layer "In5.Cu")
		(net "UART_CTS_P5_L_N")
	)
	(segment
		(start 4.132072 -102.918514)
		(end 2.387854 -104.662732)
		(width 0.127)
		(layer "In5.Cu")
		(net "UART_CTS_P5_L_N")
	)
	(segment
		(start 4.50469 -59.387994)
		(end 6.009894 -57.88279)
		(width 0.127)
		(layer "In5.Cu")
		(net "UART_CTS_P5_L_N")
	)
	(segment
		(start 20.363688 -132.955792)
		(end 20.363688 -161.95421)
		(width 0.127)
		(layer "In5.Cu")
		(net "UART_CTS_P5_L_N")
	)
	(segment
		(start 11.126978 -60.146184)
		(end 9.637776 -61.635386)
		(width 0.127)
		(layer "In5.Cu")
		(net "UART_CTS_P5_L_N")
	)
	(segment
		(start 16.219678 -129.789428)
		(end 17.197324 -129.789428)
		(width 0.127)
		(layer "In5.Cu")
		(net "UART_CTS_P5_L_N")
	)
	(segment
		(start 17.197324 -129.789428)
		(end 20.363688 -132.955792)
		(width 0.127)
		(layer "In5.Cu")
		(net "UART_CTS_P5_L_N")
	)
	(segment
		(start 6.009894 -57.88279)
		(end 10.533888 -57.88279)
		(width 0.127)
		(layer "In5.Cu")
		(net "UART_CTS_P5_L_N")
	)
	(segment
		(start 9.565386 -191.58077)
		(end 7.91083 -191.58077)
		(width 0.127)
		(layer "In5.Cu")
		(net "UART_CTS_P5_L_N")
	)
	(segment
		(start 8.789924 -63.967868)
		(end 8.789924 -99.814888)
		(width 0.127)
		(layer "In5.Cu")
		(net "UART_CTS_P5_L_N")
	)
	(segment
		(start 10.898632 -190.247524)
		(end 9.565386 -191.58077)
		(width 0.127)
		(layer "In5.Cu")
		(net "UART_CTS_P5_L_N")
	)
	(segment
		(start 11.126978 -58.47588)
		(end 11.126978 -60.146184)
		(width 0.127)
		(layer "In5.Cu")
		(net "UART_CTS_P5_L_N")
	)
	(segment
		(start 10.898632 -171.41952)
		(end 10.898632 -190.247524)
		(width 0.127)
		(layer "In5.Cu")
		(net "UART_CTS_P5_L_N")
	)
	(segment
		(start 5.686298 -102.918514)
		(end 4.132072 -102.918514)
		(width 0.127)
		(layer "In5.Cu")
		(net "UART_CTS_P5_L_N")
	)
	(segment
		(start 10.533888 -57.88279)
		(end 11.126978 -58.47588)
		(width 0.127)
		(layer "In5.Cu")
		(net "UART_CTS_P5_L_N")
	)
	(segment
		(start 7.91083 -191.58077)
		(end 7.02056 -192.47104)
		(width 0.127)
		(layer "In5.Cu")
		(net "UART_CTS_P5_L_N")
	)
	(segment
		(start 4.711954 -202.907646)
		(end 3.948938 -203.670662)
		(width 0.127)
		(layer "In5.Cu")
		(net "UART_CTS_P5_L_N")
	)
	(segment
		(start 2.387854 -104.662732)
		(end 2.387854 -109.799628)
		(width 0.127)
		(layer "In5.Cu")
		(net "UART_CTS_P5_L_N")
	)
	(segment
		(start 8.789924 -99.814888)
		(end 5.686298 -102.918514)
		(width 0.127)
		(layer "In5.Cu")
		(net "UART_CTS_P5_L_N")
	)
	(segment
		(start 11.787632 -170.53052)
		(end 10.898632 -171.41952)
		(width 0.127)
		(layer "In5.Cu")
		(net "UART_CTS_P5_L_N")
	)
	(segment
		(start 7.929626 -121.499376)
		(end 16.219678 -129.789428)
		(width 0.127)
		(layer "In5.Cu")
		(net "UART_CTS_P5_L_N")
	)
	(segment
		(start 2.387854 -109.799628)
		(end 7.929626 -115.3414)
		(width 0.127)
		(layer "In5.Cu")
		(net "UART_CTS_P5_L_N")
	)
	(segment
		(start 5.842508 -192.47104)
		(end 4.711954 -193.601594)
		(width 0.127)
		(layer "In5.Cu")
		(net "UART_CTS_P5_L_N")
	)
	(segment
		(start 9.637776 -63.120016)
		(end 8.789924 -63.967868)
		(width 0.127)
		(layer "In5.Cu")
		(net "UART_CTS_P5_L_N")
	)
	(segment
		(start 10.804906 -105.681018)
		(end 10.804906 -105.401872)
		(width 0.1524)
		(layer "B.Cu")
		(net "UART_CTS_P6_L_N")
	)
	(segment
		(start 6.448806 -203.670662)
		(end 8.613902 -203.670662)
		(width 0.1524)
		(layer "B.Cu")
		(net "UART_CTS_P6_L_N")
	)
	(segment
		(start 8.613902 -203.670662)
		(end 9.199118 -203.085446)
		(width 0.1524)
		(layer "B.Cu")
		(net "UART_CTS_P6_L_N")
	)
	(segment
		(start 19.629628 -133.534912)
		(end 7.073646 -120.97893)
		(width 0.1524)
		(layer "B.Cu")
		(net "UART_CTS_P6_L_N")
	)
	(segment
		(start 17.810988 -193.932556)
		(end 17.810988 -142.259304)
		(width 0.1524)
		(layer "B.Cu")
		(net "UART_CTS_P6_L_N")
	)
	(segment
		(start 13.39469 -105.40238)
		(end 13.39469 -108.161836)
		(width 0.1524)
		(layer "B.Cu")
		(net "UART_CTS_P6_L_N")
	)
	(segment
		(start 7.073646 -120.97893)
		(end 7.073646 -114.433858)
		(width 0.1524)
		(layer "B.Cu")
		(net "UART_CTS_P6_L_N")
	)
	(segment
		(start 10.804906 -105.401872)
		(end 11.563858 -104.64292)
		(width 0.1524)
		(layer "B.Cu")
		(net "UART_CTS_P6_L_N")
	)
	(segment
		(start 9.199118 -202.544426)
		(end 17.810988 -193.932556)
		(width 0.1524)
		(layer "B.Cu")
		(net "UART_CTS_P6_L_N")
	)
	(segment
		(start 17.810988 -142.259304)
		(end 19.629628 -140.440664)
		(width 0.1524)
		(layer "B.Cu")
		(net "UART_CTS_P6_L_N")
	)
	(segment
		(start 9.230868 -107.255056)
		(end 10.804906 -105.681018)
		(width 0.1524)
		(layer "B.Cu")
		(net "UART_CTS_P6_L_N")
	)
	(segment
		(start 9.230868 -112.276636)
		(end 9.230868 -107.255056)
		(width 0.1524)
		(layer "B.Cu")
		(net "UART_CTS_P6_L_N")
	)
	(segment
		(start 7.073646 -114.433858)
		(end 9.230868 -112.276636)
		(width 0.1524)
		(layer "B.Cu")
		(net "UART_CTS_P6_L_N")
	)
	(segment
		(start 11.563858 -104.64292)
		(end 12.63523 -104.64292)
		(width 0.1524)
		(layer "B.Cu")
		(net "UART_CTS_P6_L_N")
	)
	(segment
		(start 9.199118 -203.085446)
		(end 9.199118 -202.544426)
		(width 0.1524)
		(layer "B.Cu")
		(net "UART_CTS_P6_L_N")
	)
	(segment
		(start 12.63523 -104.64292)
		(end 13.39469 -105.40238)
		(width 0.1524)
		(layer "B.Cu")
		(net "UART_CTS_P6_L_N")
	)
	(segment
		(start 19.629628 -140.440664)
		(end 19.629628 -133.534912)
		(width 0.1524)
		(layer "B.Cu")
		(net "UART_CTS_P6_L_N")
	)
	(segment
		(start 2.669286 -333.267304)
		(end 1.949958 -332.547976)
		(width 0.127)
		(layer "In5.Cu")
		(net "UART_DSR_RP5_L")
	)
	(segment
		(start 2.669286 -334.895444)
		(end 2.669286 -333.267304)
		(width 0.127)
		(layer "In5.Cu")
		(net "UART_DSR_RP5_L")
	)
	(segment
		(start 7.087362 -339.526372)
		(end 6.141212 -339.526372)
		(width 0.127)
		(layer "In5.Cu")
		(net "UART_DSR_RP5_L")
	)
	(segment
		(start 4.346194 -335.881218)
		(end 3.65506 -335.881218)
		(width 0.127)
		(layer "In5.Cu")
		(net "UART_DSR_RP5_L")
	)
	(segment
		(start 9.171432 -342.816942)
		(end 8.125206 -341.770716)
		(width 0.127)
		(layer "In5.Cu")
		(net "UART_DSR_RP5_L")
	)
	(segment
		(start 3.65506 -335.881218)
		(end 2.669286 -334.895444)
		(width 0.127)
		(layer "In5.Cu")
		(net "UART_DSR_RP5_L")
	)
	(segment
		(start 8.125206 -340.564216)
		(end 7.087362 -339.526372)
		(width 0.127)
		(layer "In5.Cu")
		(net "UART_DSR_RP5_L")
	)
	(segment
		(start 8.125206 -341.770716)
		(end 8.125206 -340.564216)
		(width 0.127)
		(layer "In5.Cu")
		(net "UART_DSR_RP5_L")
	)
	(segment
		(start 4.877308 -338.262468)
		(end 4.877308 -336.412332)
		(width 0.127)
		(layer "In5.Cu")
		(net "UART_DSR_RP5_L")
	)
	(segment
		(start 6.141212 -339.526372)
		(end 4.877308 -338.262468)
		(width 0.127)
		(layer "In5.Cu")
		(net "UART_DSR_RP5_L")
	)
	(segment
		(start 14.893798 -462.173828)
		(end 14.893798 -410.760418)
		(width 0.127)
		(layer "In5.Cu")
		(net "UART_DSR_RP5_L")
	)
	(segment
		(start 5.77469 -493.20323)
		(end 6.706616 -492.271304)
		(width 0.127)
		(layer "In5.Cu")
		(net "UART_DSR_RP5_L")
	)
	(segment
		(start 5.77469 -497.151914)
		(end 5.77469 -493.20323)
		(width 0.127)
		(layer "In5.Cu")
		(net "UART_DSR_RP5_L")
	)
	(segment
		(start 1.949958 -332.547976)
		(end 1.949958 -331.669898)
		(width 0.127)
		(layer "In5.Cu")
		(net "UART_DSR_RP5_L")
	)
	(segment
		(start 8.135366 -404.001986)
		(end 8.135366 -394.458698)
		(width 0.127)
		(layer "In5.Cu")
		(net "UART_DSR_RP5_L")
	)
	(segment
		(start 6.706616 -492.271304)
		(end 6.706616 -470.36101)
		(width 0.127)
		(layer "In5.Cu")
		(net "UART_DSR_RP5_L")
	)
	(segment
		(start 4.877308 -336.412332)
		(end 4.346194 -335.881218)
		(width 0.127)
		(layer "In5.Cu")
		(net "UART_DSR_RP5_L")
	)
	(segment
		(start 6.706616 -470.36101)
		(end 14.893798 -462.173828)
		(width 0.127)
		(layer "In5.Cu")
		(net "UART_DSR_RP5_L")
	)
	(segment
		(start 14.893798 -410.760418)
		(end 8.135366 -404.001986)
		(width 0.127)
		(layer "In5.Cu")
		(net "UART_DSR_RP5_L")
	)
	(segment
		(start 9.171432 -377.894342)
		(end 9.171432 -342.816942)
		(width 0.127)
		(layer "In5.Cu")
		(net "UART_DSR_RP5_L")
	)
	(segment
		(start 6.767322 -380.298452)
		(end 9.171432 -377.894342)
		(width 0.127)
		(layer "In5.Cu")
		(net "UART_DSR_RP5_L")
	)
	(segment
		(start 8.135366 -394.458698)
		(end 6.767322 -393.090654)
		(width 0.127)
		(layer "In5.Cu")
		(net "UART_DSR_RP5_L")
	)
	(segment
		(start 6.767322 -393.090654)
		(end 6.767322 -380.298452)
		(width 0.127)
		(layer "In5.Cu")
		(net "UART_DSR_RP5_L")
	)
	(segment
		(start 8.138922 -491.180882)
		(end 8.138922 -470.797128)
		(width 0.127)
		(layer "In5.Cu")
		(net "UART_CTS_RP5_L_N")
	)
	(segment
		(start 16.214598 -462.721452)
		(end 16.214598 -410.212794)
		(width 0.127)
		(layer "In5.Cu")
		(net "UART_CTS_RP5_L_N")
	)
	(segment
		(start 5.536692 -333.925164)
		(end 5.048504 -333.436976)
		(width 0.127)
		(layer "In5.Cu")
		(net "UART_CTS_RP5_L_N")
	)
	(segment
		(start 6.276086 -335.490566)
		(end 5.536692 -334.751172)
		(width 0.127)
		(layer "In5.Cu")
		(net "UART_CTS_RP5_L_N")
	)
	(segment
		(start 4.280154 -329.368404)
		(end 3.648456 -329.368404)
		(width 0.127)
		(layer "In5.Cu")
		(net "UART_CTS_RP5_L_N")
	)
	(segment
		(start 8.088122 -391.738866)
		(end 8.088122 -380.846076)
		(width 0.127)
		(layer "In5.Cu")
		(net "UART_CTS_RP5_L_N")
	)
	(segment
		(start 10.663428 -494.420652)
		(end 10.663428 -493.705388)
		(width 0.127)
		(layer "In5.Cu")
		(net "UART_CTS_RP5_L_N")
	)
	(segment
		(start 16.214598 -410.212794)
		(end 10.259314 -404.25751)
		(width 0.127)
		(layer "In5.Cu")
		(net "UART_CTS_RP5_L_N")
	)
	(segment
		(start 5.536692 -334.751172)
		(end 5.536692 -333.925164)
		(width 0.127)
		(layer "In5.Cu")
		(net "UART_CTS_RP5_L_N")
	)
	(segment
		(start 7.26948 -335.490566)
		(end 6.276086 -335.490566)
		(width 0.127)
		(layer "In5.Cu")
		(net "UART_CTS_RP5_L_N")
	)
	(segment
		(start 10.259314 -404.25751)
		(end 10.259314 -393.910058)
		(width 0.127)
		(layer "In5.Cu")
		(net "UART_CTS_RP5_L_N")
	)
	(segment
		(start 10.492232 -378.441966)
		(end 10.492232 -338.178902)
		(width 0.127)
		(layer "In5.Cu")
		(net "UART_CTS_RP5_L_N")
	)
	(segment
		(start 13.39469 -497.151914)
		(end 10.663428 -494.420652)
		(width 0.127)
		(layer "In5.Cu")
		(net "UART_CTS_RP5_L_N")
	)
	(segment
		(start 8.229346 -336.450432)
		(end 7.26948 -335.490566)
		(width 0.127)
		(layer "In5.Cu")
		(net "UART_CTS_RP5_L_N")
	)
	(segment
		(start 10.259314 -393.910058)
		(end 8.088122 -391.738866)
		(width 0.127)
		(layer "In5.Cu")
		(net "UART_CTS_RP5_L_N")
	)
	(segment
		(start 3.648456 -329.368404)
		(end 1.949958 -327.669906)
		(width 0.127)
		(layer "In5.Cu")
		(net "UART_CTS_RP5_L_N")
	)
	(segment
		(start 10.492232 -338.178902)
		(end 8.763762 -336.450432)
		(width 0.127)
		(layer "In5.Cu")
		(net "UART_CTS_RP5_L_N")
	)
	(segment
		(start 8.763762 -336.450432)
		(end 8.229346 -336.450432)
		(width 0.127)
		(layer "In5.Cu")
		(net "UART_CTS_RP5_L_N")
	)
	(segment
		(start 10.663428 -493.705388)
		(end 8.138922 -491.180882)
		(width 0.127)
		(layer "In5.Cu")
		(net "UART_CTS_RP5_L_N")
	)
	(segment
		(start 5.048504 -333.436976)
		(end 5.048504 -330.136754)
		(width 0.127)
		(layer "In5.Cu")
		(net "UART_CTS_RP5_L_N")
	)
	(segment
		(start 5.048504 -330.136754)
		(end 4.280154 -329.368404)
		(width 0.127)
		(layer "In5.Cu")
		(net "UART_CTS_RP5_L_N")
	)
	(segment
		(start 8.088122 -380.846076)
		(end 10.492232 -378.441966)
		(width 0.127)
		(layer "In5.Cu")
		(net "UART_CTS_RP5_L_N")
	)
	(segment
		(start 8.138922 -470.797128)
		(end 16.214598 -462.721452)
		(width 0.127)
		(layer "In5.Cu")
		(net "UART_CTS_RP5_L_N")
	)
	(segment
		(start 12.754102 -378.373894)
		(end 9.523984 -381.604012)
		(width 0.127)
		(layer "In5.Cu")
		(net "UART_DSR_RP6_L")
	)
	(segment
		(start 9.524238 -382.425702)
		(end 9.524238 -390.205976)
		(width 0.127)
		(layer "In5.Cu")
		(net "UART_DSR_RP6_L")
	)
	(segment
		(start 7.56158 -518.59688)
		(end 5.77469 -520.38377)
		(width 0.127)
		(layer "In5.Cu")
		(net "UART_DSR_RP6_L")
	)
	(segment
		(start 23.052532 -497.14531)
		(end 7.56158 -512.636262)
		(width 0.127)
		(layer "In5.Cu")
		(net "UART_DSR_RP6_L")
	)
	(segment
		(start 17.934686 -410.845762)
		(end 17.934686 -466.118956)
		(width 0.127)
		(layer "In5.Cu")
		(net "UART_DSR_RP6_L")
	)
	(segment
		(start 9.523984 -382.425448)
		(end 9.524238 -382.425702)
		(width 0.127)
		(layer "In5.Cu")
		(net "UART_DSR_RP6_L")
	)
	(segment
		(start 6.449822 -332.669896)
		(end 11.72083 -332.669896)
		(width 0.127)
		(layer "In5.Cu")
		(net "UART_DSR_RP6_L")
	)
	(segment
		(start 11.72083 -332.669896)
		(end 12.754102 -333.703168)
		(width 0.127)
		(layer "In5.Cu")
		(net "UART_DSR_RP6_L")
	)
	(segment
		(start 9.524238 -390.205976)
		(end 19.199352 -399.88109)
		(width 0.127)
		(layer "In5.Cu")
		(net "UART_DSR_RP6_L")
	)
	(segment
		(start 17.934686 -466.118956)
		(end 23.052532 -471.236802)
		(width 0.127)
		(layer "In5.Cu")
		(net "UART_DSR_RP6_L")
	)
	(segment
		(start 19.199352 -409.581096)
		(end 17.934686 -410.845762)
		(width 0.127)
		(layer "In5.Cu")
		(net "UART_DSR_RP6_L")
	)
	(segment
		(start 7.56158 -512.636262)
		(end 7.56158 -518.59688)
		(width 0.127)
		(layer "In5.Cu")
		(net "UART_DSR_RP6_L")
	)
	(segment
		(start 9.523984 -381.604012)
		(end 9.523984 -382.425448)
		(width 0.127)
		(layer "In5.Cu")
		(net "UART_DSR_RP6_L")
	)
	(segment
		(start 12.754102 -333.703168)
		(end 12.754102 -378.373894)
		(width 0.127)
		(layer "In5.Cu")
		(net "UART_DSR_RP6_L")
	)
	(segment
		(start 19.199352 -399.88109)
		(end 19.199352 -409.581096)
		(width 0.127)
		(layer "In5.Cu")
		(net "UART_DSR_RP6_L")
	)
	(segment
		(start 5.77469 -520.38377)
		(end 5.77469 -523.661894)
		(width 0.127)
		(layer "In5.Cu")
		(net "UART_DSR_RP6_L")
	)
	(segment
		(start 23.052532 -471.236802)
		(end 23.052532 -497.14531)
		(width 0.127)
		(layer "In5.Cu")
		(net "UART_DSR_RP6_L")
	)
	(segment
		(start 9.21258 -513.320792)
		(end 9.21258 -516.659622)
		(width 0.127)
		(layer "In5.Cu")
		(net "UART_CTS_RP6_L_N")
	)
	(segment
		(start 11.175238 -389.521446)
		(end 20.850352 -399.19656)
		(width 0.127)
		(layer "In5.Cu")
		(net "UART_CTS_RP6_L_N")
	)
	(segment
		(start 9.21258 -516.659622)
		(end 13.39469 -520.841732)
		(width 0.127)
		(layer "In5.Cu")
		(net "UART_CTS_RP6_L_N")
	)
	(segment
		(start 14.628622 -332.805786)
		(end 14.405102 -333.029306)
		(width 0.127)
		(layer "In5.Cu")
		(net "UART_CTS_RP6_L_N")
	)
	(segment
		(start 6.449822 -328.669904)
		(end 11.237976 -328.669904)
		(width 0.127)
		(layer "In5.Cu")
		(net "UART_CTS_RP6_L_N")
	)
	(segment
		(start 14.405102 -333.029306)
		(end 14.405102 -379.058678)
		(width 0.127)
		(layer "In5.Cu")
		(net "UART_CTS_RP6_L_N")
	)
	(segment
		(start 20.850352 -399.19656)
		(end 20.850352 -410.454856)
		(width 0.127)
		(layer "In5.Cu")
		(net "UART_CTS_RP6_L_N")
	)
	(segment
		(start 24.703532 -470.552272)
		(end 24.703532 -497.82984)
		(width 0.127)
		(layer "In5.Cu")
		(net "UART_CTS_RP6_L_N")
	)
	(segment
		(start 20.850352 -410.454856)
		(end 19.585686 -411.719522)
		(width 0.127)
		(layer "In5.Cu")
		(net "UART_CTS_RP6_L_N")
	)
	(segment
		(start 11.175238 -382.288542)
		(end 11.175238 -389.521446)
		(width 0.127)
		(layer "In5.Cu")
		(net "UART_CTS_RP6_L_N")
	)
	(segment
		(start 14.405102 -379.058678)
		(end 11.175238 -382.288542)
		(width 0.127)
		(layer "In5.Cu")
		(net "UART_CTS_RP6_L_N")
	)
	(segment
		(start 11.237976 -328.669904)
		(end 14.628622 -332.06055)
		(width 0.127)
		(layer "In5.Cu")
		(net "UART_CTS_RP6_L_N")
	)
	(segment
		(start 19.585686 -465.434426)
		(end 24.703532 -470.552272)
		(width 0.127)
		(layer "In5.Cu")
		(net "UART_CTS_RP6_L_N")
	)
	(segment
		(start 24.703532 -497.82984)
		(end 9.21258 -513.320792)
		(width 0.127)
		(layer "In5.Cu")
		(net "UART_CTS_RP6_L_N")
	)
	(segment
		(start 13.39469 -520.841732)
		(end 13.39469 -523.661894)
		(width 0.127)
		(layer "In5.Cu")
		(net "UART_CTS_RP6_L_N")
	)
	(segment
		(start 14.628622 -332.06055)
		(end 14.628622 -332.805786)
		(width 0.127)
		(layer "In5.Cu")
		(net "UART_CTS_RP6_L_N")
	)
	(segment
		(start 19.585686 -411.719522)
		(end 19.585686 -465.434426)
		(width 0.127)
		(layer "In5.Cu")
		(net "UART_CTS_RP6_L_N")
	)
	(segment
		(start 14.038072 -332.04023)
		(end 14.298422 -332.30058)
		(width 0.127)
		(layer "In5.Cu")
		(net "UART_DTR_RP6_L_N")
	)
	(segment
		(start 14.074902 -378.921772)
		(end 10.845038 -382.151636)
		(width 0.127)
		(layer "In5.Cu")
		(net "UART_DTR_RP6_L_N")
	)
	(segment
		(start 14.298422 -332.30058)
		(end 14.298422 -332.66888)
		(width 0.127)
		(layer "In5.Cu")
		(net "UART_DTR_RP6_L_N")
	)
	(segment
		(start 14.298422 -332.66888)
		(end 14.074902 -332.8924)
		(width 0.127)
		(layer "In5.Cu")
		(net "UART_DTR_RP6_L_N")
	)
	(segment
		(start 19.255486 -465.571332)
		(end 24.373332 -470.689178)
		(width 0.127)
		(layer "In5.Cu")
		(net "UART_DTR_RP6_L_N")
	)
	(segment
		(start 24.373332 -470.689178)
		(end 24.373332 -497.692934)
		(width 0.127)
		(layer "In5.Cu")
		(net "UART_DTR_RP6_L_N")
	)
	(segment
		(start 14.074902 -332.8924)
		(end 14.074902 -378.921772)
		(width 0.127)
		(layer "In5.Cu")
		(net "UART_DTR_RP6_L_N")
	)
	(segment
		(start 14.01826 -332.04023)
		(end 14.038072 -332.04023)
		(width 0.127)
		(layer "In5.Cu")
		(net "UART_DTR_RP6_L_N")
	)
	(segment
		(start 24.373332 -497.692934)
		(end 8.88238 -513.183886)
		(width 0.127)
		(layer "In5.Cu")
		(net "UART_DTR_RP6_L_N")
	)
	(segment
		(start 8.88238 -517.879584)
		(end 12.12469 -521.121894)
		(width 0.127)
		(layer "In5.Cu")
		(net "UART_DTR_RP6_L_N")
	)
	(segment
		(start 20.520152 -399.333466)
		(end 20.520152 -410.31795)
		(width 0.127)
		(layer "In5.Cu")
		(net "UART_DTR_RP6_L_N")
	)
	(segment
		(start 19.255486 -411.582616)
		(end 19.255486 -465.571332)
		(width 0.127)
		(layer "In5.Cu")
		(net "UART_DTR_RP6_L_N")
	)
	(segment
		(start 8.449818 -329.669902)
		(end 11.647932 -329.669902)
		(width 0.127)
		(layer "In5.Cu")
		(net "UART_DTR_RP6_L_N")
	)
	(segment
		(start 20.520152 -410.31795)
		(end 19.255486 -411.582616)
		(width 0.127)
		(layer "In5.Cu")
		(net "UART_DTR_RP6_L_N")
	)
	(segment
		(start 10.845038 -389.658352)
		(end 20.520152 -399.333466)
		(width 0.127)
		(layer "In5.Cu")
		(net "UART_DTR_RP6_L_N")
	)
	(segment
		(start 8.88238 -513.183886)
		(end 8.88238 -517.879584)
		(width 0.127)
		(layer "In5.Cu")
		(net "UART_DTR_RP6_L_N")
	)
	(segment
		(start 10.845038 -382.151636)
		(end 10.845038 -389.658352)
		(width 0.127)
		(layer "In5.Cu")
		(net "UART_DTR_RP6_L_N")
	)
	(segment
		(start 11.647932 -329.669902)
		(end 14.01826 -332.04023)
		(width 0.127)
		(layer "In5.Cu")
		(net "UART_DTR_RP6_L_N")
	)
	(segment
		(start 23.712932 -470.96299)
		(end 23.712932 -497.419122)
		(width 0.127)
		(layer "In5.Cu")
		(net "UART_TX_RP6_L")
	)
	(segment
		(start 10.184384 -381.877824)
		(end 10.184384 -382.151636)
		(width 0.127)
		(layer "In5.Cu")
		(net "UART_TX_RP6_L")
	)
	(segment
		(start 13.414502 -378.647706)
		(end 10.184384 -381.877824)
		(width 0.127)
		(layer "In5.Cu")
		(net "UART_TX_RP6_L")
	)
	(segment
		(start 13.414502 -333.141066)
		(end 13.414502 -378.647706)
		(width 0.127)
		(layer "In5.Cu")
		(net "UART_TX_RP6_L")
	)
	(segment
		(start 8.22198 -521.476224)
		(end 7.331964 -522.36624)
		(width 0.127)
		(layer "In5.Cu")
		(net "UART_TX_RP6_L")
	)
	(segment
		(start 8.22198 -512.910074)
		(end 8.22198 -521.476224)
		(width 0.127)
		(layer "In5.Cu")
		(net "UART_TX_RP6_L")
	)
	(segment
		(start 7.50443 -330.6699)
		(end 7.75589 -330.92136)
		(width 0.127)
		(layer "In5.Cu")
		(net "UART_TX_RP6_L")
	)
	(segment
		(start 10.184638 -382.15189)
		(end 10.184638 -389.932164)
		(width 0.127)
		(layer "In5.Cu")
		(net "UART_TX_RP6_L")
	)
	(segment
		(start 19.859752 -410.044138)
		(end 18.595086 -411.308804)
		(width 0.127)
		(layer "In5.Cu")
		(net "UART_TX_RP6_L")
	)
	(segment
		(start 7.75589 -330.92136)
		(end 11.194796 -330.92136)
		(width 0.127)
		(layer "In5.Cu")
		(net "UART_TX_RP6_L")
	)
	(segment
		(start 7.940294 -524.648684)
		(end 9.8679 -524.648684)
		(width 0.127)
		(layer "In5.Cu")
		(net "UART_TX_RP6_L")
	)
	(segment
		(start 7.331964 -524.040354)
		(end 7.940294 -524.648684)
		(width 0.127)
		(layer "In5.Cu")
		(net "UART_TX_RP6_L")
	)
	(segment
		(start 19.859752 -399.607278)
		(end 19.859752 -410.044138)
		(width 0.127)
		(layer "In5.Cu")
		(net "UART_TX_RP6_L")
	)
	(segment
		(start 7.331964 -522.36624)
		(end 7.331964 -524.040354)
		(width 0.127)
		(layer "In5.Cu")
		(net "UART_TX_RP6_L")
	)
	(segment
		(start 18.595086 -465.845144)
		(end 23.712932 -470.96299)
		(width 0.127)
		(layer "In5.Cu")
		(net "UART_TX_RP6_L")
	)
	(segment
		(start 6.449822 -330.6699)
		(end 7.50443 -330.6699)
		(width 0.127)
		(layer "In5.Cu")
		(net "UART_TX_RP6_L")
	)
	(segment
		(start 23.712932 -497.419122)
		(end 8.22198 -512.910074)
		(width 0.127)
		(layer "In5.Cu")
		(net "UART_TX_RP6_L")
	)
	(segment
		(start 18.595086 -411.308804)
		(end 18.595086 -465.845144)
		(width 0.127)
		(layer "In5.Cu")
		(net "UART_TX_RP6_L")
	)
	(segment
		(start 9.8679 -524.648684)
		(end 10.85469 -523.661894)
		(width 0.127)
		(layer "In5.Cu")
		(net "UART_TX_RP6_L")
	)
	(segment
		(start 10.184638 -389.932164)
		(end 19.859752 -399.607278)
		(width 0.127)
		(layer "In5.Cu")
		(net "UART_TX_RP6_L")
	)
	(segment
		(start 10.184384 -382.151636)
		(end 10.184638 -382.15189)
		(width 0.127)
		(layer "In5.Cu")
		(net "UART_TX_RP6_L")
	)
	(segment
		(start 11.194796 -330.92136)
		(end 13.414502 -333.141066)
		(width 0.127)
		(layer "In5.Cu")
		(net "UART_TX_RP6_L")
	)
	(segment
		(start 19.529552 -409.907232)
		(end 18.264886 -411.171898)
		(width 0.127)
		(layer "In5.Cu")
		(net "UART_RX_RP6_L")
	)
	(segment
		(start 19.529552 -399.744184)
		(end 19.529552 -409.907232)
		(width 0.127)
		(layer "In5.Cu")
		(net "UART_RX_RP6_L")
	)
	(segment
		(start 11.430508 -331.669898)
		(end 13.084302 -333.323692)
		(width 0.127)
		(layer "In5.Cu")
		(net "UART_RX_RP6_L")
	)
	(segment
		(start 18.264886 -411.171898)
		(end 18.264886 -465.98205)
		(width 0.127)
		(layer "In5.Cu")
		(net "UART_RX_RP6_L")
	)
	(segment
		(start 18.264886 -465.98205)
		(end 23.382732 -471.099896)
		(width 0.127)
		(layer "In5.Cu")
		(net "UART_RX_RP6_L")
	)
	(segment
		(start 9.854184 -382.288542)
		(end 9.854438 -382.288796)
		(width 0.127)
		(layer "In5.Cu")
		(net "UART_RX_RP6_L")
	)
	(segment
		(start 13.084302 -378.5108)
		(end 9.854184 -381.740918)
		(width 0.127)
		(layer "In5.Cu")
		(net "UART_RX_RP6_L")
	)
	(segment
		(start 7.04469 -519.857736)
		(end 7.04469 -521.121894)
		(width 0.127)
		(layer "In5.Cu")
		(net "UART_RX_RP6_L")
	)
	(segment
		(start 23.382732 -497.282216)
		(end 7.89178 -512.773168)
		(width 0.127)
		(layer "In5.Cu")
		(net "UART_RX_RP6_L")
	)
	(segment
		(start 23.382732 -471.099896)
		(end 23.382732 -497.282216)
		(width 0.127)
		(layer "In5.Cu")
		(net "UART_RX_RP6_L")
	)
	(segment
		(start 9.854438 -390.06907)
		(end 19.529552 -399.744184)
		(width 0.127)
		(layer "In5.Cu")
		(net "UART_RX_RP6_L")
	)
	(segment
		(start 7.89178 -512.773168)
		(end 7.89178 -519.010646)
		(width 0.127)
		(layer "In5.Cu")
		(net "UART_RX_RP6_L")
	)
	(segment
		(start 8.449818 -331.669898)
		(end 11.430508 -331.669898)
		(width 0.127)
		(layer "In5.Cu")
		(net "UART_RX_RP6_L")
	)
	(segment
		(start 7.89178 -519.010646)
		(end 7.04469 -519.857736)
		(width 0.127)
		(layer "In5.Cu")
		(net "UART_RX_RP6_L")
	)
	(segment
		(start 9.854438 -382.288796)
		(end 9.854438 -390.06907)
		(width 0.127)
		(layer "In5.Cu")
		(net "UART_RX_RP6_L")
	)
	(segment
		(start 13.084302 -333.323692)
		(end 13.084302 -378.5108)
		(width 0.127)
		(layer "In5.Cu")
		(net "UART_RX_RP6_L")
	)
	(segment
		(start 9.854184 -381.740918)
		(end 9.854184 -382.288542)
		(width 0.127)
		(layer "In5.Cu")
		(net "UART_RX_RP6_L")
	)
	(segment
		(start 12.37742 -336.948272)
		(end 12.374626 -336.951066)
		(width 0.127)
		(layer "In5.Cu")
		(net "UART_RTS_RP6_L_N")
	)
	(segment
		(start 12.37742 -339.488272)
		(end 12.374626 -339.491066)
		(width 0.127)
		(layer "In5.Cu")
		(net "UART_RTS_RP6_L_N")
	)
	(segment
		(start 12.185142 -333.669894)
		(end 12.374626 -333.859378)
		(width 0.127)
		(layer "In5.Cu")
		(net "UART_RTS_RP6_L_N")
	)
	(segment
		(start 12.37742 -334.039972)
		(end 12.37742 -334.408272)
		(width 0.127)
		(layer "In5.Cu")
		(net "UART_RTS_RP6_L_N")
	)
	(segment
		(start 12.374626 -333.859378)
		(end 12.374626 -334.037178)
		(width 0.127)
		(layer "In5.Cu")
		(net "UART_RTS_RP6_L_N")
	)
	(segment
		(start 12.374626 -335.307178)
		(end 12.37742 -335.309972)
		(width 0.127)
		(layer "In5.Cu")
		(net "UART_RTS_RP6_L_N")
	)
	(segment
		(start 8.449818 -333.669894)
		(end 12.185142 -333.669894)
		(width 0.127)
		(layer "In5.Cu")
		(net "UART_RTS_RP6_L_N")
	)
	(segment
		(start 12.374626 -335.681066)
		(end 12.374626 -336.577178)
		(width 0.127)
		(layer "In5.Cu")
		(net "UART_RTS_RP6_L_N")
	)
	(segment
		(start 12.37742 -334.408272)
		(end 12.374626 -334.411066)
		(width 0.127)
		(layer "In5.Cu")
		(net "UART_RTS_RP6_L_N")
	)
	(segment
		(start 9.144762 -381.446786)
		(end 9.144762 -390.363202)
		(width 0.127)
		(layer "In5.Cu")
		(net "UART_RTS_RP6_L_N")
	)
	(segment
		(start 12.374626 -337.847178)
		(end 12.37742 -337.849972)
		(width 0.127)
		(layer "In5.Cu")
		(net "UART_RTS_RP6_L_N")
	)
	(segment
		(start 12.374626 -339.117178)
		(end 12.37742 -339.119972)
		(width 0.127)
		(layer "In5.Cu")
		(net "UART_RTS_RP6_L_N")
	)
	(segment
		(start 12.374626 -340.761066)
		(end 12.374626 -341.657178)
		(width 0.127)
		(layer "In5.Cu")
		(net "UART_RTS_RP6_L_N")
	)
	(segment
		(start 12.374626 -341.657178)
		(end 12.37742 -341.659972)
		(width 0.127)
		(layer "In5.Cu")
		(net "UART_RTS_RP6_L_N")
	)
	(segment
		(start 12.374626 -334.411066)
		(end 12.374626 -335.307178)
		(width 0.127)
		(layer "In5.Cu")
		(net "UART_RTS_RP6_L_N")
	)
	(segment
		(start 12.374626 -334.037178)
		(end 12.37742 -334.039972)
		(width 0.127)
		(layer "In5.Cu")
		(net "UART_RTS_RP6_L_N")
	)
	(segment
		(start 17.55521 -410.6164)
		(end 17.55521 -466.276182)
		(width 0.127)
		(layer "In5.Cu")
		(net "UART_RTS_RP6_L_N")
	)
	(segment
		(start 12.37742 -340.758272)
		(end 12.374626 -340.761066)
		(width 0.127)
		(layer "In5.Cu")
		(net "UART_RTS_RP6_L_N")
	)
	(segment
		(start 12.374626 -338.221066)
		(end 12.374626 -339.117178)
		(width 0.127)
		(layer "In5.Cu")
		(net "UART_RTS_RP6_L_N")
	)
	(segment
		(start 12.37742 -340.389972)
		(end 12.37742 -340.758272)
		(width 0.127)
		(layer "In5.Cu")
		(net "UART_RTS_RP6_L_N")
	)
	(segment
		(start 12.374626 -342.031066)
		(end 12.374626 -378.216922)
		(width 0.127)
		(layer "In5.Cu")
		(net "UART_RTS_RP6_L_N")
	)
	(segment
		(start 7.182104 -518.44448)
		(end 4.50469 -521.121894)
		(width 0.127)
		(layer "In5.Cu")
		(net "UART_RTS_RP6_L_N")
	)
	(segment
		(start 12.37742 -335.678272)
		(end 12.374626 -335.681066)
		(width 0.127)
		(layer "In5.Cu")
		(net "UART_RTS_RP6_L_N")
	)
	(segment
		(start 12.374626 -339.491066)
		(end 12.374626 -340.387178)
		(width 0.127)
		(layer "In5.Cu")
		(net "UART_RTS_RP6_L_N")
	)
	(segment
		(start 12.37742 -342.028272)
		(end 12.374626 -342.031066)
		(width 0.127)
		(layer "In5.Cu")
		(net "UART_RTS_RP6_L_N")
	)
	(segment
		(start 12.37742 -341.659972)
		(end 12.37742 -342.028272)
		(width 0.127)
		(layer "In5.Cu")
		(net "UART_RTS_RP6_L_N")
	)
	(segment
		(start 22.673056 -471.394028)
		(end 22.673056 -496.988084)
		(width 0.127)
		(layer "In5.Cu")
		(net "UART_RTS_RP6_L_N")
	)
	(segment
		(start 12.374626 -336.577178)
		(end 12.37742 -336.579972)
		(width 0.127)
		(layer "In5.Cu")
		(net "UART_RTS_RP6_L_N")
	)
	(segment
		(start 12.374626 -340.387178)
		(end 12.37742 -340.389972)
		(width 0.127)
		(layer "In5.Cu")
		(net "UART_RTS_RP6_L_N")
	)
	(segment
		(start 9.144762 -390.363202)
		(end 18.819876 -400.038316)
		(width 0.127)
		(layer "In5.Cu")
		(net "UART_RTS_RP6_L_N")
	)
	(segment
		(start 7.182104 -512.479036)
		(end 7.182104 -518.44448)
		(width 0.127)
		(layer "In5.Cu")
		(net "UART_RTS_RP6_L_N")
	)
	(segment
		(start 17.55521 -466.276182)
		(end 22.673056 -471.394028)
		(width 0.127)
		(layer "In5.Cu")
		(net "UART_RTS_RP6_L_N")
	)
	(segment
		(start 18.819876 -400.038316)
		(end 18.819876 -409.351734)
		(width 0.127)
		(layer "In5.Cu")
		(net "UART_RTS_RP6_L_N")
	)
	(segment
		(start 22.673056 -496.988084)
		(end 7.182104 -512.479036)
		(width 0.127)
		(layer "In5.Cu")
		(net "UART_RTS_RP6_L_N")
	)
	(segment
		(start 12.374626 -378.216922)
		(end 9.144762 -381.446786)
		(width 0.127)
		(layer "In5.Cu")
		(net "UART_RTS_RP6_L_N")
	)
	(segment
		(start 12.374626 -336.951066)
		(end 12.374626 -337.847178)
		(width 0.127)
		(layer "In5.Cu")
		(net "UART_RTS_RP6_L_N")
	)
	(segment
		(start 12.37742 -338.218272)
		(end 12.374626 -338.221066)
		(width 0.127)
		(layer "In5.Cu")
		(net "UART_RTS_RP6_L_N")
	)
	(segment
		(start 12.37742 -335.309972)
		(end 12.37742 -335.678272)
		(width 0.127)
		(layer "In5.Cu")
		(net "UART_RTS_RP6_L_N")
	)
	(segment
		(start 12.37742 -337.849972)
		(end 12.37742 -338.218272)
		(width 0.127)
		(layer "In5.Cu")
		(net "UART_RTS_RP6_L_N")
	)
	(segment
		(start 18.819876 -409.351734)
		(end 17.55521 -410.6164)
		(width 0.127)
		(layer "In5.Cu")
		(net "UART_RTS_RP6_L_N")
	)
	(segment
		(start 12.37742 -336.579972)
		(end 12.37742 -336.948272)
		(width 0.127)
		(layer "In5.Cu")
		(net "UART_RTS_RP6_L_N")
	)
	(segment
		(start 12.37742 -339.119972)
		(end 12.37742 -339.488272)
		(width 0.127)
		(layer "In5.Cu")
		(net "UART_RTS_RP6_L_N")
	)
	(via
		(at 15.045944 -170.372532)
		(size 0.508)
		(drill 0.254)
		(layers "F.Cu" "B.Cu")
		(net "GND28")
	)
	(segment
		(start 10.64387 -191.892174)
		(end 10.64387 -191.538352)
		(width 0.1524)
		(layer "B.Cu")
		(net "GND28")
	)
	(segment
		(start 9.072118 -193.463926)
		(end 10.64387 -191.892174)
		(width 0.1524)
		(layer "B.Cu")
		(net "GND28")
	)
	(segment
		(start 15.045944 -187.136278)
		(end 15.045944 -170.372532)
		(width 0.1524)
		(layer "B.Cu")
		(net "GND28")
	)
	(segment
		(start 7.851648 -193.463926)
		(end 9.072118 -193.463926)
		(width 0.1524)
		(layer "B.Cu")
		(net "GND28")
	)
	(segment
		(start 1.948942 -192.67043)
		(end 7.058152 -192.67043)
		(width 0.1524)
		(layer "B.Cu")
		(net "GND28")
	)
	(segment
		(start 10.64387 -191.538352)
		(end 15.045944 -187.136278)
		(width 0.1524)
		(layer "B.Cu")
		(net "GND28")
	)
	(segment
		(start 7.058152 -192.67043)
		(end 7.851648 -193.463926)
		(width 0.1524)
		(layer "B.Cu")
		(net "GND28")
	)
	(via
		(at 13.838682 -172.67174)
		(size 0.508)
		(drill 0.254)
		(layers "F.Cu" "B.Cu")
		(net "GND29")
	)
	(segment
		(start 7.328916 -190.803022)
		(end 8.165338 -191.639444)
		(width 0.1524)
		(layer "B.Cu")
		(net "GND29")
	)
	(segment
		(start 3.948938 -191.670432)
		(end 4.816348 -190.803022)
		(width 0.1524)
		(layer "B.Cu")
		(net "GND29")
	)
	(segment
		(start 8.165338 -191.639444)
		(end 10.026904 -191.639444)
		(width 0.1524)
		(layer "B.Cu")
		(net "GND29")
	)
	(segment
		(start 4.816348 -190.803022)
		(end 7.328916 -190.803022)
		(width 0.1524)
		(layer "B.Cu")
		(net "GND29")
	)
	(segment
		(start 13.838682 -187.827666)
		(end 13.838682 -172.67174)
		(width 0.1524)
		(layer "B.Cu")
		(net "GND29")
	)
	(segment
		(start 10.026904 -191.639444)
		(end 13.838682 -187.827666)
		(width 0.1524)
		(layer "B.Cu")
		(net "GND29")
	)
	(segment
		(start 26.253186 -310.812688)
		(end 26.253186 -339.747606)
		(width 0.1524)
		(layer "F.Cu")
		(net "POWER_SW3_PWR_CTR_12V")
	)
	(segment
		(start 27.00274 -249.929396)
		(end 27.00274 -262.026654)
		(width 0.1524)
		(layer "F.Cu")
		(net "POWER_SW3_PWR_CTR_12V")
	)
	(segment
		(start 25.772618 -286.878268)
		(end 27.922728 -289.028378)
		(width 0.1524)
		(layer "F.Cu")
		(net "POWER_SW3_PWR_CTR_12V")
	)
	(segment
		(start 26.463498 -236.019594)
		(end 24.974042 -237.50905)
		(width 0.1524)
		(layer "F.Cu")
		(net "POWER_SW3_PWR_CTR_12V")
	)
	(segment
		(start 21.769578 -198.275956)
		(end 26.463498 -202.969876)
		(width 0.1524)
		(layer "F.Cu")
		(net "POWER_SW3_PWR_CTR_12V")
	)
	(segment
		(start 27.922728 -289.028378)
		(end 27.922728 -309.143146)
		(width 0.1524)
		(layer "F.Cu")
		(net "POWER_SW3_PWR_CTR_12V")
	)
	(segment
		(start 25.772618 -283.988256)
		(end 25.772618 -286.878268)
		(width 0.1524)
		(layer "F.Cu")
		(net "POWER_SW3_PWR_CTR_12V")
	)
	(segment
		(start 28.294076 -281.466798)
		(end 25.772618 -283.988256)
		(width 0.1524)
		(layer "F.Cu")
		(net "POWER_SW3_PWR_CTR_12V")
	)
	(segment
		(start 2.439924 -159.325056)
		(end 2.439924 -160.960562)
		(width 0.1524)
		(layer "F.Cu")
		(net "POWER_SW3_PWR_CTR_12V")
	)
	(segment
		(start 25.378918 -340.621874)
		(end 24.07666 -340.621874)
		(width 0.1524)
		(layer "F.Cu")
		(net "POWER_SW3_PWR_CTR_12V")
	)
	(segment
		(start 32.678116 -280.187146)
		(end 31.398464 -281.466798)
		(width 0.1524)
		(layer "F.Cu")
		(net "POWER_SW3_PWR_CTR_12V")
	)
	(segment
		(start 27.922728 -309.143146)
		(end 26.253186 -310.812688)
		(width 0.1524)
		(layer "F.Cu")
		(net "POWER_SW3_PWR_CTR_12V")
	)
	(segment
		(start 10.065512 -343.669874)
		(end 9.065514 -344.669872)
		(width 0.1524)
		(layer "F.Cu")
		(net "POWER_SW3_PWR_CTR_12V")
	)
	(segment
		(start 17.323562 -179.941982)
		(end 21.769578 -184.387998)
		(width 0.1524)
		(layer "F.Cu")
		(net "POWER_SW3_PWR_CTR_12V")
	)
	(segment
		(start 3.121406 -161.642044)
		(end 3.121406 -180.013102)
		(width 0.1524)
		(layer "F.Cu")
		(net "POWER_SW3_PWR_CTR_12V")
	)
	(segment
		(start 27.00274 -262.026654)
		(end 32.678116 -267.70203)
		(width 0.1524)
		(layer "F.Cu")
		(net "POWER_SW3_PWR_CTR_12V")
	)
	(segment
		(start 24.07666 -340.621874)
		(end 21.02866 -343.669874)
		(width 0.1524)
		(layer "F.Cu")
		(net "POWER_SW3_PWR_CTR_12V")
	)
	(segment
		(start 21.02866 -343.669874)
		(end 10.065512 -343.669874)
		(width 0.1524)
		(layer "F.Cu")
		(net "POWER_SW3_PWR_CTR_12V")
	)
	(segment
		(start 3.121406 -180.013102)
		(end 3.961638 -180.853334)
		(width 0.1524)
		(layer "F.Cu")
		(net "POWER_SW3_PWR_CTR_12V")
	)
	(segment
		(start 32.678116 -267.70203)
		(end 32.678116 -280.187146)
		(width 0.1524)
		(layer "F.Cu")
		(net "POWER_SW3_PWR_CTR_12V")
	)
	(segment
		(start 26.463498 -202.969876)
		(end 26.463498 -236.019594)
		(width 0.1524)
		(layer "F.Cu")
		(net "POWER_SW3_PWR_CTR_12V")
	)
	(segment
		(start 24.974042 -237.50905)
		(end 24.974042 -247.900698)
		(width 0.1524)
		(layer "F.Cu")
		(net "POWER_SW3_PWR_CTR_12V")
	)
	(segment
		(start 9.065514 -344.669872)
		(end 6.449822 -344.669872)
		(width 0.1524)
		(layer "F.Cu")
		(net "POWER_SW3_PWR_CTR_12V")
	)
	(segment
		(start 3.961638 -180.853334)
		(end 7.144766 -180.853334)
		(width 0.1524)
		(layer "F.Cu")
		(net "POWER_SW3_PWR_CTR_12V")
	)
	(segment
		(start 26.253186 -339.747606)
		(end 25.378918 -340.621874)
		(width 0.1524)
		(layer "F.Cu")
		(net "POWER_SW3_PWR_CTR_12V")
	)
	(segment
		(start 2.439924 -160.960562)
		(end 3.121406 -161.642044)
		(width 0.1524)
		(layer "F.Cu")
		(net "POWER_SW3_PWR_CTR_12V")
	)
	(segment
		(start 24.974042 -247.900698)
		(end 27.00274 -249.929396)
		(width 0.1524)
		(layer "F.Cu")
		(net "POWER_SW3_PWR_CTR_12V")
	)
	(segment
		(start 8.056118 -179.941982)
		(end 17.323562 -179.941982)
		(width 0.1524)
		(layer "F.Cu")
		(net "POWER_SW3_PWR_CTR_12V")
	)
	(segment
		(start 7.144766 -180.853334)
		(end 8.056118 -179.941982)
		(width 0.1524)
		(layer "F.Cu")
		(net "POWER_SW3_PWR_CTR_12V")
	)
	(segment
		(start 31.398464 -281.466798)
		(end 28.294076 -281.466798)
		(width 0.1524)
		(layer "F.Cu")
		(net "POWER_SW3_PWR_CTR_12V")
	)
	(segment
		(start 21.769578 -184.387998)
		(end 21.769578 -198.275956)
		(width 0.1524)
		(layer "F.Cu")
		(net "POWER_SW3_PWR_CTR_12V")
	)
	(segment
		(start 3.529838 -353.68357)
		(end 3.13817 -353.291902)
		(width 0.1524)
		(layer "F.Cu")
		(net "POWER_SW1_PWR_CTR_12V")
	)
	(segment
		(start 1.399794 -379.784864)
		(end 1.399794 -372.963948)
		(width 0.1524)
		(layer "F.Cu")
		(net "POWER_SW1_PWR_CTR_12V")
	)
	(segment
		(start 3.665474 -345.63177)
		(end 4.25704 -345.63177)
		(width 0.1524)
		(layer "F.Cu")
		(net "POWER_SW1_PWR_CTR_12V")
	)
	(segment
		(start 3.529838 -370.833904)
		(end 3.529838 -353.68357)
		(width 0.1524)
		(layer "F.Cu")
		(net "POWER_SW1_PWR_CTR_12V")
	)
	(segment
		(start 2.439924 -380.824994)
		(end 1.399794 -379.784864)
		(width 0.1524)
		(layer "F.Cu")
		(net "POWER_SW1_PWR_CTR_12V")
	)
	(segment
		(start 3.13817 -346.159074)
		(end 3.665474 -345.63177)
		(width 0.1524)
		(layer "F.Cu")
		(net "POWER_SW1_PWR_CTR_12V")
	)
	(segment
		(start 4.782058 -345.106752)
		(end 4.782058 -344.33764)
		(width 0.1524)
		(layer "F.Cu")
		(net "POWER_SW1_PWR_CTR_12V")
	)
	(segment
		(start 1.399794 -372.963948)
		(end 3.529838 -370.833904)
		(width 0.1524)
		(layer "F.Cu")
		(net "POWER_SW1_PWR_CTR_12V")
	)
	(segment
		(start 3.13817 -353.291902)
		(end 3.13817 -346.159074)
		(width 0.1524)
		(layer "F.Cu")
		(net "POWER_SW1_PWR_CTR_12V")
	)
	(segment
		(start 4.25704 -345.63177)
		(end 4.782058 -345.106752)
		(width 0.1524)
		(layer "F.Cu")
		(net "POWER_SW1_PWR_CTR_12V")
	)
	(segment
		(start 4.782058 -344.33764)
		(end 6.449822 -342.669876)
		(width 0.1524)
		(layer "F.Cu")
		(net "POWER_SW1_PWR_CTR_12V")
	)
	(segment
		(start 5.30479 -344.736928)
		(end 6.371844 -343.669874)
		(width 0.1524)
		(layer "F.Cu")
		(net "POWER_SW2_PWR_CTR_12V")
	)
	(segment
		(start 4.43992 -371.87505)
		(end 4.43992 -353.537774)
		(width 0.1524)
		(layer "F.Cu")
		(net "POWER_SW2_PWR_CTR_12V")
	)
	(segment
		(start 6.371844 -343.669874)
		(end 8.449818 -343.669874)
		(width 0.1524)
		(layer "F.Cu")
		(net "POWER_SW2_PWR_CTR_12V")
	)
	(segment
		(start 4.923028 -345.730322)
		(end 5.30479 -345.34856)
		(width 0.1524)
		(layer "F.Cu")
		(net "POWER_SW2_PWR_CTR_12V")
	)
	(segment
		(start 2.439924 -373.875046)
		(end 4.43992 -371.87505)
		(width 0.1524)
		(layer "F.Cu")
		(net "POWER_SW2_PWR_CTR_12V")
	)
	(segment
		(start 4.923028 -353.054666)
		(end 4.923028 -345.730322)
		(width 0.1524)
		(layer "F.Cu")
		(net "POWER_SW2_PWR_CTR_12V")
	)
	(segment
		(start 5.30479 -345.34856)
		(end 5.30479 -344.736928)
		(width 0.1524)
		(layer "F.Cu")
		(net "POWER_SW2_PWR_CTR_12V")
	)
	(segment
		(start 4.43992 -353.537774)
		(end 4.923028 -353.054666)
		(width 0.1524)
		(layer "F.Cu")
		(net "POWER_SW2_PWR_CTR_12V")
	)
	(via
		(at 11.93292 -338.034122)
		(size 0.508)
		(drill 0.254)
		(layers "F.Cu" "B.Cu")
		(net "GND36")
	)
	(segment
		(start 11.93292 -338.034122)
		(end 10.29716 -339.669882)
		(width 0.127)
		(layer "In2.Cu")
		(net "GND36")
	)
	(segment
		(start 10.29716 -339.669882)
		(end 8.449818 -339.669882)
		(width 0.127)
		(layer "In2.Cu")
		(net "GND36")
	)
	(segment
		(start 6.893814 -347.45168)
		(end 3.282188 -347.45168)
		(width 0.127)
		(layer "B.Cu")
		(net "LAN2_P2_N")
	)
	(segment
		(start 10.522458 -391.785094)
		(end 8.739632 -390.002268)
		(width 0.127)
		(layer "B.Cu")
		(net "LAN2_P2_N")
	)
	(segment
		(start 8.893556 -348.434406)
		(end 7.87654 -348.434406)
		(width 0.127)
		(layer "B.Cu")
		(net "LAN2_P2_N")
	)
	(segment
		(start 11.17473 -409.614878)
		(end 9.94537 -408.385518)
		(width 0.127)
		(layer "B.Cu")
		(net "LAN2_P2_N")
	)
	(segment
		(start 8.739632 -359.718102)
		(end 9.756902 -358.700832)
		(width 0.127)
		(layer "B.Cu")
		(net "LAN2_P2_N")
	)
	(segment
		(start 2.882138 -347.85173)
		(end 2.824988 -347.965522)
		(width 0.127)
		(layer "B.Cu")
		(net "LAN2_P2_N")
	)
	(segment
		(start 2.824988 -347.965522)
		(end 2.654554 -348.022672)
		(width 0.127)
		(layer "B.Cu")
		(net "LAN2_P2_N")
	)
	(segment
		(start 9.756902 -358.700832)
		(end 9.756902 -349.297752)
		(width 0.127)
		(layer "B.Cu")
		(net "LAN2_P2_N")
	)
	(segment
		(start 7.87654 -348.434406)
		(end 6.893814 -347.45168)
		(width 0.127)
		(layer "B.Cu")
		(net "LAN2_P2_N")
	)
	(segment
		(start 3.282188 -347.45168)
		(end 2.882138 -347.85173)
		(width 0.127)
		(layer "B.Cu")
		(net "LAN2_P2_N")
	)
	(segment
		(start 9.756902 -349.297752)
		(end 8.893556 -348.434406)
		(width 0.127)
		(layer "B.Cu")
		(net "LAN2_P2_N")
	)
	(segment
		(start 2.654554 -348.022672)
		(end 1.949958 -347.669866)
		(width 0.127)
		(layer "B.Cu")
		(net "LAN2_P2_N")
	)
	(segment
		(start 9.94537 -408.385518)
		(end 9.94537 -407.534364)
		(width 0.127)
		(layer "B.Cu")
		(net "LAN2_P2_N")
	)
	(segment
		(start 9.94537 -407.534364)
		(end 10.522458 -406.957276)
		(width 0.127)
		(layer "B.Cu")
		(net "LAN2_P2_N")
	)
	(segment
		(start 8.739632 -390.002268)
		(end 8.739632 -359.718102)
		(width 0.127)
		(layer "B.Cu")
		(net "LAN2_P2_N")
	)
	(segment
		(start 10.522458 -406.957276)
		(end 10.522458 -391.785094)
		(width 0.127)
		(layer "B.Cu")
		(net "LAN2_P2_N")
	)
	(segment
		(start 11.17473 -412.239968)
		(end 11.17473 -409.614878)
		(width 0.127)
		(layer "B.Cu")
		(net "LAN2_P2_N")
	)
	(segment
		(start 9.166098 -352.693478)
		(end 9.350502 -352.509074)
		(width 0.127)
		(layer "B.Cu")
		(net "LAN2_P2_P")
	)
	(segment
		(start 9.95045 -394.892784)
		(end 10.116058 -394.727176)
		(width 0.127)
		(layer "B.Cu")
		(net "LAN2_P2_P")
	)
	(segment
		(start 9.95045 -404.019512)
		(end 9.95045 -403.638512)
		(width 0.127)
		(layer "B.Cu")
		(net "LAN2_P2_P")
	)
	(segment
		(start 10.116058 -404.56612)
		(end 10.116058 -404.18512)
		(width 0.127)
		(layer "B.Cu")
		(net "LAN2_P2_P")
	)
	(segment
		(start 10.116058 -394.346176)
		(end 9.95045 -394.180568)
		(width 0.127)
		(layer "B.Cu")
		(net "LAN2_P2_P")
	)
	(segment
		(start 9.166098 -357.21671)
		(end 9.350502 -357.032306)
		(width 0.127)
		(layer "B.Cu")
		(net "LAN2_P2_P")
	)
	(segment
		(start 9.95045 -403.638512)
		(end 10.116058 -403.472904)
		(width 0.127)
		(layer "B.Cu")
		(net "LAN2_P2_P")
	)
	(segment
		(start 9.95045 -394.180568)
		(end 9.95045 -393.799568)
		(width 0.127)
		(layer "B.Cu")
		(net "LAN2_P2_P")
	)
	(segment
		(start 10.116058 -392.540744)
		(end 10.116058 -391.953496)
		(width 0.127)
		(layer "B.Cu")
		(net "LAN2_P2_P")
	)
	(segment
		(start 9.95045 -399.646648)
		(end 9.95045 -399.265648)
		(width 0.127)
		(layer "B.Cu")
		(net "LAN2_P2_P")
	)
	(segment
		(start 9.166098 -354.955094)
		(end 9.350502 -354.77069)
		(width 0.127)
		(layer "B.Cu")
		(net "LAN2_P2_P")
	)
	(segment
		(start 9.166098 -353.824286)
		(end 9.350502 -353.639882)
		(width 0.127)
		(layer "B.Cu")
		(net "LAN2_P2_P")
	)
	(segment
		(start 9.166098 -356.466902)
		(end 9.166098 -356.085902)
		(width 0.127)
		(layer "B.Cu")
		(net "LAN2_P2_P")
	)
	(segment
		(start 10.116058 -400.193256)
		(end 10.116058 -399.812256)
		(width 0.127)
		(layer "B.Cu")
		(net "LAN2_P2_P")
	)
	(segment
		(start 10.116058 -406.371552)
		(end 9.95045 -406.205944)
		(width 0.127)
		(layer "B.Cu")
		(net "LAN2_P2_P")
	)
	(segment
		(start 10.116058 -403.472904)
		(end 10.116058 -403.091904)
		(width 0.127)
		(layer "B.Cu")
		(net "LAN2_P2_P")
	)
	(segment
		(start 10.116058 -395.820392)
		(end 10.116058 -395.439392)
		(width 0.127)
		(layer "B.Cu")
		(net "LAN2_P2_P")
	)
	(segment
		(start 9.350502 -355.901498)
		(end 9.350502 -355.520498)
		(width 0.127)
		(layer "B.Cu")
		(net "LAN2_P2_P")
	)
	(segment
		(start 7.708138 -348.840806)
		(end 6.725412 -347.85808)
		(width 0.127)
		(layer "B.Cu")
		(net "LAN2_P2_P")
	)
	(segment
		(start 10.116058 -393.25296)
		(end 9.95045 -393.087352)
		(width 0.127)
		(layer "B.Cu")
		(net "LAN2_P2_P")
	)
	(segment
		(start 10.116058 -401.286472)
		(end 10.116058 -400.905472)
		(width 0.127)
		(layer "B.Cu")
		(net "LAN2_P2_P")
	)
	(segment
		(start 10.116058 -403.091904)
		(end 9.95045 -402.926296)
		(width 0.127)
		(layer "B.Cu")
		(net "LAN2_P2_P")
	)
	(segment
		(start 9.350502 -349.466154)
		(end 8.725154 -348.840806)
		(width 0.127)
		(layer "B.Cu")
		(net "LAN2_P2_P")
	)
	(segment
		(start 9.166098 -354.205286)
		(end 9.166098 -353.824286)
		(width 0.127)
		(layer "B.Cu")
		(net "LAN2_P2_P")
	)
	(segment
		(start 10.116058 -396.532608)
		(end 9.95045 -396.367)
		(width 0.127)
		(layer "B.Cu")
		(net "LAN2_P2_P")
	)
	(segment
		(start 10.116058 -398.71904)
		(end 9.95045 -398.553432)
		(width 0.127)
		(layer "B.Cu")
		(net "LAN2_P2_P")
	)
	(segment
		(start 8.333232 -390.17067)
		(end 8.333232 -359.5497)
		(width 0.127)
		(layer "B.Cu")
		(net "LAN2_P2_P")
	)
	(segment
		(start 10.116058 -393.63396)
		(end 10.116058 -393.25296)
		(width 0.127)
		(layer "B.Cu")
		(net "LAN2_P2_P")
	)
	(segment
		(start 9.166098 -353.074478)
		(end 9.166098 -352.693478)
		(width 0.127)
		(layer "B.Cu")
		(net "LAN2_P2_P")
	)
	(segment
		(start 9.95045 -397.079216)
		(end 10.116058 -396.913608)
		(width 0.127)
		(layer "B.Cu")
		(net "LAN2_P2_P")
	)
	(segment
		(start 10.116058 -401.998688)
		(end 9.95045 -401.83308)
		(width 0.127)
		(layer "B.Cu")
		(net "LAN2_P2_P")
	)
	(segment
		(start 10.116058 -398.006824)
		(end 10.116058 -397.625824)
		(width 0.127)
		(layer "B.Cu")
		(net "LAN2_P2_P")
	)
	(segment
		(start 10.116058 -406.788874)
		(end 10.116058 -406.371552)
		(width 0.127)
		(layer "B.Cu")
		(net "LAN2_P2_P")
	)
	(segment
		(start 8.193278 -409.699968)
		(end 9.53897 -408.354276)
		(width 0.127)
		(layer "B.Cu")
		(net "LAN2_P2_P")
	)
	(segment
		(start 9.95045 -402.545296)
		(end 10.116058 -402.379688)
		(width 0.127)
		(layer "B.Cu")
		(net "LAN2_P2_P")
	)
	(segment
		(start 9.95045 -393.799568)
		(end 10.116058 -393.63396)
		(width 0.127)
		(layer "B.Cu")
		(net "LAN2_P2_P")
	)
	(segment
		(start 9.95045 -398.172432)
		(end 10.116058 -398.006824)
		(width 0.127)
		(layer "B.Cu")
		(net "LAN2_P2_P")
	)
	(segment
		(start 9.95045 -404.731728)
		(end 10.116058 -404.56612)
		(width 0.127)
		(layer "B.Cu")
		(net "LAN2_P2_P")
	)
	(segment
		(start 10.116058 -399.812256)
		(end 9.95045 -399.646648)
		(width 0.127)
		(layer "B.Cu")
		(net "LAN2_P2_P")
	)
	(segment
		(start 9.95045 -400.739864)
		(end 9.95045 -400.358864)
		(width 0.127)
		(layer "B.Cu")
		(net "LAN2_P2_P")
	)
	(segment
		(start 10.116058 -397.625824)
		(end 9.95045 -397.460216)
		(width 0.127)
		(layer "B.Cu")
		(net "LAN2_P2_P")
	)
	(segment
		(start 9.95045 -396.367)
		(end 9.95045 -395.986)
		(width 0.127)
		(layer "B.Cu")
		(net "LAN2_P2_P")
	)
	(segment
		(start 9.95045 -397.460216)
		(end 9.95045 -397.079216)
		(width 0.127)
		(layer "B.Cu")
		(net "LAN2_P2_P")
	)
	(segment
		(start 7.36473 -409.699968)
		(end 8.193278 -409.699968)
		(width 0.127)
		(layer "B.Cu")
		(net "LAN2_P2_P")
	)
	(segment
		(start 9.95045 -395.986)
		(end 10.116058 -395.820392)
		(width 0.127)
		(layer "B.Cu")
		(net "LAN2_P2_P")
	)
	(segment
		(start 9.95045 -401.83308)
		(end 9.95045 -401.45208)
		(width 0.127)
		(layer "B.Cu")
		(net "LAN2_P2_P")
	)
	(segment
		(start 9.95045 -405.824944)
		(end 10.116058 -405.659336)
		(width 0.127)
		(layer "B.Cu")
		(net "LAN2_P2_P")
	)
	(segment
		(start 9.166098 -357.59771)
		(end 9.166098 -357.21671)
		(width 0.127)
		(layer "B.Cu")
		(net "LAN2_P2_P")
	)
	(segment
		(start 9.95045 -398.553432)
		(end 9.95045 -398.172432)
		(width 0.127)
		(layer "B.Cu")
		(net "LAN2_P2_P")
	)
	(segment
		(start 3.189224 -348.146878)
		(end 3.245866 -348.317312)
		(width 0.127)
		(layer "B.Cu")
		(net "LAN2_P2_P")
	)
	(segment
		(start 9.350502 -353.639882)
		(end 9.350502 -353.258882)
		(width 0.127)
		(layer "B.Cu")
		(net "LAN2_P2_P")
	)
	(segment
		(start 9.95045 -395.273784)
		(end 9.95045 -394.892784)
		(width 0.127)
		(layer "B.Cu")
		(net "LAN2_P2_P")
	)
	(segment
		(start 9.350502 -358.53243)
		(end 9.350502 -357.782114)
		(width 0.127)
		(layer "B.Cu")
		(net "LAN2_P2_P")
	)
	(segment
		(start 6.725412 -347.85808)
		(end 3.45059 -347.85808)
		(width 0.127)
		(layer "B.Cu")
		(net "LAN2_P2_P")
	)
	(segment
		(start 9.350502 -356.651306)
		(end 9.166098 -356.466902)
		(width 0.127)
		(layer "B.Cu")
		(net "LAN2_P2_P")
	)
	(segment
		(start 9.350502 -357.782114)
		(end 9.166098 -357.59771)
		(width 0.127)
		(layer "B.Cu")
		(net "LAN2_P2_P")
	)
	(segment
		(start 10.116058 -394.727176)
		(end 10.116058 -394.346176)
		(width 0.127)
		(layer "B.Cu")
		(net "LAN2_P2_P")
	)
	(segment
		(start 3.45059 -347.85808)
		(end 3.216656 -348.092014)
		(width 0.127)
		(layer "B.Cu")
		(net "LAN2_P2_P")
	)
	(segment
		(start 3.216656 -348.092014)
		(end 3.189224 -348.146878)
		(width 0.127)
		(layer "B.Cu")
		(net "LAN2_P2_P")
	)
	(segment
		(start 10.116058 -404.18512)
		(end 9.95045 -404.019512)
		(width 0.127)
		(layer "B.Cu")
		(net "LAN2_P2_P")
	)
	(segment
		(start 3.245866 -348.317312)
		(end 3.949954 -348.669864)
		(width 0.127)
		(layer "B.Cu")
		(net "LAN2_P2_P")
	)
	(segment
		(start 9.95045 -402.926296)
		(end 9.95045 -402.545296)
		(width 0.127)
		(layer "B.Cu")
		(net "LAN2_P2_P")
	)
	(segment
		(start 10.116058 -405.659336)
		(end 10.116058 -405.278336)
		(width 0.127)
		(layer "B.Cu")
		(net "LAN2_P2_P")
	)
	(segment
		(start 10.116058 -402.379688)
		(end 10.116058 -401.998688)
		(width 0.127)
		(layer "B.Cu")
		(net "LAN2_P2_P")
	)
	(segment
		(start 9.53897 -408.354276)
		(end 9.53897 -407.365962)
		(width 0.127)
		(layer "B.Cu")
		(net "LAN2_P2_P")
	)
	(segment
		(start 10.116058 -399.10004)
		(end 10.116058 -398.71904)
		(width 0.127)
		(layer "B.Cu")
		(net "LAN2_P2_P")
	)
	(segment
		(start 9.350502 -352.509074)
		(end 9.350502 -349.466154)
		(width 0.127)
		(layer "B.Cu")
		(net "LAN2_P2_P")
	)
	(segment
		(start 9.350502 -357.032306)
		(end 9.350502 -356.651306)
		(width 0.127)
		(layer "B.Cu")
		(net "LAN2_P2_P")
	)
	(segment
		(start 9.95045 -400.358864)
		(end 10.116058 -400.193256)
		(width 0.127)
		(layer "B.Cu")
		(net "LAN2_P2_P")
	)
	(segment
		(start 9.95045 -393.087352)
		(end 9.95045 -392.706352)
		(width 0.127)
		(layer "B.Cu")
		(net "LAN2_P2_P")
	)
	(segment
		(start 10.116058 -400.905472)
		(end 9.95045 -400.739864)
		(width 0.127)
		(layer "B.Cu")
		(net "LAN2_P2_P")
	)
	(segment
		(start 9.95045 -405.112728)
		(end 9.95045 -404.731728)
		(width 0.127)
		(layer "B.Cu")
		(net "LAN2_P2_P")
	)
	(segment
		(start 9.350502 -354.38969)
		(end 9.166098 -354.205286)
		(width 0.127)
		(layer "B.Cu")
		(net "LAN2_P2_P")
	)
	(segment
		(start 9.95045 -406.205944)
		(end 9.95045 -405.824944)
		(width 0.127)
		(layer "B.Cu")
		(net "LAN2_P2_P")
	)
	(segment
		(start 9.350502 -353.258882)
		(end 9.166098 -353.074478)
		(width 0.127)
		(layer "B.Cu")
		(net "LAN2_P2_P")
	)
	(segment
		(start 9.53897 -407.365962)
		(end 10.116058 -406.788874)
		(width 0.127)
		(layer "B.Cu")
		(net "LAN2_P2_P")
	)
	(segment
		(start 9.95045 -401.45208)
		(end 10.116058 -401.286472)
		(width 0.127)
		(layer "B.Cu")
		(net "LAN2_P2_P")
	)
	(segment
		(start 10.116058 -396.913608)
		(end 10.116058 -396.532608)
		(width 0.127)
		(layer "B.Cu")
		(net "LAN2_P2_P")
	)
	(segment
		(start 9.95045 -392.706352)
		(end 10.116058 -392.540744)
		(width 0.127)
		(layer "B.Cu")
		(net "LAN2_P2_P")
	)
	(segment
		(start 10.116058 -395.439392)
		(end 9.95045 -395.273784)
		(width 0.127)
		(layer "B.Cu")
		(net "LAN2_P2_P")
	)
	(segment
		(start 10.116058 -391.953496)
		(end 8.333232 -390.17067)
		(width 0.127)
		(layer "B.Cu")
		(net "LAN2_P2_P")
	)
	(segment
		(start 9.350502 -355.520498)
		(end 9.166098 -355.336094)
		(width 0.127)
		(layer "B.Cu")
		(net "LAN2_P2_P")
	)
	(segment
		(start 8.333232 -359.5497)
		(end 9.350502 -358.53243)
		(width 0.127)
		(layer "B.Cu")
		(net "LAN2_P2_P")
	)
	(segment
		(start 10.116058 -405.278336)
		(end 9.95045 -405.112728)
		(width 0.127)
		(layer "B.Cu")
		(net "LAN2_P2_P")
	)
	(segment
		(start 8.725154 -348.840806)
		(end 7.708138 -348.840806)
		(width 0.127)
		(layer "B.Cu")
		(net "LAN2_P2_P")
	)
	(segment
		(start 9.166098 -355.336094)
		(end 9.166098 -354.955094)
		(width 0.127)
		(layer "B.Cu")
		(net "LAN2_P2_P")
	)
	(segment
		(start 9.166098 -356.085902)
		(end 9.350502 -355.901498)
		(width 0.127)
		(layer "B.Cu")
		(net "LAN2_P2_P")
	)
	(segment
		(start 9.350502 -354.77069)
		(end 9.350502 -354.38969)
		(width 0.127)
		(layer "B.Cu")
		(net "LAN2_P2_P")
	)
	(segment
		(start 9.95045 -399.265648)
		(end 10.116058 -399.10004)
		(width 0.127)
		(layer "B.Cu")
		(net "LAN2_P2_P")
	)
	(segment
		(start 6.068314 -394.39723)
		(end 6.814312 -395.143228)
		(width 0.127)
		(layer "B.Cu")
		(net "LAN2_P1_P")
	)
	(segment
		(start 6.068314 -371.941852)
		(end 6.068314 -394.39723)
		(width 0.127)
		(layer "B.Cu")
		(net "LAN2_P1_P")
	)
	(segment
		(start 3.322828 -410.430726)
		(end 3.794252 -410.90215)
		(width 0.127)
		(layer "B.Cu")
		(net "LAN2_P1_P")
	)
	(segment
		(start 5.312918 -410.67482)
		(end 4.82473 -409.699968)
		(width 0.127)
		(layer "B.Cu")
		(net "LAN2_P1_P")
	)
	(segment
		(start 5.515102 -371.38864)
		(end 6.068314 -371.941852)
		(width 0.127)
		(layer "B.Cu")
		(net "LAN2_P1_P")
	)
	(segment
		(start 5.515102 -350.335342)
		(end 5.515102 -371.38864)
		(width 0.127)
		(layer "B.Cu")
		(net "LAN2_P1_P")
	)
	(segment
		(start 5.141722 -410.90215)
		(end 5.254498 -410.845762)
		(width 0.127)
		(layer "B.Cu")
		(net "LAN2_P1_P")
	)
	(segment
		(start 3.293364 -349.5294)
		(end 4.70916 -349.5294)
		(width 0.127)
		(layer "B.Cu")
		(net "LAN2_P1_P")
	)
	(segment
		(start 5.255768 -410.845)
		(end 5.312918 -410.67482)
		(width 0.127)
		(layer "B.Cu")
		(net "LAN2_P1_P")
	)
	(segment
		(start 3.794252 -410.90215)
		(end 5.141722 -410.90215)
		(width 0.127)
		(layer "B.Cu")
		(net "LAN2_P1_P")
	)
	(segment
		(start 2.535428 -350.287336)
		(end 3.293364 -349.5294)
		(width 0.127)
		(layer "B.Cu")
		(net "LAN2_P1_P")
	)
	(segment
		(start 4.70916 -349.5294)
		(end 5.515102 -350.335342)
		(width 0.127)
		(layer "B.Cu")
		(net "LAN2_P1_P")
	)
	(segment
		(start 6.814312 -405.190452)
		(end 3.322828 -408.681936)
		(width 0.127)
		(layer "B.Cu")
		(net "LAN2_P1_P")
	)
	(segment
		(start 1.949958 -351.669858)
		(end 2.654554 -351.317052)
		(width 0.127)
		(layer "B.Cu")
		(net "LAN2_P1_P")
	)
	(segment
		(start 5.254498 -410.845762)
		(end 5.255768 -410.845)
		(width 0.127)
		(layer "B.Cu")
		(net "LAN2_P1_P")
	)
	(segment
		(start 2.711196 -351.146618)
		(end 2.654554 -351.033334)
		(width 0.127)
		(layer "B.Cu")
		(net "LAN2_P1_P")
	)
	(segment
		(start 3.322828 -408.681936)
		(end 3.322828 -410.430726)
		(width 0.127)
		(layer "B.Cu")
		(net "LAN2_P1_P")
	)
	(segment
		(start 2.654554 -351.033334)
		(end 2.535428 -350.914208)
		(width 0.127)
		(layer "B.Cu")
		(net "LAN2_P1_P")
	)
	(segment
		(start 6.814312 -395.143228)
		(end 6.814312 -405.190452)
		(width 0.127)
		(layer "B.Cu")
		(net "LAN2_P1_P")
	)
	(segment
		(start 2.654554 -351.317052)
		(end 2.711196 -351.146618)
		(width 0.127)
		(layer "B.Cu")
		(net "LAN2_P1_P")
	)
	(segment
		(start 2.535428 -350.914208)
		(end 2.535428 -350.287336)
		(width 0.127)
		(layer "B.Cu")
		(net "LAN2_P1_P")
	)
	(segment
		(start 5.661914 -372.110254)
		(end 5.108702 -371.557042)
		(width 0.127)
		(layer "B.Cu")
		(net "LAN2_P1_N")
	)
	(segment
		(start 6.213856 -396.878302)
		(end 6.407912 -396.684246)
		(width 0.127)
		(layer "B.Cu")
		(net "LAN2_P1_N")
	)
	(segment
		(start 3.018282 -350.85147)
		(end 3.075432 -350.965262)
		(width 0.127)
		(layer "B.Cu")
		(net "LAN2_P1_N")
	)
	(segment
		(start 3.461766 -349.9358)
		(end 2.941828 -350.455738)
		(width 0.127)
		(layer "B.Cu")
		(net "LAN2_P1_N")
	)
	(segment
		(start 6.213856 -396.10919)
		(end 6.213856 -395.72819)
		(width 0.127)
		(layer "B.Cu")
		(net "LAN2_P1_N")
	)
	(segment
		(start 3.018028 -350.85147)
		(end 3.018282 -350.85147)
		(width 0.127)
		(layer "B.Cu")
		(net "LAN2_P1_N")
	)
	(segment
		(start 6.213856 -397.259302)
		(end 6.213856 -396.878302)
		(width 0.127)
		(layer "B.Cu")
		(net "LAN2_P1_N")
	)
	(segment
		(start 3.62585 -411.30855)
		(end 2.916428 -410.599128)
		(width 0.127)
		(layer "B.Cu")
		(net "LAN2_P1_N")
	)
	(segment
		(start 5.60705 -411.265878)
		(end 5.436616 -411.209236)
		(width 0.127)
		(layer "B.Cu")
		(net "LAN2_P1_N")
	)
	(segment
		(start 3.075432 -350.965262)
		(end 3.245866 -351.022412)
		(width 0.127)
		(layer "B.Cu")
		(net "LAN2_P1_N")
	)
	(segment
		(start 2.988564 -350.792542)
		(end 3.018028 -350.85147)
		(width 0.127)
		(layer "B.Cu")
		(net "LAN2_P1_N")
	)
	(segment
		(start 5.661914 -394.565632)
		(end 5.661914 -372.110254)
		(width 0.127)
		(layer "B.Cu")
		(net "LAN2_P1_N")
	)
	(segment
		(start 4.540758 -349.9358)
		(end 3.461766 -349.9358)
		(width 0.127)
		(layer "B.Cu")
		(net "LAN2_P1_N")
	)
	(segment
		(start 6.407912 -405.02205)
		(end 6.407912 -397.453358)
		(width 0.127)
		(layer "B.Cu")
		(net "LAN2_P1_N")
	)
	(segment
		(start 6.09473 -412.239968)
		(end 5.60705 -411.265878)
		(width 0.127)
		(layer "B.Cu")
		(net "LAN2_P1_N")
	)
	(segment
		(start 5.436616 -411.209236)
		(end 5.323586 -411.265878)
		(width 0.127)
		(layer "B.Cu")
		(net "LAN2_P1_N")
	)
	(segment
		(start 2.916428 -408.513534)
		(end 6.407912 -405.02205)
		(width 0.127)
		(layer "B.Cu")
		(net "LAN2_P1_N")
	)
	(segment
		(start 5.108702 -350.503744)
		(end 4.540758 -349.9358)
		(width 0.127)
		(layer "B.Cu")
		(net "LAN2_P1_N")
	)
	(segment
		(start 6.407912 -396.303246)
		(end 6.213856 -396.10919)
		(width 0.127)
		(layer "B.Cu")
		(net "LAN2_P1_N")
	)
	(segment
		(start 2.941828 -350.455738)
		(end 2.941828 -350.745806)
		(width 0.127)
		(layer "B.Cu")
		(net "LAN2_P1_N")
	)
	(segment
		(start 6.213856 -395.72819)
		(end 6.407912 -395.534134)
		(width 0.127)
		(layer "B.Cu")
		(net "LAN2_P1_N")
	)
	(segment
		(start 6.407912 -395.534134)
		(end 6.407912 -395.31163)
		(width 0.127)
		(layer "B.Cu")
		(net "LAN2_P1_N")
	)
	(segment
		(start 5.108702 -371.557042)
		(end 5.108702 -350.503744)
		(width 0.127)
		(layer "B.Cu")
		(net "LAN2_P1_N")
	)
	(segment
		(start 2.941828 -350.745806)
		(end 2.988564 -350.792542)
		(width 0.127)
		(layer "B.Cu")
		(net "LAN2_P1_N")
	)
	(segment
		(start 6.407912 -396.684246)
		(end 6.407912 -396.303246)
		(width 0.127)
		(layer "B.Cu")
		(net "LAN2_P1_N")
	)
	(segment
		(start 6.407912 -395.31163)
		(end 5.661914 -394.565632)
		(width 0.127)
		(layer "B.Cu")
		(net "LAN2_P1_N")
	)
	(segment
		(start 3.245866 -351.022412)
		(end 3.949954 -350.66986)
		(width 0.127)
		(layer "B.Cu")
		(net "LAN2_P1_N")
	)
	(segment
		(start 5.237988 -411.30855)
		(end 3.62585 -411.30855)
		(width 0.127)
		(layer "B.Cu")
		(net "LAN2_P1_N")
	)
	(segment
		(start 6.407912 -397.453358)
		(end 6.213856 -397.259302)
		(width 0.127)
		(layer "B.Cu")
		(net "LAN2_P1_N")
	)
	(segment
		(start 2.916428 -410.599128)
		(end 2.916428 -408.513534)
		(width 0.127)
		(layer "B.Cu")
		(net "LAN2_P1_N")
	)
	(segment
		(start 5.323586 -411.265878)
		(end 5.237988 -411.30855)
		(width 0.127)
		(layer "B.Cu")
		(net "LAN2_P1_N")
	)
	(via
		(at 14.509496 -171.533058)
		(size 0.508)
		(drill 0.254)
		(layers "F.Cu" "B.Cu")
		(net "GND61")
	)
	(segment
		(start 10.323576 -190.677546)
		(end 13.209524 -187.791598)
		(width 0.1524)
		(layer "B.Cu")
		(net "GND61")
	)
	(segment
		(start 13.209524 -172.07865)
		(end 13.755116 -171.533058)
		(width 0.1524)
		(layer "B.Cu")
		(net "GND61")
	)
	(segment
		(start 13.755116 -171.533058)
		(end 14.509496 -171.533058)
		(width 0.1524)
		(layer "B.Cu")
		(net "GND61")
	)
	(segment
		(start 8.448802 -190.670434)
		(end 8.455914 -190.677546)
		(width 0.1524)
		(layer "B.Cu")
		(net "GND61")
	)
	(segment
		(start 8.455914 -190.677546)
		(end 10.323576 -190.677546)
		(width 0.1524)
		(layer "B.Cu")
		(net "GND61")
	)
	(segment
		(start 13.209524 -187.791598)
		(end 13.209524 -172.07865)
		(width 0.1524)
		(layer "B.Cu")
		(net "GND61")
	)
	(via
		(at 11.93292 -335.494122)
		(size 0.508)
		(drill 0.254)
		(layers "F.Cu" "B.Cu")
		(net "GND37")
	)
	(segment
		(start 10.757154 -336.669888)
		(end 11.93292 -335.494122)
		(width 0.127)
		(layer "In2.Cu")
		(net "GND37")
	)
	(segment
		(start 6.449822 -336.669888)
		(end 10.757154 -336.669888)
		(width 0.127)
		(layer "In2.Cu")
		(net "GND37")
	)
	(via
		(at 11.93292 -334.224122)
		(size 0.508)
		(drill 0.254)
		(layers "F.Cu" "B.Cu")
		(net "GND4")
	)
	(segment
		(start 1.949958 -335.66989)
		(end 7.121906 -335.66989)
		(width 0.127)
		(layer "In2.Cu")
		(net "GND4")
	)
	(segment
		(start 11.283188 -334.873854)
		(end 11.93292 -334.224122)
		(width 0.127)
		(layer "In2.Cu")
		(net "GND4")
	)
	(segment
		(start 7.917942 -334.873854)
		(end 11.283188 -334.873854)
		(width 0.127)
		(layer "In2.Cu")
		(net "GND4")
	)
	(segment
		(start 7.121906 -335.66989)
		(end 7.917942 -334.873854)
		(width 0.127)
		(layer "In2.Cu")
		(net "GND4")
	)
	(via
		(at 11.93292 -336.764122)
		(size 0.508)
		(drill 0.254)
		(layers "F.Cu" "B.Cu")
		(net "GND3")
	)
	(segment
		(start 10.183622 -338.51342)
		(end 11.93292 -336.764122)
		(width 0.127)
		(layer "In2.Cu")
		(net "GND3")
	)
	(segment
		(start 4.833112 -337.786726)
		(end 7.091934 -337.786726)
		(width 0.127)
		(layer "In2.Cu")
		(net "GND3")
	)
	(segment
		(start 7.818628 -338.51342)
		(end 10.183622 -338.51342)
		(width 0.127)
		(layer "In2.Cu")
		(net "GND3")
	)
	(segment
		(start 7.091934 -337.786726)
		(end 7.818628 -338.51342)
		(width 0.127)
		(layer "In2.Cu")
		(net "GND3")
	)
	(segment
		(start 3.949954 -338.669884)
		(end 4.833112 -337.786726)
		(width 0.127)
		(layer "In2.Cu")
		(net "GND3")
	)
	(segment
		(start 2.534412 -187.326016)
		(end 3.468116 -186.392312)
		(width 0.127)
		(layer "B.Cu")
		(net "LAN1_P3_P")
	)
	(segment
		(start 12.149074 -133.087872)
		(end 12.149074 -131.478528)
		(width 0.127)
		(layer "B.Cu")
		(net "LAN1_P3_P")
	)
	(segment
		(start 10.63625 -159.086804)
		(end 10.63625 -157.701234)
		(width 0.127)
		(layer "B.Cu")
		(net "LAN1_P3_P")
	)
	(segment
		(start 10.370058 -163.236148)
		(end 10.63625 -162.969956)
		(width 0.127)
		(layer "B.Cu")
		(net "LAN1_P3_P")
	)
	(segment
		(start 2.653538 -188.033914)
		(end 2.534412 -187.914788)
		(width 0.127)
		(layer "B.Cu")
		(net "LAN1_P3_P")
	)
	(segment
		(start 10.370058 -161.02838)
		(end 10.370058 -160.64738)
		(width 0.127)
		(layer "B.Cu")
		(net "LAN1_P3_P")
	)
	(segment
		(start 10.63625 -161.675572)
		(end 10.63625 -161.294572)
		(width 0.127)
		(layer "B.Cu")
		(net "LAN1_P3_P")
	)
	(segment
		(start 7.024116 -186.392312)
		(end 8.081264 -187.44946)
		(width 0.127)
		(layer "B.Cu")
		(net "LAN1_P3_P")
	)
	(segment
		(start 10.63625 -165.177724)
		(end 10.370058 -164.911532)
		(width 0.127)
		(layer "B.Cu")
		(net "LAN1_P3_P")
	)
	(segment
		(start 10.63625 -186.25185)
		(end 10.63625 -166.472108)
		(width 0.127)
		(layer "B.Cu")
		(net "LAN1_P3_P")
	)
	(segment
		(start 10.370058 -159.352996)
		(end 10.63625 -159.086804)
		(width 0.127)
		(layer "B.Cu")
		(net "LAN1_P3_P")
	)
	(segment
		(start 10.370058 -159.733996)
		(end 10.370058 -159.352996)
		(width 0.127)
		(layer "B.Cu")
		(net "LAN1_P3_P")
	)
	(segment
		(start 10.63625 -157.701234)
		(end 9.99744 -157.062424)
		(width 0.127)
		(layer "B.Cu")
		(net "LAN1_P3_P")
	)
	(segment
		(start 2.71018 -188.147198)
		(end 2.653538 -188.033914)
		(width 0.127)
		(layer "B.Cu")
		(net "LAN1_P3_P")
	)
	(segment
		(start 9.43864 -187.44946)
		(end 10.63625 -186.25185)
		(width 0.127)
		(layer "B.Cu")
		(net "LAN1_P3_P")
	)
	(segment
		(start 10.63625 -162.969956)
		(end 10.63625 -162.588956)
		(width 0.127)
		(layer "B.Cu")
		(net "LAN1_P3_P")
	)
	(segment
		(start 10.63625 -161.294572)
		(end 10.370058 -161.02838)
		(width 0.127)
		(layer "B.Cu")
		(net "LAN1_P3_P")
	)
	(segment
		(start 9.331198 -128.0287)
		(end 8.90651 -128.453388)
		(width 0.127)
		(layer "B.Cu")
		(net "LAN1_P3_P")
	)
	(segment
		(start 9.133332 -130.184906)
		(end 9.246108 -130.241294)
		(width 0.127)
		(layer "B.Cu")
		(net "LAN1_P3_P")
	)
	(segment
		(start 8.90651 -129.958084)
		(end 9.133078 -130.184906)
		(width 0.127)
		(layer "B.Cu")
		(net "LAN1_P3_P")
	)
	(segment
		(start 10.370058 -161.941764)
		(end 10.63625 -161.675572)
		(width 0.127)
		(layer "B.Cu")
		(net "LAN1_P3_P")
	)
	(segment
		(start 10.63625 -160.381188)
		(end 10.63625 -160.000188)
		(width 0.127)
		(layer "B.Cu")
		(net "LAN1_P3_P")
	)
	(segment
		(start 10.370058 -160.64738)
		(end 10.63625 -160.381188)
		(width 0.127)
		(layer "B.Cu")
		(net "LAN1_P3_P")
	)
	(segment
		(start 2.534412 -187.914788)
		(end 2.534412 -187.326016)
		(width 0.127)
		(layer "B.Cu")
		(net "LAN1_P3_P")
	)
	(segment
		(start 10.370058 -163.617148)
		(end 10.370058 -163.236148)
		(width 0.127)
		(layer "B.Cu")
		(net "LAN1_P3_P")
	)
	(segment
		(start 3.468116 -186.392312)
		(end 7.024116 -186.392312)
		(width 0.127)
		(layer "B.Cu")
		(net "LAN1_P3_P")
	)
	(segment
		(start 10.63625 -166.472108)
		(end 10.370058 -166.205916)
		(width 0.127)
		(layer "B.Cu")
		(net "LAN1_P3_P")
	)
	(segment
		(start 11.100562 -128.77165)
		(end 10.357612 -128.0287)
		(width 0.127)
		(layer "B.Cu")
		(net "LAN1_P3_P")
	)
	(segment
		(start 10.63625 -164.26434)
		(end 10.63625 -163.88334)
		(width 0.127)
		(layer "B.Cu")
		(net "LAN1_P3_P")
	)
	(segment
		(start 11.100562 -130.430016)
		(end 11.100562 -128.77165)
		(width 0.127)
		(layer "B.Cu")
		(net "LAN1_P3_P")
	)
	(segment
		(start 9.246108 -130.241294)
		(end 9.416542 -130.184652)
		(width 0.127)
		(layer "B.Cu")
		(net "LAN1_P3_P")
	)
	(segment
		(start 10.63625 -162.588956)
		(end 10.370058 -162.322764)
		(width 0.127)
		(layer "B.Cu")
		(net "LAN1_P3_P")
	)
	(segment
		(start 9.416542 -130.184652)
		(end 9.90473 -129.210054)
		(width 0.127)
		(layer "B.Cu")
		(net "LAN1_P3_P")
	)
	(segment
		(start 10.370058 -162.322764)
		(end 10.370058 -161.941764)
		(width 0.127)
		(layer "B.Cu")
		(net "LAN1_P3_P")
	)
	(segment
		(start 10.63625 -160.000188)
		(end 10.370058 -159.733996)
		(width 0.127)
		(layer "B.Cu")
		(net "LAN1_P3_P")
	)
	(segment
		(start 9.99744 -157.062424)
		(end 9.99744 -135.239506)
		(width 0.127)
		(layer "B.Cu")
		(net "LAN1_P3_P")
	)
	(segment
		(start 10.370058 -166.205916)
		(end 10.370058 -165.824916)
		(width 0.127)
		(layer "B.Cu")
		(net "LAN1_P3_P")
	)
	(segment
		(start 12.149074 -131.478528)
		(end 11.100562 -130.430016)
		(width 0.127)
		(layer "B.Cu")
		(net "LAN1_P3_P")
	)
	(segment
		(start 8.90651 -128.453388)
		(end 8.90651 -129.958084)
		(width 0.127)
		(layer "B.Cu")
		(net "LAN1_P3_P")
	)
	(segment
		(start 9.133078 -130.184906)
		(end 9.133332 -130.184906)
		(width 0.127)
		(layer "B.Cu")
		(net "LAN1_P3_P")
	)
	(segment
		(start 10.370058 -165.824916)
		(end 10.63625 -165.558724)
		(width 0.127)
		(layer "B.Cu")
		(net "LAN1_P3_P")
	)
	(segment
		(start 10.370058 -164.530532)
		(end 10.63625 -164.26434)
		(width 0.127)
		(layer "B.Cu")
		(net "LAN1_P3_P")
	)
	(segment
		(start 10.370058 -164.911532)
		(end 10.370058 -164.530532)
		(width 0.127)
		(layer "B.Cu")
		(net "LAN1_P3_P")
	)
	(segment
		(start 2.653538 -188.317632)
		(end 2.71018 -188.147198)
		(width 0.127)
		(layer "B.Cu")
		(net "LAN1_P3_P")
	)
	(segment
		(start 1.948942 -188.670438)
		(end 2.653538 -188.317632)
		(width 0.127)
		(layer "B.Cu")
		(net "LAN1_P3_P")
	)
	(segment
		(start 10.357612 -128.0287)
		(end 9.331198 -128.0287)
		(width 0.127)
		(layer "B.Cu")
		(net "LAN1_P3_P")
	)
	(segment
		(start 10.63625 -165.558724)
		(end 10.63625 -165.177724)
		(width 0.127)
		(layer "B.Cu")
		(net "LAN1_P3_P")
	)
	(segment
		(start 9.99744 -135.239506)
		(end 12.149074 -133.087872)
		(width 0.127)
		(layer "B.Cu")
		(net "LAN1_P3_P")
	)
	(segment
		(start 8.081264 -187.44946)
		(end 9.43864 -187.44946)
		(width 0.127)
		(layer "B.Cu")
		(net "LAN1_P3_P")
	)
	(segment
		(start 10.63625 -163.88334)
		(end 10.370058 -163.617148)
		(width 0.127)
		(layer "B.Cu")
		(net "LAN1_P3_P")
	)
	(segment
		(start 6.583172 -146.62785)
		(end 6.94817 -146.262852)
		(width 0.127)
		(layer "B.Cu")
		(net "LAN1_P4_P")
	)
	(segment
		(start 6.94817 -150.320248)
		(end 6.583172 -149.95525)
		(width 0.127)
		(layer "B.Cu")
		(net "LAN1_P4_P")
	)
	(segment
		(start 4.928108 -131.170426)
		(end 5.322824 -130.775456)
		(width 0.127)
		(layer "B.Cu")
		(net "LAN1_P4_P")
	)
	(segment
		(start 7.452868 -177.668174)
		(end 7.452868 -176.425606)
		(width 0.127)
		(layer "B.Cu")
		(net "LAN1_P4_P")
	)
	(segment
		(start 3.410712 -182.88762)
		(end 4.432046 -182.88762)
		(width 0.127)
		(layer "B.Cu")
		(net "LAN1_P4_P")
	)
	(segment
		(start 5.539486 -144.26565)
		(end 5.666486 -144.13865)
		(width 0.127)
		(layer "B.Cu")
		(net "LAN1_P4_P")
	)
	(segment
		(start 6.583172 -144.13865)
		(end 6.94817 -143.773652)
		(width 0.127)
		(layer "B.Cu")
		(net "LAN1_P4_P")
	)
	(segment
		(start 6.94817 -175.920908)
		(end 6.94817 -150.320248)
		(width 0.127)
		(layer "B.Cu")
		(net "LAN1_P4_P")
	)
	(segment
		(start 5.666486 -146.62785)
		(end 6.583172 -146.62785)
		(width 0.127)
		(layer "B.Cu")
		(net "LAN1_P4_P")
	)
	(segment
		(start 5.666486 -144.13865)
		(end 6.583172 -144.13865)
		(width 0.127)
		(layer "B.Cu")
		(net "LAN1_P4_P")
	)
	(segment
		(start 6.94817 -134.714996)
		(end 4.928108 -132.694934)
		(width 0.127)
		(layer "B.Cu")
		(net "LAN1_P4_P")
	)
	(segment
		(start 5.539486 -149.82825)
		(end 5.539486 -149.24405)
		(width 0.127)
		(layer "B.Cu")
		(net "LAN1_P4_P")
	)
	(segment
		(start 5.666486 -147.46605)
		(end 5.539486 -147.33905)
		(width 0.127)
		(layer "B.Cu")
		(net "LAN1_P4_P")
	)
	(segment
		(start 3.21818 -185.15457)
		(end 3.317494 -184.955942)
		(width 0.127)
		(layer "B.Cu")
		(net "LAN1_P4_P")
	)
	(segment
		(start 3.274822 -185.325004)
		(end 3.21818 -185.15457)
		(width 0.127)
		(layer "B.Cu")
		(net "LAN1_P4_P")
	)
	(segment
		(start 6.583172 -147.46605)
		(end 5.666486 -147.46605)
		(width 0.127)
		(layer "B.Cu")
		(net "LAN1_P4_P")
	)
	(segment
		(start 4.928108 -132.694934)
		(end 4.928108 -131.170426)
		(width 0.127)
		(layer "B.Cu")
		(net "LAN1_P4_P")
	)
	(segment
		(start 5.539486 -146.75485)
		(end 5.666486 -146.62785)
		(width 0.127)
		(layer "B.Cu")
		(net "LAN1_P4_P")
	)
	(segment
		(start 6.94817 -148.752052)
		(end 6.94817 -147.831048)
		(width 0.127)
		(layer "B.Cu")
		(net "LAN1_P4_P")
	)
	(segment
		(start 5.539486 -149.24405)
		(end 5.666486 -149.11705)
		(width 0.127)
		(layer "B.Cu")
		(net "LAN1_P4_P")
	)
	(segment
		(start 5.539486 -144.84985)
		(end 5.539486 -144.26565)
		(width 0.127)
		(layer "B.Cu")
		(net "LAN1_P4_P")
	)
	(segment
		(start 6.94817 -145.341848)
		(end 6.583172 -144.97685)
		(width 0.127)
		(layer "B.Cu")
		(net "LAN1_P4_P")
	)
	(segment
		(start 6.583172 -149.11705)
		(end 6.94817 -148.752052)
		(width 0.127)
		(layer "B.Cu")
		(net "LAN1_P4_P")
	)
	(segment
		(start 6.94817 -146.262852)
		(end 6.94817 -145.341848)
		(width 0.127)
		(layer "B.Cu")
		(net "LAN1_P4_P")
	)
	(segment
		(start 5.21335 -182.106316)
		(end 5.21335 -179.907692)
		(width 0.127)
		(layer "B.Cu")
		(net "LAN1_P4_P")
	)
	(segment
		(start 6.94817 -143.773652)
		(end 6.94817 -134.714996)
		(width 0.127)
		(layer "B.Cu")
		(net "LAN1_P4_P")
	)
	(segment
		(start 5.666486 -144.97685)
		(end 5.539486 -144.84985)
		(width 0.127)
		(layer "B.Cu")
		(net "LAN1_P4_P")
	)
	(segment
		(start 3.948938 -185.670444)
		(end 3.274822 -185.325004)
		(width 0.127)
		(layer "B.Cu")
		(net "LAN1_P4_P")
	)
	(segment
		(start 3.102864 -184.07888)
		(end 3.102864 -183.195468)
		(width 0.127)
		(layer "B.Cu")
		(net "LAN1_P4_P")
	)
	(segment
		(start 6.583172 -144.97685)
		(end 5.666486 -144.97685)
		(width 0.127)
		(layer "B.Cu")
		(net "LAN1_P4_P")
	)
	(segment
		(start 6.94817 -147.831048)
		(end 6.583172 -147.46605)
		(width 0.127)
		(layer "B.Cu")
		(net "LAN1_P4_P")
	)
	(segment
		(start 3.317494 -184.955942)
		(end 3.317494 -184.29351)
		(width 0.127)
		(layer "B.Cu")
		(net "LAN1_P4_P")
	)
	(segment
		(start 6.583172 -149.95525)
		(end 5.666486 -149.95525)
		(width 0.127)
		(layer "B.Cu")
		(net "LAN1_P4_P")
	)
	(segment
		(start 3.317494 -184.29351)
		(end 3.102864 -184.07888)
		(width 0.127)
		(layer "B.Cu")
		(net "LAN1_P4_P")
	)
	(segment
		(start 5.21335 -179.907692)
		(end 7.452868 -177.668174)
		(width 0.127)
		(layer "B.Cu")
		(net "LAN1_P4_P")
	)
	(segment
		(start 3.102864 -183.195468)
		(end 3.410712 -182.88762)
		(width 0.127)
		(layer "B.Cu")
		(net "LAN1_P4_P")
	)
	(segment
		(start 5.666486 -149.95525)
		(end 5.539486 -149.82825)
		(width 0.127)
		(layer "B.Cu")
		(net "LAN1_P4_P")
	)
	(segment
		(start 7.452868 -176.425606)
		(end 6.94817 -175.920908)
		(width 0.127)
		(layer "B.Cu")
		(net "LAN1_P4_P")
	)
	(segment
		(start 5.606542 -130.775456)
		(end 6.09473 -131.750054)
		(width 0.127)
		(layer "B.Cu")
		(net "LAN1_P4_P")
	)
	(segment
		(start 5.436108 -130.718814)
		(end 5.606542 -130.775456)
		(width 0.127)
		(layer "B.Cu")
		(net "LAN1_P4_P")
	)
	(segment
		(start 4.432046 -182.88762)
		(end 5.21335 -182.106316)
		(width 0.127)
		(layer "B.Cu")
		(net "LAN1_P4_P")
	)
	(segment
		(start 5.322824 -130.775456)
		(end 5.436108 -130.718814)
		(width 0.127)
		(layer "B.Cu")
		(net "LAN1_P4_P")
	)
	(segment
		(start 5.666486 -149.11705)
		(end 6.583172 -149.11705)
		(width 0.127)
		(layer "B.Cu")
		(net "LAN1_P4_P")
	)
	(segment
		(start 5.539486 -147.33905)
		(end 5.539486 -146.75485)
		(width 0.127)
		(layer "B.Cu")
		(net "LAN1_P4_P")
	)
	(segment
		(start 2.661158 -181.958234)
		(end 1.948942 -182.67045)
		(width 0.1524)
		(layer "F.Cu")
		(net "CM_PWR_CTL_IN")
	)
	(segment
		(start 1.40335 -161.050986)
		(end 2.661158 -162.308794)
		(width 0.1524)
		(layer "F.Cu")
		(net "CM_PWR_CTL_IN")
	)
	(segment
		(start 2.439924 -152.374854)
		(end 1.40335 -153.411428)
		(width 0.1524)
		(layer "F.Cu")
		(net "CM_PWR_CTL_IN")
	)
	(segment
		(start 1.40335 -153.411428)
		(end 1.40335 -161.050986)
		(width 0.1524)
		(layer "F.Cu")
		(net "CM_PWR_CTL_IN")
	)
	(segment
		(start 2.661158 -162.308794)
		(end 2.661158 -181.958234)
		(width 0.1524)
		(layer "F.Cu")
		(net "CM_PWR_CTL_IN")
	)
	(segment
		(start 9.162796 -127.6223)
		(end 8.50011 -128.284986)
		(width 0.127)
		(layer "B.Cu")
		(net "LAN1_P3_N")
	)
	(segment
		(start 8.50011 -128.284986)
		(end 8.50011 -130.126486)
		(width 0.127)
		(layer "B.Cu")
		(net "LAN1_P3_N")
	)
	(segment
		(start 8.951214 -130.54838)
		(end 9.06399 -130.604768)
		(width 0.127)
		(layer "B.Cu")
		(net "LAN1_P3_N")
	)
	(segment
		(start 3.017266 -187.85205)
		(end 3.017012 -187.85205)
		(width 0.127)
		(layer "B.Cu")
		(net "LAN1_P3_N")
	)
	(segment
		(start 10.40384 -135.407908)
		(end 12.555474 -133.256274)
		(width 0.127)
		(layer "B.Cu")
		(net "LAN1_P3_N")
	)
	(segment
		(start 9.06526 -130.60553)
		(end 9.12241 -130.775964)
		(width 0.127)
		(layer "B.Cu")
		(net "LAN1_P3_N")
	)
	(segment
		(start 3.017012 -187.85205)
		(end 2.987548 -187.793122)
		(width 0.127)
		(layer "B.Cu")
		(net "LAN1_P3_N")
	)
	(segment
		(start 2.940812 -187.494418)
		(end 3.636518 -186.798712)
		(width 0.127)
		(layer "B.Cu")
		(net "LAN1_P3_N")
	)
	(segment
		(start 11.506962 -130.261614)
		(end 11.506962 -128.603248)
		(width 0.127)
		(layer "B.Cu")
		(net "LAN1_P3_N")
	)
	(segment
		(start 2.940812 -187.746386)
		(end 2.940812 -187.494418)
		(width 0.127)
		(layer "B.Cu")
		(net "LAN1_P3_N")
	)
	(segment
		(start 11.04265 -186.420252)
		(end 11.04265 -157.532832)
		(width 0.127)
		(layer "B.Cu")
		(net "LAN1_P3_N")
	)
	(segment
		(start 11.04265 -157.532832)
		(end 10.40384 -156.894022)
		(width 0.127)
		(layer "B.Cu")
		(net "LAN1_P3_N")
	)
	(segment
		(start 3.074416 -187.965842)
		(end 3.017266 -187.85205)
		(width 0.127)
		(layer "B.Cu")
		(net "LAN1_P3_N")
	)
	(segment
		(start 7.912862 -187.85586)
		(end 9.607042 -187.85586)
		(width 0.127)
		(layer "B.Cu")
		(net "LAN1_P3_N")
	)
	(segment
		(start 3.948938 -187.67044)
		(end 3.24485 -188.022992)
		(width 0.127)
		(layer "B.Cu")
		(net "LAN1_P3_N")
	)
	(segment
		(start 3.636518 -186.798712)
		(end 6.855714 -186.798712)
		(width 0.127)
		(layer "B.Cu")
		(net "LAN1_P3_N")
	)
	(segment
		(start 10.40384 -156.894022)
		(end 10.40384 -135.407908)
		(width 0.127)
		(layer "B.Cu")
		(net "LAN1_P3_N")
	)
	(segment
		(start 9.06399 -130.604768)
		(end 9.06526 -130.60553)
		(width 0.127)
		(layer "B.Cu")
		(net "LAN1_P3_N")
	)
	(segment
		(start 9.12241 -130.775964)
		(end 8.63473 -131.750054)
		(width 0.127)
		(layer "B.Cu")
		(net "LAN1_P3_N")
	)
	(segment
		(start 9.607042 -187.85586)
		(end 11.04265 -186.420252)
		(width 0.127)
		(layer "B.Cu")
		(net "LAN1_P3_N")
	)
	(segment
		(start 10.526014 -127.6223)
		(end 9.162796 -127.6223)
		(width 0.127)
		(layer "B.Cu")
		(net "LAN1_P3_N")
	)
	(segment
		(start 8.50011 -130.126486)
		(end 8.892032 -130.518662)
		(width 0.127)
		(layer "B.Cu")
		(net "LAN1_P3_N")
	)
	(segment
		(start 6.855714 -186.798712)
		(end 7.912862 -187.85586)
		(width 0.127)
		(layer "B.Cu")
		(net "LAN1_P3_N")
	)
	(segment
		(start 3.24485 -188.022992)
		(end 3.074416 -187.965842)
		(width 0.127)
		(layer "B.Cu")
		(net "LAN1_P3_N")
	)
	(segment
		(start 12.555474 -133.256274)
		(end 12.555474 -131.310126)
		(width 0.127)
		(layer "B.Cu")
		(net "LAN1_P3_N")
	)
	(segment
		(start 11.506962 -128.603248)
		(end 10.526014 -127.6223)
		(width 0.127)
		(layer "B.Cu")
		(net "LAN1_P3_N")
	)
	(segment
		(start 12.555474 -131.310126)
		(end 11.506962 -130.261614)
		(width 0.127)
		(layer "B.Cu")
		(net "LAN1_P3_N")
	)
	(segment
		(start 8.892032 -130.518662)
		(end 8.951214 -130.54838)
		(width 0.127)
		(layer "B.Cu")
		(net "LAN1_P3_N")
	)
	(segment
		(start 2.987548 -187.793122)
		(end 2.940812 -187.746386)
		(width 0.127)
		(layer "B.Cu")
		(net "LAN1_P3_N")
	)
	(segment
		(start 5.082032 -130.441446)
		(end 5.25399 -130.35534)
		(width 0.127)
		(layer "B.Cu")
		(net "LAN1_P4_N")
	)
	(segment
		(start 5.31241 -130.184144)
		(end 4.82473 -129.210054)
		(width 0.127)
		(layer "B.Cu")
		(net "LAN1_P4_N")
	)
	(segment
		(start 4.521708 -132.863336)
		(end 4.521708 -131.002024)
		(width 0.127)
		(layer "B.Cu")
		(net "LAN1_P4_N")
	)
	(segment
		(start 2.854452 -184.97296)
		(end 2.911094 -184.85993)
		(width 0.127)
		(layer "B.Cu")
		(net "LAN1_P4_N")
	)
	(segment
		(start 5.133086 -144.097248)
		(end 5.498084 -143.73225)
		(width 0.127)
		(layer "B.Cu")
		(net "LAN1_P4_N")
	)
	(segment
		(start 5.133086 -147.507452)
		(end 5.133086 -146.586448)
		(width 0.127)
		(layer "B.Cu")
		(net "LAN1_P4_N")
	)
	(segment
		(start 6.54177 -146.09445)
		(end 6.54177 -145.51025)
		(width 0.127)
		(layer "B.Cu")
		(net "LAN1_P4_N")
	)
	(segment
		(start 7.046468 -176.594008)
		(end 6.54177 -176.08931)
		(width 0.127)
		(layer "B.Cu")
		(net "LAN1_P4_N")
	)
	(segment
		(start 5.133086 -149.996652)
		(end 5.133086 -149.075648)
		(width 0.127)
		(layer "B.Cu")
		(net "LAN1_P4_N")
	)
	(segment
		(start 6.41477 -147.87245)
		(end 5.498084 -147.87245)
		(width 0.127)
		(layer "B.Cu")
		(net "LAN1_P4_N")
	)
	(segment
		(start 5.498084 -143.73225)
		(end 6.41477 -143.73225)
		(width 0.127)
		(layer "B.Cu")
		(net "LAN1_P4_N")
	)
	(segment
		(start 6.41477 -143.73225)
		(end 6.54177 -143.60525)
		(width 0.127)
		(layer "B.Cu")
		(net "LAN1_P4_N")
	)
	(segment
		(start 5.498084 -148.71065)
		(end 6.41477 -148.71065)
		(width 0.127)
		(layer "B.Cu")
		(net "LAN1_P4_N")
	)
	(segment
		(start 5.133086 -146.586448)
		(end 5.498084 -146.22145)
		(width 0.127)
		(layer "B.Cu")
		(net "LAN1_P4_N")
	)
	(segment
		(start 5.133086 -145.018252)
		(end 5.133086 -144.097248)
		(width 0.127)
		(layer "B.Cu")
		(net "LAN1_P4_N")
	)
	(segment
		(start 6.41477 -150.36165)
		(end 5.498084 -150.36165)
		(width 0.127)
		(layer "B.Cu")
		(net "LAN1_P4_N")
	)
	(segment
		(start 6.54177 -176.08931)
		(end 6.54177 -150.48865)
		(width 0.127)
		(layer "B.Cu")
		(net "LAN1_P4_N")
	)
	(segment
		(start 4.521708 -131.002024)
		(end 5.082032 -130.441446)
		(width 0.127)
		(layer "B.Cu")
		(net "LAN1_P4_N")
	)
	(segment
		(start 6.54177 -145.51025)
		(end 6.41477 -145.38325)
		(width 0.127)
		(layer "B.Cu")
		(net "LAN1_P4_N")
	)
	(segment
		(start 4.263644 -182.48122)
		(end 4.80695 -181.937914)
		(width 0.127)
		(layer "B.Cu")
		(net "LAN1_P4_N")
	)
	(segment
		(start 6.41477 -146.22145)
		(end 6.54177 -146.09445)
		(width 0.127)
		(layer "B.Cu")
		(net "LAN1_P4_N")
	)
	(segment
		(start 2.911094 -184.85993)
		(end 2.911094 -184.461912)
		(width 0.127)
		(layer "B.Cu")
		(net "LAN1_P4_N")
	)
	(segment
		(start 6.54177 -143.60525)
		(end 6.54177 -134.883398)
		(width 0.127)
		(layer "B.Cu")
		(net "LAN1_P4_N")
	)
	(segment
		(start 5.25526 -130.354578)
		(end 5.31241 -130.184144)
		(width 0.127)
		(layer "B.Cu")
		(net "LAN1_P4_N")
	)
	(segment
		(start 6.54177 -134.883398)
		(end 4.521708 -132.863336)
		(width 0.127)
		(layer "B.Cu")
		(net "LAN1_P4_N")
	)
	(segment
		(start 2.696464 -183.027066)
		(end 3.24231 -182.48122)
		(width 0.127)
		(layer "B.Cu")
		(net "LAN1_P4_N")
	)
	(segment
		(start 4.80695 -179.73929)
		(end 7.046468 -177.499772)
		(width 0.127)
		(layer "B.Cu")
		(net "LAN1_P4_N")
	)
	(segment
		(start 6.54177 -150.48865)
		(end 6.41477 -150.36165)
		(width 0.127)
		(layer "B.Cu")
		(net "LAN1_P4_N")
	)
	(segment
		(start 3.24231 -182.48122)
		(end 4.263644 -182.48122)
		(width 0.127)
		(layer "B.Cu")
		(net "LAN1_P4_N")
	)
	(segment
		(start 4.80695 -181.937914)
		(end 4.80695 -179.73929)
		(width 0.127)
		(layer "B.Cu")
		(net "LAN1_P4_N")
	)
	(segment
		(start 2.68351 -185.030364)
		(end 2.853944 -184.973214)
		(width 0.127)
		(layer "B.Cu")
		(net "LAN1_P4_N")
	)
	(segment
		(start 6.54177 -147.99945)
		(end 6.41477 -147.87245)
		(width 0.127)
		(layer "B.Cu")
		(net "LAN1_P4_N")
	)
	(segment
		(start 5.498084 -147.87245)
		(end 5.133086 -147.507452)
		(width 0.127)
		(layer "B.Cu")
		(net "LAN1_P4_N")
	)
	(segment
		(start 5.133086 -149.075648)
		(end 5.498084 -148.71065)
		(width 0.127)
		(layer "B.Cu")
		(net "LAN1_P4_N")
	)
	(segment
		(start 5.498084 -150.36165)
		(end 5.133086 -149.996652)
		(width 0.127)
		(layer "B.Cu")
		(net "LAN1_P4_N")
	)
	(segment
		(start 6.41477 -145.38325)
		(end 5.498084 -145.38325)
		(width 0.127)
		(layer "B.Cu")
		(net "LAN1_P4_N")
	)
	(segment
		(start 2.911094 -184.461912)
		(end 2.696464 -184.247282)
		(width 0.127)
		(layer "B.Cu")
		(net "LAN1_P4_N")
	)
	(segment
		(start 5.498084 -145.38325)
		(end 5.133086 -145.018252)
		(width 0.127)
		(layer "B.Cu")
		(net "LAN1_P4_N")
	)
	(segment
		(start 5.25399 -130.35534)
		(end 5.25526 -130.354578)
		(width 0.127)
		(layer "B.Cu")
		(net "LAN1_P4_N")
	)
	(segment
		(start 1.948942 -184.670446)
		(end 2.68351 -185.030364)
		(width 0.127)
		(layer "B.Cu")
		(net "LAN1_P4_N")
	)
	(segment
		(start 2.853944 -184.973214)
		(end 2.854452 -184.97296)
		(width 0.127)
		(layer "B.Cu")
		(net "LAN1_P4_N")
	)
	(segment
		(start 6.54177 -148.58365)
		(end 6.54177 -147.99945)
		(width 0.127)
		(layer "B.Cu")
		(net "LAN1_P4_N")
	)
	(segment
		(start 6.41477 -148.71065)
		(end 6.54177 -148.58365)
		(width 0.127)
		(layer "B.Cu")
		(net "LAN1_P4_N")
	)
	(segment
		(start 2.696464 -184.247282)
		(end 2.696464 -183.027066)
		(width 0.127)
		(layer "B.Cu")
		(net "LAN1_P4_N")
	)
	(segment
		(start 7.046468 -177.499772)
		(end 7.046468 -176.594008)
		(width 0.127)
		(layer "B.Cu")
		(net "LAN1_P4_N")
	)
	(segment
		(start 5.498084 -146.22145)
		(end 6.41477 -146.22145)
		(width 0.127)
		(layer "B.Cu")
		(net "LAN1_P4_N")
	)
	(segment
		(start 10.738612 -190.088012)
		(end 10.738612 -178.552602)
		(width 0.127)
		(layer "In2.Cu")
		(net "UART_RX_P1_L")
	)
	(segment
		(start 10.738612 -178.552602)
		(end 20.287234 -169.00398)
		(width 0.127)
		(layer "In2.Cu")
		(net "UART_RX_P1_L")
	)
	(segment
		(start 4.454906 -198.670418)
		(end 4.99364 -198.131684)
		(width 0.127)
		(layer "In2.Cu")
		(net "UART_RX_P1_L")
	)
	(segment
		(start 7.087108 -192.772538)
		(end 7.9121 -191.947546)
		(width 0.127)
		(layer "In2.Cu")
		(net "UART_RX_P1_L")
	)
	(segment
		(start 10.422636 -32.992822)
		(end 10.422636 -13.284708)
		(width 0.127)
		(layer "In2.Cu")
		(net "UART_RX_P1_L")
	)
	(segment
		(start 6.126226 -192.772538)
		(end 7.087108 -192.772538)
		(width 0.127)
		(layer "In2.Cu")
		(net "UART_RX_P1_L")
	)
	(segment
		(start 10.422636 -13.284708)
		(end 10.85469 -12.852654)
		(width 0.127)
		(layer "In2.Cu")
		(net "UART_RX_P1_L")
	)
	(segment
		(start 15.33017 -104.594152)
		(end 11.766042 -101.030024)
		(width 0.127)
		(layer "In2.Cu")
		(net "UART_RX_P1_L")
	)
	(segment
		(start 20.287234 -169.00398)
		(end 20.287234 -131.671314)
		(width 0.127)
		(layer "In2.Cu")
		(net "UART_RX_P1_L")
	)
	(segment
		(start 17.859502 -60.622688)
		(end 17.859502 -40.429688)
		(width 0.127)
		(layer "In2.Cu")
		(net "UART_RX_P1_L")
	)
	(segment
		(start 11.766042 -101.030024)
		(end 11.766042 -66.716148)
		(width 0.127)
		(layer "In2.Cu")
		(net "UART_RX_P1_L")
	)
	(segment
		(start 1.948942 -198.670418)
		(end 4.454906 -198.670418)
		(width 0.127)
		(layer "In2.Cu")
		(net "UART_RX_P1_L")
	)
	(segment
		(start 4.99364 -198.131684)
		(end 4.99364 -193.905124)
		(width 0.127)
		(layer "In2.Cu")
		(net "UART_RX_P1_L")
	)
	(segment
		(start 10.16254 -115.106196)
		(end 15.33017 -109.938566)
		(width 0.127)
		(layer "In2.Cu")
		(net "UART_RX_P1_L")
	)
	(segment
		(start 11.766042 -66.716148)
		(end 17.859502 -60.622688)
		(width 0.127)
		(layer "In2.Cu")
		(net "UART_RX_P1_L")
	)
	(segment
		(start 8.879078 -191.947546)
		(end 10.738612 -190.088012)
		(width 0.127)
		(layer "In2.Cu")
		(net "UART_RX_P1_L")
	)
	(segment
		(start 10.85469 -12.852654)
		(end 10.85469 -8.878062)
		(width 0.127)
		(layer "In2.Cu")
		(net "UART_RX_P1_L")
	)
	(segment
		(start 20.287234 -131.671314)
		(end 10.16254 -121.54662)
		(width 0.127)
		(layer "In2.Cu")
		(net "UART_RX_P1_L")
	)
	(segment
		(start 10.16254 -121.54662)
		(end 10.16254 -115.106196)
		(width 0.127)
		(layer "In2.Cu")
		(net "UART_RX_P1_L")
	)
	(segment
		(start 17.859502 -40.429688)
		(end 10.422636 -32.992822)
		(width 0.127)
		(layer "In2.Cu")
		(net "UART_RX_P1_L")
	)
	(segment
		(start 15.33017 -109.938566)
		(end 15.33017 -104.594152)
		(width 0.127)
		(layer "In2.Cu")
		(net "UART_RX_P1_L")
	)
	(segment
		(start 4.99364 -193.905124)
		(end 6.126226 -192.772538)
		(width 0.127)
		(layer "In2.Cu")
		(net "UART_RX_P1_L")
	)
	(segment
		(start 7.9121 -191.947546)
		(end 8.879078 -191.947546)
		(width 0.127)
		(layer "In2.Cu")
		(net "UART_RX_P1_L")
	)
	(segment
		(start 4.344924 -192.500758)
		(end 4.946904 -191.898778)
		(width 0.127)
		(layer "In2.Cu")
		(net "UART_DTR_P1_L_N")
	)
	(segment
		(start 9.723374 -178.166522)
		(end 19.296634 -168.593262)
		(width 0.127)
		(layer "In2.Cu")
		(net "UART_DTR_P1_L_N")
	)
	(segment
		(start 1.948942 -196.670422)
		(end 2.710688 -195.908676)
		(width 0.127)
		(layer "In2.Cu")
		(net "UART_DTR_P1_L_N")
	)
	(segment
		(start 14.33957 -105.00487)
		(end 10.775442 -101.440742)
		(width 0.127)
		(layer "In2.Cu")
		(net "UART_DTR_P1_L_N")
	)
	(segment
		(start 9.723374 -188.772546)
		(end 9.723374 -178.166522)
		(width 0.127)
		(layer "In2.Cu")
		(net "UART_DTR_P1_L_N")
	)
	(segment
		(start 10.775442 -101.440742)
		(end 10.775442 -66.305176)
		(width 0.127)
		(layer "In2.Cu")
		(net "UART_DTR_P1_L_N")
	)
	(segment
		(start 2.710688 -193.165222)
		(end 2.726944 -193.148966)
		(width 0.127)
		(layer "In2.Cu")
		(net "UART_DTR_P1_L_N")
	)
	(segment
		(start 4.946904 -191.898778)
		(end 4.946904 -191.403986)
		(width 0.127)
		(layer "In2.Cu")
		(net "UART_DTR_P1_L_N")
	)
	(segment
		(start 2.710688 -195.908676)
		(end 2.710688 -193.165222)
		(width 0.127)
		(layer "In2.Cu")
		(net "UART_DTR_P1_L_N")
	)
	(segment
		(start 6.917182 -190.443104)
		(end 7.82955 -189.530736)
		(width 0.127)
		(layer "In2.Cu")
		(net "UART_DTR_P1_L_N")
	)
	(segment
		(start 4.946904 -191.403986)
		(end 5.907786 -190.443104)
		(width 0.127)
		(layer "In2.Cu")
		(net "UART_DTR_P1_L_N")
	)
	(segment
		(start 9.17194 -121.957338)
		(end 9.17194 -114.695478)
		(width 0.127)
		(layer "In2.Cu")
		(net "UART_DTR_P1_L_N")
	)
	(segment
		(start 16.868902 -60.211716)
		(end 16.868902 -40.84066)
		(width 0.127)
		(layer "In2.Cu")
		(net "UART_DTR_P1_L_N")
	)
	(segment
		(start 14.33957 -109.527848)
		(end 14.33957 -105.00487)
		(width 0.127)
		(layer "In2.Cu")
		(net "UART_DTR_P1_L_N")
	)
	(segment
		(start 9.432036 -33.403794)
		(end 9.432036 -12.535408)
		(width 0.127)
		(layer "In2.Cu")
		(net "UART_DTR_P1_L_N")
	)
	(segment
		(start 19.296634 -168.593262)
		(end 19.296634 -132.082032)
		(width 0.127)
		(layer "In2.Cu")
		(net "UART_DTR_P1_L_N")
	)
	(segment
		(start 7.82955 -189.530736)
		(end 8.965184 -189.530736)
		(width 0.127)
		(layer "In2.Cu")
		(net "UART_DTR_P1_L_N")
	)
	(segment
		(start 19.296634 -132.082032)
		(end 9.17194 -121.957338)
		(width 0.127)
		(layer "In2.Cu")
		(net "UART_DTR_P1_L_N")
	)
	(segment
		(start 5.907786 -190.443104)
		(end 6.917182 -190.443104)
		(width 0.127)
		(layer "In2.Cu")
		(net "UART_DTR_P1_L_N")
	)
	(segment
		(start 16.868902 -40.84066)
		(end 9.432036 -33.403794)
		(width 0.127)
		(layer "In2.Cu")
		(net "UART_DTR_P1_L_N")
	)
	(segment
		(start 2.726944 -193.148966)
		(end 2.726944 -193.148712)
		(width 0.127)
		(layer "In2.Cu")
		(net "UART_DTR_P1_L_N")
	)
	(segment
		(start 2.726944 -193.148712)
		(end 3.374644 -192.500758)
		(width 0.127)
		(layer "In2.Cu")
		(net "UART_DTR_P1_L_N")
	)
	(segment
		(start 8.965184 -189.530736)
		(end 9.723374 -188.772546)
		(width 0.127)
		(layer "In2.Cu")
		(net "UART_DTR_P1_L_N")
	)
	(segment
		(start 9.432036 -12.535408)
		(end 5.77469 -8.878062)
		(width 0.127)
		(layer "In2.Cu")
		(net "UART_DTR_P1_L_N")
	)
	(segment
		(start 3.374644 -192.500758)
		(end 4.344924 -192.500758)
		(width 0.127)
		(layer "In2.Cu")
		(net "UART_DTR_P1_L_N")
	)
	(segment
		(start 10.775442 -66.305176)
		(end 16.868902 -60.211716)
		(width 0.127)
		(layer "In2.Cu")
		(net "UART_DTR_P1_L_N")
	)
	(segment
		(start 9.17194 -114.695478)
		(end 14.33957 -109.527848)
		(width 0.127)
		(layer "In2.Cu")
		(net "UART_DTR_P1_L_N")
	)
	(segment
		(start 9.145524 -64.180212)
		(end 9.993376 -63.33236)
		(width 0.127)
		(layer "In5.Cu")
		(net "UART_RX_P5_L")
	)
	(segment
		(start 4.093718 -206.670656)
		(end 5.046218 -205.718156)
		(width 0.127)
		(layer "In5.Cu")
		(net "UART_RX_P5_L")
	)
	(segment
		(start 2.743454 -104.810052)
		(end 4.279392 -103.274114)
		(width 0.127)
		(layer "In5.Cu")
		(net "UART_RX_P5_L")
	)
	(segment
		(start 5.989828 -192.82664)
		(end 7.16788 -192.82664)
		(width 0.127)
		(layer "In5.Cu")
		(net "UART_RX_P5_L")
	)
	(segment
		(start 17.370044 -129.459228)
		(end 16.356584 -129.459228)
		(width 0.127)
		(layer "In5.Cu")
		(net "UART_RX_P5_L")
	)
	(segment
		(start 9.993376 -62.789308)
		(end 10.85469 -61.927994)
		(width 0.127)
		(layer "In5.Cu")
		(net "UART_RX_P5_L")
	)
	(segment
		(start 2.743454 -109.652308)
		(end 2.743454 -104.810052)
		(width 0.127)
		(layer "In5.Cu")
		(net "UART_RX_P5_L")
	)
	(segment
		(start 1.948942 -206.670656)
		(end 4.093718 -206.670656)
		(width 0.127)
		(layer "In5.Cu")
		(net "UART_RX_P5_L")
	)
	(segment
		(start 8.259826 -115.16868)
		(end 2.743454 -109.652308)
		(width 0.127)
		(layer "In5.Cu")
		(net "UART_RX_P5_L")
	)
	(segment
		(start 7.16788 -192.82664)
		(end 8.05815 -191.93637)
		(width 0.127)
		(layer "In5.Cu")
		(net "UART_RX_P5_L")
	)
	(segment
		(start 12.039092 -170.78198)
		(end 20.719288 -162.10153)
		(width 0.127)
		(layer "In5.Cu")
		(net "UART_RX_P5_L")
	)
	(segment
		(start 5.046218 -205.718156)
		(end 5.046218 -193.77025)
		(width 0.127)
		(layer "In5.Cu")
		(net "UART_RX_P5_L")
	)
	(segment
		(start 8.05815 -191.93637)
		(end 9.712706 -191.93637)
		(width 0.127)
		(layer "In5.Cu")
		(net "UART_RX_P5_L")
	)
	(segment
		(start 4.279392 -103.274114)
		(end 5.833618 -103.274114)
		(width 0.127)
		(layer "In5.Cu")
		(net "UART_RX_P5_L")
	)
	(segment
		(start 11.254232 -190.394844)
		(end 11.254232 -171.56684)
		(width 0.127)
		(layer "In5.Cu")
		(net "UART_RX_P5_L")
	)
	(segment
		(start 9.993376 -63.33236)
		(end 9.993376 -62.789308)
		(width 0.127)
		(layer "In5.Cu")
		(net "UART_RX_P5_L")
	)
	(segment
		(start 20.719288 -132.808472)
		(end 17.370044 -129.459228)
		(width 0.127)
		(layer "In5.Cu")
		(net "UART_RX_P5_L")
	)
	(segment
		(start 9.145524 -99.962208)
		(end 9.145524 -64.180212)
		(width 0.127)
		(layer "In5.Cu")
		(net "UART_RX_P5_L")
	)
	(segment
		(start 8.259826 -121.36247)
		(end 8.259826 -115.16868)
		(width 0.127)
		(layer "In5.Cu")
		(net "UART_RX_P5_L")
	)
	(segment
		(start 20.719288 -162.10153)
		(end 20.719288 -132.808472)
		(width 0.127)
		(layer "In5.Cu")
		(net "UART_RX_P5_L")
	)
	(segment
		(start 5.833618 -103.274114)
		(end 9.145524 -99.962208)
		(width 0.127)
		(layer "In5.Cu")
		(net "UART_RX_P5_L")
	)
	(segment
		(start 11.254232 -171.56684)
		(end 12.039092 -170.78198)
		(width 0.127)
		(layer "In5.Cu")
		(net "UART_RX_P5_L")
	)
	(segment
		(start 5.046218 -193.77025)
		(end 5.989828 -192.82664)
		(width 0.127)
		(layer "In5.Cu")
		(net "UART_RX_P5_L")
	)
	(segment
		(start 16.356584 -129.459228)
		(end 8.259826 -121.36247)
		(width 0.127)
		(layer "In5.Cu")
		(net "UART_RX_P5_L")
	)
	(segment
		(start 9.712706 -191.93637)
		(end 11.254232 -190.394844)
		(width 0.127)
		(layer "In5.Cu")
		(net "UART_RX_P5_L")
	)
	(segment
		(start 11.083036 -32.71901)
		(end 11.083036 -13.872718)
		(width 0.127)
		(layer "In2.Cu")
		(net "UART_RTS_P1_L_N")
	)
	(segment
		(start 18.519902 -60.8965)
		(end 18.519902 -40.155876)
		(width 0.127)
		(layer "In2.Cu")
		(net "UART_RTS_P1_L_N")
	)
	(segment
		(start 11.399012 -191.503046)
		(end 11.399012 -178.826414)
		(width 0.127)
		(layer "In2.Cu")
		(net "UART_RTS_P1_L_N")
	)
	(segment
		(start 11.399012 -178.826414)
		(end 20.947634 -169.277792)
		(width 0.127)
		(layer "In2.Cu")
		(net "UART_RTS_P1_L_N")
	)
	(segment
		(start 10.82294 -115.380262)
		(end 15.99057 -110.212632)
		(width 0.127)
		(layer "In2.Cu")
		(net "UART_RTS_P1_L_N")
	)
	(segment
		(start 20.947634 -169.277792)
		(end 20.947634 -131.397502)
		(width 0.127)
		(layer "In2.Cu")
		(net "UART_RTS_P1_L_N")
	)
	(segment
		(start 20.947634 -131.397502)
		(end 10.82294 -121.272808)
		(width 0.127)
		(layer "In2.Cu")
		(net "UART_RTS_P1_L_N")
	)
	(segment
		(start 9.057386 -193.844672)
		(end 11.399012 -191.503046)
		(width 0.127)
		(layer "In2.Cu")
		(net "UART_RTS_P1_L_N")
	)
	(segment
		(start 5.971286 -194.859148)
		(end 7.14502 -194.859148)
		(width 0.127)
		(layer "In2.Cu")
		(net "UART_RTS_P1_L_N")
	)
	(segment
		(start 12.426442 -100.554536)
		(end 12.426442 -66.98996)
		(width 0.127)
		(layer "In2.Cu")
		(net "UART_RTS_P1_L_N")
	)
	(segment
		(start 4.343146 -200.670414)
		(end 5.65404 -199.35952)
		(width 0.127)
		(layer "In2.Cu")
		(net "UART_RTS_P1_L_N")
	)
	(segment
		(start 13.39469 -11.561064)
		(end 13.39469 -8.878062)
		(width 0.127)
		(layer "In2.Cu")
		(net "UART_RTS_P1_L_N")
	)
	(segment
		(start 8.159496 -193.844672)
		(end 9.057386 -193.844672)
		(width 0.127)
		(layer "In2.Cu")
		(net "UART_RTS_P1_L_N")
	)
	(segment
		(start 15.99057 -104.118664)
		(end 12.426442 -100.554536)
		(width 0.127)
		(layer "In2.Cu")
		(net "UART_RTS_P1_L_N")
	)
	(segment
		(start 11.083036 -13.872718)
		(end 13.39469 -11.561064)
		(width 0.127)
		(layer "In2.Cu")
		(net "UART_RTS_P1_L_N")
	)
	(segment
		(start 12.426442 -66.98996)
		(end 18.519902 -60.8965)
		(width 0.127)
		(layer "In2.Cu")
		(net "UART_RTS_P1_L_N")
	)
	(segment
		(start 18.519902 -40.155876)
		(end 11.083036 -32.71901)
		(width 0.127)
		(layer "In2.Cu")
		(net "UART_RTS_P1_L_N")
	)
	(segment
		(start 1.948942 -200.670414)
		(end 4.343146 -200.670414)
		(width 0.127)
		(layer "In2.Cu")
		(net "UART_RTS_P1_L_N")
	)
	(segment
		(start 5.65404 -195.176394)
		(end 5.971286 -194.859148)
		(width 0.127)
		(layer "In2.Cu")
		(net "UART_RTS_P1_L_N")
	)
	(segment
		(start 15.99057 -110.212632)
		(end 15.99057 -104.118664)
		(width 0.127)
		(layer "In2.Cu")
		(net "UART_RTS_P1_L_N")
	)
	(segment
		(start 7.14502 -194.859148)
		(end 8.159496 -193.844672)
		(width 0.127)
		(layer "In2.Cu")
		(net "UART_RTS_P1_L_N")
	)
	(segment
		(start 10.82294 -121.272808)
		(end 10.82294 -115.380262)
		(width 0.127)
		(layer "In2.Cu")
		(net "UART_RTS_P1_L_N")
	)
	(segment
		(start 5.65404 -199.35952)
		(end 5.65404 -195.176394)
		(width 0.127)
		(layer "In2.Cu")
		(net "UART_RTS_P1_L_N")
	)
	(segment
		(start 6.072886 -190.841122)
		(end 7.082282 -190.841122)
		(width 0.127)
		(layer "In2.Cu")
		(net "UART_CTS_P1_L_N")
	)
	(segment
		(start 17.199102 -60.348622)
		(end 17.199102 -40.7035)
		(width 0.127)
		(layer "In2.Cu")
		(net "UART_CTS_P1_L_N")
	)
	(segment
		(start 6.958076 -8.213344)
		(end 6.1976 -7.452868)
		(width 0.127)
		(layer "In2.Cu")
		(net "UART_CTS_P1_L_N")
	)
	(segment
		(start 19.626834 -168.730168)
		(end 19.626834 -131.945126)
		(width 0.127)
		(layer "In2.Cu")
		(net "UART_CTS_P1_L_N")
	)
	(segment
		(start 11.105642 -101.303836)
		(end 11.105642 -66.442082)
		(width 0.127)
		(layer "In2.Cu")
		(net "UART_CTS_P1_L_N")
	)
	(segment
		(start 9.047226 -189.928754)
		(end 10.078212 -188.897768)
		(width 0.127)
		(layer "In2.Cu")
		(net "UART_CTS_P1_L_N")
	)
	(segment
		(start 3.040888 -194.762628)
		(end 3.040888 -193.397632)
		(width 0.127)
		(layer "In2.Cu")
		(net "UART_CTS_P1_L_N")
	)
	(segment
		(start 10.078212 -178.27879)
		(end 19.626834 -168.730168)
		(width 0.127)
		(layer "In2.Cu")
		(net "UART_CTS_P1_L_N")
	)
	(segment
		(start 19.626834 -131.945126)
		(end 9.50214 -121.820432)
		(width 0.127)
		(layer "In2.Cu")
		(net "UART_CTS_P1_L_N")
	)
	(segment
		(start 5.619496 -7.452868)
		(end 4.50469 -6.338062)
		(width 0.127)
		(layer "In2.Cu")
		(net "UART_CTS_P1_L_N")
	)
	(segment
		(start 7.082282 -190.841122)
		(end 7.99465 -189.928754)
		(width 0.127)
		(layer "In2.Cu")
		(net "UART_CTS_P1_L_N")
	)
	(segment
		(start 3.539744 -192.898776)
		(end 4.510024 -192.898776)
		(width 0.127)
		(layer "In2.Cu")
		(net "UART_CTS_P1_L_N")
	)
	(segment
		(start 3.948938 -195.670678)
		(end 3.040888 -194.762628)
		(width 0.127)
		(layer "In2.Cu")
		(net "UART_CTS_P1_L_N")
	)
	(segment
		(start 17.199102 -40.7035)
		(end 9.762236 -33.266634)
		(width 0.127)
		(layer "In2.Cu")
		(net "UART_CTS_P1_L_N")
	)
	(segment
		(start 9.762236 -11.945112)
		(end 6.958076 -9.140952)
		(width 0.127)
		(layer "In2.Cu")
		(net "UART_CTS_P1_L_N")
	)
	(segment
		(start 9.762236 -33.266634)
		(end 9.762236 -11.945112)
		(width 0.127)
		(layer "In2.Cu")
		(net "UART_CTS_P1_L_N")
	)
	(segment
		(start 9.50214 -121.820432)
		(end 9.50214 -114.832384)
		(width 0.127)
		(layer "In2.Cu")
		(net "UART_CTS_P1_L_N")
	)
	(segment
		(start 3.040888 -193.397632)
		(end 3.539744 -192.898776)
		(width 0.127)
		(layer "In2.Cu")
		(net "UART_CTS_P1_L_N")
	)
	(segment
		(start 11.105642 -66.442082)
		(end 17.199102 -60.348622)
		(width 0.127)
		(layer "In2.Cu")
		(net "UART_CTS_P1_L_N")
	)
	(segment
		(start 10.078212 -188.897768)
		(end 10.078212 -178.27879)
		(width 0.127)
		(layer "In2.Cu")
		(net "UART_CTS_P1_L_N")
	)
	(segment
		(start 5.344922 -192.063878)
		(end 5.344922 -191.569086)
		(width 0.127)
		(layer "In2.Cu")
		(net "UART_CTS_P1_L_N")
	)
	(segment
		(start 4.510024 -192.898776)
		(end 5.344922 -192.063878)
		(width 0.127)
		(layer "In2.Cu")
		(net "UART_CTS_P1_L_N")
	)
	(segment
		(start 6.958076 -9.140952)
		(end 6.958076 -8.213344)
		(width 0.127)
		(layer "In2.Cu")
		(net "UART_CTS_P1_L_N")
	)
	(segment
		(start 7.99465 -189.928754)
		(end 9.047226 -189.928754)
		(width 0.127)
		(layer "In2.Cu")
		(net "UART_CTS_P1_L_N")
	)
	(segment
		(start 14.66977 -104.867964)
		(end 11.105642 -101.303836)
		(width 0.127)
		(layer "In2.Cu")
		(net "UART_CTS_P1_L_N")
	)
	(segment
		(start 9.50214 -114.832384)
		(end 14.66977 -109.664754)
		(width 0.127)
		(layer "In2.Cu")
		(net "UART_CTS_P1_L_N")
	)
	(segment
		(start 5.344922 -191.569086)
		(end 6.072886 -190.841122)
		(width 0.127)
		(layer "In2.Cu")
		(net "UART_CTS_P1_L_N")
	)
	(segment
		(start 6.1976 -7.452868)
		(end 5.619496 -7.452868)
		(width 0.127)
		(layer "In2.Cu")
		(net "UART_CTS_P1_L_N")
	)
	(segment
		(start 14.66977 -109.664754)
		(end 14.66977 -104.867964)
		(width 0.127)
		(layer "In2.Cu")
		(net "UART_CTS_P1_L_N")
	)
	(segment
		(start 15.66037 -104.457246)
		(end 12.096242 -100.893118)
		(width 0.127)
		(layer "In2.Cu")
		(net "UART_DSR_P1_L_N")
	)
	(segment
		(start 12.096242 -100.893118)
		(end 12.096242 -66.853054)
		(width 0.127)
		(layer "In2.Cu")
		(net "UART_DSR_P1_L_N")
	)
	(segment
		(start 5.32384 -195.039488)
		(end 5.83438 -194.528948)
		(width 0.127)
		(layer "In2.Cu")
		(net "UART_DSR_P1_L_N")
	)
	(segment
		(start 5.83438 -194.528948)
		(end 7.008114 -194.528948)
		(width 0.127)
		(layer "In2.Cu")
		(net "UART_DSR_P1_L_N")
	)
	(segment
		(start 20.617434 -131.534408)
		(end 10.49274 -121.409714)
		(width 0.127)
		(layer "In2.Cu")
		(net "UART_DSR_P1_L_N")
	)
	(segment
		(start 8.02259 -193.514472)
		(end 8.92048 -193.514472)
		(width 0.127)
		(layer "In2.Cu")
		(net "UART_DSR_P1_L_N")
	)
	(segment
		(start 8.92048 -193.514472)
		(end 11.068812 -191.36614)
		(width 0.127)
		(layer "In2.Cu")
		(net "UART_DSR_P1_L_N")
	)
	(segment
		(start 5.32384 -198.888096)
		(end 5.32384 -195.039488)
		(width 0.127)
		(layer "In2.Cu")
		(net "UART_DSR_P1_L_N")
	)
	(segment
		(start 7.008114 -194.528948)
		(end 8.02259 -193.514472)
		(width 0.127)
		(layer "In2.Cu")
		(net "UART_DSR_P1_L_N")
	)
	(segment
		(start 11.068812 -191.36614)
		(end 11.068812 -178.689508)
		(width 0.127)
		(layer "In2.Cu")
		(net "UART_DSR_P1_L_N")
	)
	(segment
		(start 3.948938 -199.67067)
		(end 4.541266 -199.67067)
		(width 0.127)
		(layer "In2.Cu")
		(net "UART_DSR_P1_L_N")
	)
	(segment
		(start 12.096242 -66.853054)
		(end 18.189702 -60.759594)
		(width 0.127)
		(layer "In2.Cu")
		(net "UART_DSR_P1_L_N")
	)
	(segment
		(start 20.617434 -169.140886)
		(end 20.617434 -131.534408)
		(width 0.127)
		(layer "In2.Cu")
		(net "UART_DSR_P1_L_N")
	)
	(segment
		(start 18.189702 -40.292782)
		(end 10.752836 -32.855916)
		(width 0.127)
		(layer "In2.Cu")
		(net "UART_DSR_P1_L_N")
	)
	(segment
		(start 10.752836 -13.421868)
		(end 12.12469 -12.050014)
		(width 0.127)
		(layer "In2.Cu")
		(net "UART_DSR_P1_L_N")
	)
	(segment
		(start 10.49274 -121.409714)
		(end 10.49274 -115.243356)
		(width 0.127)
		(layer "In2.Cu")
		(net "UART_DSR_P1_L_N")
	)
	(segment
		(start 18.189702 -60.759594)
		(end 18.189702 -40.292782)
		(width 0.127)
		(layer "In2.Cu")
		(net "UART_DSR_P1_L_N")
	)
	(segment
		(start 4.541266 -199.67067)
		(end 5.32384 -198.888096)
		(width 0.127)
		(layer "In2.Cu")
		(net "UART_DSR_P1_L_N")
	)
	(segment
		(start 15.66037 -110.075726)
		(end 15.66037 -104.457246)
		(width 0.127)
		(layer "In2.Cu")
		(net "UART_DSR_P1_L_N")
	)
	(segment
		(start 10.49274 -115.243356)
		(end 15.66037 -110.075726)
		(width 0.127)
		(layer "In2.Cu")
		(net "UART_DSR_P1_L_N")
	)
	(segment
		(start 11.068812 -178.689508)
		(end 20.617434 -169.140886)
		(width 0.127)
		(layer "In2.Cu")
		(net "UART_DSR_P1_L_N")
	)
	(segment
		(start 10.752836 -32.855916)
		(end 10.752836 -13.421868)
		(width 0.127)
		(layer "In2.Cu")
		(net "UART_DSR_P1_L_N")
	)
	(segment
		(start 12.12469 -12.050014)
		(end 12.12469 -6.338062)
		(width 0.127)
		(layer "In2.Cu")
		(net "UART_DSR_P1_L_N")
	)
	(segment
		(start 1.332992 -204.05471)
		(end 1.332992 -204.052424)
		(width 0.127)
		(layer "In5.Cu")
		(net "UART_DTR_P5_L_N")
	)
	(segment
		(start 2.590038 -194.234054)
		(end 2.590038 -193.10731)
		(width 0.127)
		(layer "In5.Cu")
		(net "UART_DTR_P5_L_N")
	)
	(segment
		(start 1.948942 -204.67066)
		(end 1.332992 -204.05471)
		(width 0.127)
		(layer "In5.Cu")
		(net "UART_DTR_P5_L_N")
	)
	(segment
		(start 2.647442 -200.98385)
		(end 2.647442 -200.291446)
		(width 0.127)
		(layer "In5.Cu")
		(net "UART_DTR_P5_L_N")
	)
	(segment
		(start 10.978134 -169.721022)
		(end 19.218656 -161.4805)
		(width 0.127)
		(layer "In5.Cu")
		(net "UART_DTR_P5_L_N")
	)
	(segment
		(start 2.70256 -196.99478)
		(end 2.70256 -196.346572)
		(width 0.127)
		(layer "In5.Cu")
		(net "UART_DTR_P5_L_N")
	)
	(segment
		(start 2.752598 -194.944746)
		(end 2.752598 -194.396614)
		(width 0.127)
		(layer "In5.Cu")
		(net "UART_DTR_P5_L_N")
	)
	(segment
		(start 7.644892 -99.340924)
		(end 7.644892 -63.798196)
		(width 0.127)
		(layer "In5.Cu")
		(net "UART_DTR_P5_L_N")
	)
	(segment
		(start 2.752598 -194.396614)
		(end 2.590038 -194.234054)
		(width 0.127)
		(layer "In5.Cu")
		(net "UART_DTR_P5_L_N")
	)
	(segment
		(start 6.939026 -121.910094)
		(end 6.939026 -115.969542)
		(width 0.127)
		(layer "In5.Cu")
		(net "UART_DTR_P5_L_N")
	)
	(segment
		(start 2.484882 -196.128894)
		(end 2.484882 -195.212462)
		(width 0.127)
		(layer "In5.Cu")
		(net "UART_DTR_P5_L_N")
	)
	(segment
		(start 2.484882 -195.212462)
		(end 2.752598 -194.944746)
		(width 0.127)
		(layer "In5.Cu")
		(net "UART_DTR_P5_L_N")
	)
	(segment
		(start 3.02514 -191.180212)
		(end 3.74904 -190.456312)
		(width 0.127)
		(layer "In5.Cu")
		(net "UART_DTR_P5_L_N")
	)
	(segment
		(start 2.499106 -199.19823)
		(end 2.647442 -199.049894)
		(width 0.127)
		(layer "In5.Cu")
		(net "UART_DTR_P5_L_N")
	)
	(segment
		(start 7.958582 -187.738512)
		(end 9.294876 -187.738512)
		(width 0.127)
		(layer "In5.Cu")
		(net "UART_DTR_P5_L_N")
	)
	(segment
		(start 3.74904 -190.456312)
		(end 4.555744 -190.456312)
		(width 0.127)
		(layer "In5.Cu")
		(net "UART_DTR_P5_L_N")
	)
	(segment
		(start 2.499106 -200.14311)
		(end 2.499106 -199.19823)
		(width 0.127)
		(layer "In5.Cu")
		(net "UART_DTR_P5_L_N")
	)
	(segment
		(start 2.647442 -199.049894)
		(end 2.647442 -198.29145)
		(width 0.127)
		(layer "In5.Cu")
		(net "UART_DTR_P5_L_N")
	)
	(segment
		(start 7.644892 -63.798196)
		(end 5.77469 -61.927994)
		(width 0.127)
		(layer "In5.Cu")
		(net "UART_DTR_P5_L_N")
	)
	(segment
		(start 2.464054 -198.108062)
		(end 2.464054 -197.233286)
		(width 0.127)
		(layer "In5.Cu")
		(net "UART_DTR_P5_L_N")
	)
	(segment
		(start 3.875278 -101.77399)
		(end 5.211826 -101.77399)
		(width 0.127)
		(layer "In5.Cu")
		(net "UART_DTR_P5_L_N")
	)
	(segment
		(start 9.754108 -187.27928)
		(end 9.754108 -170.945302)
		(width 0.127)
		(layer "In5.Cu")
		(net "UART_DTR_P5_L_N")
	)
	(segment
		(start 1.397254 -104.252014)
		(end 3.875278 -101.77399)
		(width 0.127)
		(layer "In5.Cu")
		(net "UART_DTR_P5_L_N")
	)
	(segment
		(start 9.754108 -170.945302)
		(end 10.978134 -169.721022)
		(width 0.127)
		(layer "In5.Cu")
		(net "UART_DTR_P5_L_N")
	)
	(segment
		(start 1.332992 -204.052424)
		(end 1.250442 -203.969874)
		(width 0.127)
		(layer "In5.Cu")
		(net "UART_DTR_P5_L_N")
	)
	(segment
		(start 2.647442 -198.29145)
		(end 2.464054 -198.108062)
		(width 0.127)
		(layer "In5.Cu")
		(net "UART_DTR_P5_L_N")
	)
	(segment
		(start 6.939026 -115.969542)
		(end 1.397254 -110.42777)
		(width 0.127)
		(layer "In5.Cu")
		(net "UART_DTR_P5_L_N")
	)
	(segment
		(start 6.93928 -188.757814)
		(end 7.958582 -187.738512)
		(width 0.127)
		(layer "In5.Cu")
		(net "UART_DTR_P5_L_N")
	)
	(segment
		(start 15.80896 -130.780028)
		(end 6.939026 -121.910094)
		(width 0.127)
		(layer "In5.Cu")
		(net "UART_DTR_P5_L_N")
	)
	(segment
		(start 3.02514 -192.672208)
		(end 3.02514 -191.180212)
		(width 0.127)
		(layer "In5.Cu")
		(net "UART_DTR_P5_L_N")
	)
	(segment
		(start 16.31823 -130.780028)
		(end 15.80896 -130.780028)
		(width 0.127)
		(layer "In5.Cu")
		(net "UART_DTR_P5_L_N")
	)
	(segment
		(start 2.647442 -200.291446)
		(end 2.499106 -200.14311)
		(width 0.127)
		(layer "In5.Cu")
		(net "UART_DTR_P5_L_N")
	)
	(segment
		(start 1.250442 -202.38085)
		(end 2.647442 -200.98385)
		(width 0.127)
		(layer "In5.Cu")
		(net "UART_DTR_P5_L_N")
	)
	(segment
		(start 2.70256 -196.346572)
		(end 2.484882 -196.128894)
		(width 0.127)
		(layer "In5.Cu")
		(net "UART_DTR_P5_L_N")
	)
	(segment
		(start 2.590038 -193.10731)
		(end 3.02514 -192.672208)
		(width 0.127)
		(layer "In5.Cu")
		(net "UART_DTR_P5_L_N")
	)
	(segment
		(start 9.294876 -187.738512)
		(end 9.754108 -187.27928)
		(width 0.127)
		(layer "In5.Cu")
		(net "UART_DTR_P5_L_N")
	)
	(segment
		(start 4.555744 -190.456312)
		(end 6.254242 -188.757814)
		(width 0.127)
		(layer "In5.Cu")
		(net "UART_DTR_P5_L_N")
	)
	(segment
		(start 1.397254 -110.42777)
		(end 1.397254 -104.252014)
		(width 0.127)
		(layer "In5.Cu")
		(net "UART_DTR_P5_L_N")
	)
	(segment
		(start 1.250442 -203.969874)
		(end 1.250442 -202.38085)
		(width 0.127)
		(layer "In5.Cu")
		(net "UART_DTR_P5_L_N")
	)
	(segment
		(start 19.218656 -161.4805)
		(end 19.218656 -133.680454)
		(width 0.127)
		(layer "In5.Cu")
		(net "UART_DTR_P5_L_N")
	)
	(segment
		(start 19.218656 -133.680454)
		(end 16.31823 -130.780028)
		(width 0.127)
		(layer "In5.Cu")
		(net "UART_DTR_P5_L_N")
	)
	(segment
		(start 6.254242 -188.757814)
		(end 6.93928 -188.757814)
		(width 0.127)
		(layer "In5.Cu")
		(net "UART_DTR_P5_L_N")
	)
	(segment
		(start 5.211826 -101.77399)
		(end 7.644892 -99.340924)
		(width 0.127)
		(layer "In5.Cu")
		(net "UART_DTR_P5_L_N")
	)
	(segment
		(start 2.464054 -197.233286)
		(end 2.70256 -196.99478)
		(width 0.127)
		(layer "In5.Cu")
		(net "UART_DTR_P5_L_N")
	)
	(segment
		(start 9.83234 -114.96929)
		(end 9.83234 -121.683526)
		(width 0.127)
		(layer "In2.Cu")
		(net "UART_TX_P1_L")
	)
	(segment
		(start 10.092436 -9.385808)
		(end 10.092436 -33.129728)
		(width 0.127)
		(layer "In2.Cu")
		(net "UART_TX_P1_L")
	)
	(segment
		(start 4.66344 -193.768218)
		(end 4.66344 -196.956172)
		(width 0.127)
		(layer "In2.Cu")
		(net "UART_TX_P1_L")
	)
	(segment
		(start 9.83234 -121.683526)
		(end 19.957034 -131.80822)
		(width 0.127)
		(layer "In2.Cu")
		(net "UART_TX_P1_L")
	)
	(segment
		(start 17.529302 -60.485528)
		(end 11.435842 -66.578988)
		(width 0.127)
		(layer "In2.Cu")
		(net "UART_TX_P1_L")
	)
	(segment
		(start 4.66344 -196.956172)
		(end 3.948938 -197.670674)
		(width 0.127)
		(layer "In2.Cu")
		(net "UART_TX_P1_L")
	)
	(segment
		(start 19.957034 -168.867074)
		(end 10.408412 -178.415696)
		(width 0.127)
		(layer "In2.Cu")
		(net "UART_TX_P1_L")
	)
	(segment
		(start 6.950202 -192.442338)
		(end 5.98932 -192.442338)
		(width 0.127)
		(layer "In2.Cu")
		(net "UART_TX_P1_L")
	)
	(segment
		(start 14.99997 -109.80166)
		(end 9.83234 -114.96929)
		(width 0.127)
		(layer "In2.Cu")
		(net "UART_TX_P1_L")
	)
	(segment
		(start 5.98932 -192.442338)
		(end 4.66344 -193.768218)
		(width 0.127)
		(layer "In2.Cu")
		(net "UART_TX_P1_L")
	)
	(segment
		(start 7.775194 -191.617346)
		(end 6.950202 -192.442338)
		(width 0.127)
		(layer "In2.Cu")
		(net "UART_TX_P1_L")
	)
	(segment
		(start 10.408412 -189.950852)
		(end 8.741918 -191.617346)
		(width 0.127)
		(layer "In2.Cu")
		(net "UART_TX_P1_L")
	)
	(segment
		(start 17.529302 -40.566594)
		(end 17.529302 -60.485528)
		(width 0.127)
		(layer "In2.Cu")
		(net "UART_TX_P1_L")
	)
	(segment
		(start 7.04469 -6.338062)
		(end 10.092436 -9.385808)
		(width 0.127)
		(layer "In2.Cu")
		(net "UART_TX_P1_L")
	)
	(segment
		(start 10.408412 -178.415696)
		(end 10.408412 -189.950852)
		(width 0.127)
		(layer "In2.Cu")
		(net "UART_TX_P1_L")
	)
	(segment
		(start 11.435842 -66.578988)
		(end 11.435842 -101.16693)
		(width 0.127)
		(layer "In2.Cu")
		(net "UART_TX_P1_L")
	)
	(segment
		(start 19.957034 -131.80822)
		(end 19.957034 -168.867074)
		(width 0.127)
		(layer "In2.Cu")
		(net "UART_TX_P1_L")
	)
	(segment
		(start 14.99997 -104.731058)
		(end 14.99997 -109.80166)
		(width 0.127)
		(layer "In2.Cu")
		(net "UART_TX_P1_L")
	)
	(segment
		(start 10.092436 -33.129728)
		(end 17.529302 -40.566594)
		(width 0.127)
		(layer "In2.Cu")
		(net "UART_TX_P1_L")
	)
	(segment
		(start 8.741918 -191.617346)
		(end 7.775194 -191.617346)
		(width 0.127)
		(layer "In2.Cu")
		(net "UART_TX_P1_L")
	)
	(segment
		(start 11.435842 -101.16693)
		(end 14.99997 -104.731058)
		(width 0.127)
		(layer "In2.Cu")
		(net "UART_TX_P1_L")
	)
	(segment
		(start 11.965432 -191.3128)
		(end 11.965432 -171.86148)
		(width 0.127)
		(layer "In5.Cu")
		(net "UART_RTS_P5_L_N")
	)
	(segment
		(start 9.856724 -65.46596)
		(end 13.39469 -61.927994)
		(width 0.127)
		(layer "In5.Cu")
		(net "UART_RTS_P5_L_N")
	)
	(segment
		(start 6.2738 -194.773296)
		(end 7.301738 -194.773296)
		(width 0.127)
		(layer "In5.Cu")
		(net "UART_RTS_P5_L_N")
	)
	(segment
		(start 5.739384 -195.307712)
		(end 6.2738 -194.773296)
		(width 0.127)
		(layer "In5.Cu")
		(net "UART_RTS_P5_L_N")
	)
	(segment
		(start 21.430488 -132.457952)
		(end 17.771364 -128.798828)
		(width 0.127)
		(layer "In5.Cu")
		(net "UART_RTS_P5_L_N")
	)
	(segment
		(start 4.574032 -103.985314)
		(end 6.128258 -103.985314)
		(width 0.127)
		(layer "In5.Cu")
		(net "UART_RTS_P5_L_N")
	)
	(segment
		(start 8.920226 -114.82324)
		(end 3.454654 -109.357668)
		(width 0.127)
		(layer "In5.Cu")
		(net "UART_RTS_P5_L_N")
	)
	(segment
		(start 5.739384 -207.133952)
		(end 5.739384 -195.307712)
		(width 0.127)
		(layer "In5.Cu")
		(net "UART_RTS_P5_L_N")
	)
	(segment
		(start 6.128258 -103.985314)
		(end 9.856724 -100.256848)
		(width 0.127)
		(layer "In5.Cu")
		(net "UART_RTS_P5_L_N")
	)
	(segment
		(start 16.630396 -128.798828)
		(end 8.920226 -121.088658)
		(width 0.127)
		(layer "In5.Cu")
		(net "UART_RTS_P5_L_N")
	)
	(segment
		(start 21.430488 -162.39617)
		(end 21.430488 -132.457952)
		(width 0.127)
		(layer "In5.Cu")
		(net "UART_RTS_P5_L_N")
	)
	(segment
		(start 11.965432 -171.86148)
		(end 12.542012 -171.2849)
		(width 0.127)
		(layer "In5.Cu")
		(net "UART_RTS_P5_L_N")
	)
	(segment
		(start 8.1788 -193.896234)
		(end 9.381998 -193.896234)
		(width 0.127)
		(layer "In5.Cu")
		(net "UART_RTS_P5_L_N")
	)
	(segment
		(start 17.771364 -128.798828)
		(end 16.630396 -128.798828)
		(width 0.127)
		(layer "In5.Cu")
		(net "UART_RTS_P5_L_N")
	)
	(segment
		(start 4.202684 -208.670652)
		(end 5.739384 -207.133952)
		(width 0.127)
		(layer "In5.Cu")
		(net "UART_RTS_P5_L_N")
	)
	(segment
		(start 12.542012 -171.2849)
		(end 21.430488 -162.39617)
		(width 0.127)
		(layer "In5.Cu")
		(net "UART_RTS_P5_L_N")
	)
	(segment
		(start 7.301738 -194.773296)
		(end 8.1788 -193.896234)
		(width 0.127)
		(layer "In5.Cu")
		(net "UART_RTS_P5_L_N")
	)
	(segment
		(start 3.454654 -105.104692)
		(end 4.574032 -103.985314)
		(width 0.127)
		(layer "In5.Cu")
		(net "UART_RTS_P5_L_N")
	)
	(segment
		(start 1.948942 -208.670652)
		(end 4.202684 -208.670652)
		(width 0.127)
		(layer "In5.Cu")
		(net "UART_RTS_P5_L_N")
	)
	(segment
		(start 9.381998 -193.896234)
		(end 11.965432 -191.3128)
		(width 0.127)
		(layer "In5.Cu")
		(net "UART_RTS_P5_L_N")
	)
	(segment
		(start 9.856724 -100.256848)
		(end 9.856724 -65.46596)
		(width 0.127)
		(layer "In5.Cu")
		(net "UART_RTS_P5_L_N")
	)
	(segment
		(start 3.454654 -109.357668)
		(end 3.454654 -105.104692)
		(width 0.127)
		(layer "In5.Cu")
		(net "UART_RTS_P5_L_N")
	)
	(segment
		(start 8.920226 -121.088658)
		(end 8.920226 -114.82324)
		(width 0.127)
		(layer "In5.Cu")
		(net "UART_RTS_P5_L_N")
	)
	(segment
		(start 5.418836 -102.53726)
		(end 8.40867 -99.547426)
		(width 0.127)
		(layer "In5.Cu")
		(net "UART_TX_P5_L")
	)
	(segment
		(start 8.220964 -189.852554)
		(end 9.598406 -189.852554)
		(width 0.127)
		(layer "In5.Cu")
		(net "UART_TX_P5_L")
	)
	(segment
		(start 9.598406 -189.852554)
		(end 10.517378 -188.933582)
		(width 0.127)
		(layer "In5.Cu")
		(net "UART_TX_P5_L")
	)
	(segment
		(start 19.904964 -161.873692)
		(end 19.904964 -133.396228)
		(width 0.127)
		(layer "In5.Cu")
		(net "UART_TX_P5_L")
	)
	(segment
		(start 3.250438 -197.960234)
		(end 3.250438 -197.381114)
		(width 0.127)
		(layer "In5.Cu")
		(net "UART_TX_P5_L")
	)
	(segment
		(start 16.628364 -130.119628)
		(end 16.082772 -130.119628)
		(width 0.127)
		(layer "In5.Cu")
		(net "UART_TX_P5_L")
	)
	(segment
		(start 3.250438 -199.38111)
		(end 3.375914 -199.255634)
		(width 0.127)
		(layer "In5.Cu")
		(net "UART_TX_P5_L")
	)
	(segment
		(start 3.403854 -197.227698)
		(end 3.403854 -196.113654)
		(width 0.127)
		(layer "In5.Cu")
		(net "UART_TX_P5_L")
	)
	(segment
		(start 9.256522 -62.966346)
		(end 9.256522 -61.159898)
		(width 0.127)
		(layer "In5.Cu")
		(net "UART_TX_P5_L")
	)
	(segment
		(start 11.517884 -170.260772)
		(end 19.904964 -161.873692)
		(width 0.127)
		(layer "In5.Cu")
		(net "UART_TX_P5_L")
	)
	(segment
		(start 3.414014 -195.217542)
		(end 3.414014 -194.123818)
		(width 0.127)
		(layer "In5.Cu")
		(net "UART_TX_P5_L")
	)
	(segment
		(start 3.250438 -199.96023)
		(end 3.250438 -199.38111)
		(width 0.127)
		(layer "In5.Cu")
		(net "UART_TX_P5_L")
	)
	(segment
		(start 3.81762 -192.81394)
		(end 4.317238 -192.81394)
		(width 0.127)
		(layer "In5.Cu")
		(net "UART_TX_P5_L")
	)
	(segment
		(start 9.256522 -61.159898)
		(end 10.47369 -59.94273)
		(width 0.127)
		(layer "In5.Cu")
		(net "UART_TX_P5_L")
	)
	(segment
		(start 3.382772 -201.248772)
		(end 3.382772 -200.092564)
		(width 0.127)
		(layer "In5.Cu")
		(net "UART_TX_P5_L")
	)
	(segment
		(start 6.326124 -190.805054)
		(end 7.268464 -190.805054)
		(width 0.127)
		(layer "In5.Cu")
		(net "UART_TX_P5_L")
	)
	(segment
		(start 2.057654 -104.525826)
		(end 4.04622 -102.53726)
		(width 0.127)
		(layer "In5.Cu")
		(net "UART_TX_P5_L")
	)
	(segment
		(start 2.057654 -110.00867)
		(end 2.057654 -104.525826)
		(width 0.127)
		(layer "In5.Cu")
		(net "UART_TX_P5_L")
	)
	(segment
		(start 3.250438 -204.972158)
		(end 3.250438 -201.381106)
		(width 0.127)
		(layer "In5.Cu")
		(net "UART_TX_P5_L")
	)
	(segment
		(start 4.04622 -102.53726)
		(end 5.418836 -102.53726)
		(width 0.127)
		(layer "In5.Cu")
		(net "UART_TX_P5_L")
	)
	(segment
		(start 7.599426 -115.550442)
		(end 2.057654 -110.00867)
		(width 0.127)
		(layer "In5.Cu")
		(net "UART_TX_P5_L")
	)
	(segment
		(start 3.250438 -193.960242)
		(end 3.250438 -193.381122)
		(width 0.127)
		(layer "In5.Cu")
		(net "UART_TX_P5_L")
	)
	(segment
		(start 9.729724 -58.275728)
		(end 8.156956 -58.275728)
		(width 0.127)
		(layer "In5.Cu")
		(net "UART_TX_P5_L")
	)
	(segment
		(start 3.414014 -194.123818)
		(end 3.250438 -193.960242)
		(width 0.127)
		(layer "In5.Cu")
		(net "UART_TX_P5_L")
	)
	(segment
		(start 3.193542 -195.438014)
		(end 3.414014 -195.217542)
		(width 0.127)
		(layer "In5.Cu")
		(net "UART_TX_P5_L")
	)
	(segment
		(start 8.40867 -99.547426)
		(end 8.40867 -63.814198)
		(width 0.127)
		(layer "In5.Cu")
		(net "UART_TX_P5_L")
	)
	(segment
		(start 7.268464 -190.805054)
		(end 8.220964 -189.852554)
		(width 0.127)
		(layer "In5.Cu")
		(net "UART_TX_P5_L")
	)
	(segment
		(start 3.250438 -201.381106)
		(end 3.382772 -201.248772)
		(width 0.127)
		(layer "In5.Cu")
		(net "UART_TX_P5_L")
	)
	(segment
		(start 8.156956 -58.275728)
		(end 7.04469 -59.387994)
		(width 0.127)
		(layer "In5.Cu")
		(net "UART_TX_P5_L")
	)
	(segment
		(start 10.47369 -59.94273)
		(end 10.47369 -59.019694)
		(width 0.127)
		(layer "In5.Cu")
		(net "UART_TX_P5_L")
	)
	(segment
		(start 10.517378 -188.933582)
		(end 10.517378 -171.261532)
		(width 0.127)
		(layer "In5.Cu")
		(net "UART_TX_P5_L")
	)
	(segment
		(start 10.517378 -171.261532)
		(end 11.517884 -170.260772)
		(width 0.127)
		(layer "In5.Cu")
		(net "UART_TX_P5_L")
	)
	(segment
		(start 19.904964 -133.396228)
		(end 16.628364 -130.119628)
		(width 0.127)
		(layer "In5.Cu")
		(net "UART_TX_P5_L")
	)
	(segment
		(start 3.193542 -195.903342)
		(end 3.193542 -195.438014)
		(width 0.127)
		(layer "In5.Cu")
		(net "UART_TX_P5_L")
	)
	(segment
		(start 3.382772 -200.092564)
		(end 3.250438 -199.96023)
		(width 0.127)
		(layer "In5.Cu")
		(net "UART_TX_P5_L")
	)
	(segment
		(start 8.40867 -63.814198)
		(end 9.256522 -62.966346)
		(width 0.127)
		(layer "In5.Cu")
		(net "UART_TX_P5_L")
	)
	(segment
		(start 10.47369 -59.019694)
		(end 9.729724 -58.275728)
		(width 0.127)
		(layer "In5.Cu")
		(net "UART_TX_P5_L")
	)
	(segment
		(start 3.250438 -193.381122)
		(end 3.81762 -192.81394)
		(width 0.127)
		(layer "In5.Cu")
		(net "UART_TX_P5_L")
	)
	(segment
		(start 3.403854 -196.113654)
		(end 3.193542 -195.903342)
		(width 0.127)
		(layer "In5.Cu")
		(net "UART_TX_P5_L")
	)
	(segment
		(start 3.250438 -197.381114)
		(end 3.403854 -197.227698)
		(width 0.127)
		(layer "In5.Cu")
		(net "UART_TX_P5_L")
	)
	(segment
		(start 4.317238 -192.81394)
		(end 6.326124 -190.805054)
		(width 0.127)
		(layer "In5.Cu")
		(net "UART_TX_P5_L")
	)
	(segment
		(start 16.082772 -130.119628)
		(end 7.599426 -121.636282)
		(width 0.127)
		(layer "In5.Cu")
		(net "UART_TX_P5_L")
	)
	(segment
		(start 7.599426 -121.636282)
		(end 7.599426 -115.550442)
		(width 0.127)
		(layer "In5.Cu")
		(net "UART_TX_P5_L")
	)
	(segment
		(start 3.948938 -205.670658)
		(end 3.250438 -204.972158)
		(width 0.127)
		(layer "In5.Cu")
		(net "UART_TX_P5_L")
	)
	(segment
		(start 3.375914 -198.08571)
		(end 3.250438 -197.960234)
		(width 0.127)
		(layer "In5.Cu")
		(net "UART_TX_P5_L")
	)
	(segment
		(start 3.375914 -199.255634)
		(end 3.375914 -198.08571)
		(width 0.127)
		(layer "In5.Cu")
		(net "UART_TX_P5_L")
	)
	(segment
		(start 4.758182 -334.37449)
		(end 3.949954 -333.566262)
		(width 0.127)
		(layer "In5.Cu")
		(net "UART_RTS_RP5_L_N")
	)
	(segment
		(start 8.095488 -338.370164)
		(end 7.212838 -337.487514)
		(width 0.127)
		(layer "In5.Cu")
		(net "UART_RTS_RP5_L_N")
	)
	(segment
		(start 6.288278 -498.66042)
		(end 7.058152 -497.890546)
		(width 0.127)
		(layer "In5.Cu")
		(net "UART_RTS_RP5_L_N")
	)
	(segment
		(start 9.124188 -393.97813)
		(end 7.427722 -392.281664)
		(width 0.127)
		(layer "In5.Cu")
		(net "UART_RTS_RP5_L_N")
	)
	(segment
		(start 4.758182 -335.122266)
		(end 4.758182 -334.37449)
		(width 0.127)
		(layer "In5.Cu")
		(net "UART_RTS_RP5_L_N")
	)
	(segment
		(start 7.449058 -470.55278)
		(end 15.554198 -462.44764)
		(width 0.127)
		(layer "In5.Cu")
		(net "UART_RTS_RP5_L_N")
	)
	(segment
		(start 7.058152 -497.890546)
		(end 7.058152 -496.692174)
		(width 0.127)
		(layer "In5.Cu")
		(net "UART_RTS_RP5_L_N")
	)
	(segment
		(start 9.08558 -338.370164)
		(end 8.095488 -338.370164)
		(width 0.127)
		(layer "In5.Cu")
		(net "UART_RTS_RP5_L_N")
	)
	(segment
		(start 7.449058 -493.201452)
		(end 7.449058 -470.55278)
		(width 0.127)
		(layer "In5.Cu")
		(net "UART_RTS_RP5_L_N")
	)
	(segment
		(start 5.439918 -498.66042)
		(end 6.288278 -498.66042)
		(width 0.127)
		(layer "In5.Cu")
		(net "UART_RTS_RP5_L_N")
	)
	(segment
		(start 5.718048 -337.080352)
		(end 5.718048 -336.082132)
		(width 0.127)
		(layer "In5.Cu")
		(net "UART_RTS_RP5_L_N")
	)
	(segment
		(start 7.427722 -380.572264)
		(end 9.831832 -378.168154)
		(width 0.127)
		(layer "In5.Cu")
		(net "UART_RTS_RP5_L_N")
	)
	(segment
		(start 7.058152 -496.692174)
		(end 8.012684 -495.737642)
		(width 0.127)
		(layer "In5.Cu")
		(net "UART_RTS_RP5_L_N")
	)
	(segment
		(start 4.50469 -494.611914)
		(end 4.50469 -497.725192)
		(width 0.127)
		(layer "In5.Cu")
		(net "UART_RTS_RP5_L_N")
	)
	(segment
		(start 8.012684 -495.737642)
		(end 8.012684 -493.765078)
		(width 0.127)
		(layer "In5.Cu")
		(net "UART_RTS_RP5_L_N")
	)
	(segment
		(start 15.554198 -462.44764)
		(end 15.554198 -410.486606)
		(width 0.127)
		(layer "In5.Cu")
		(net "UART_RTS_RP5_L_N")
	)
	(segment
		(start 7.212838 -337.487514)
		(end 6.12521 -337.487514)
		(width 0.127)
		(layer "In5.Cu")
		(net "UART_RTS_RP5_L_N")
	)
	(segment
		(start 8.012684 -493.765078)
		(end 7.449058 -493.201452)
		(width 0.127)
		(layer "In5.Cu")
		(net "UART_RTS_RP5_L_N")
	)
	(segment
		(start 5.718048 -336.082132)
		(end 4.758182 -335.122266)
		(width 0.127)
		(layer "In5.Cu")
		(net "UART_RTS_RP5_L_N")
	)
	(segment
		(start 4.50469 -497.725192)
		(end 5.439918 -498.66042)
		(width 0.127)
		(layer "In5.Cu")
		(net "UART_RTS_RP5_L_N")
	)
	(segment
		(start 9.124188 -404.056596)
		(end 9.124188 -393.97813)
		(width 0.127)
		(layer "In5.Cu")
		(net "UART_RTS_RP5_L_N")
	)
	(segment
		(start 7.427722 -392.281664)
		(end 7.427722 -380.572264)
		(width 0.127)
		(layer "In5.Cu")
		(net "UART_RTS_RP5_L_N")
	)
	(segment
		(start 15.554198 -410.486606)
		(end 9.124188 -404.056596)
		(width 0.127)
		(layer "In5.Cu")
		(net "UART_RTS_RP5_L_N")
	)
	(segment
		(start 3.949954 -333.566262)
		(end 3.949954 -332.669896)
		(width 0.127)
		(layer "In5.Cu")
		(net "UART_RTS_RP5_L_N")
	)
	(segment
		(start 9.831832 -378.168154)
		(end 9.831832 -339.116416)
		(width 0.127)
		(layer "In5.Cu")
		(net "UART_RTS_RP5_L_N")
	)
	(segment
		(start 9.831832 -339.116416)
		(end 9.08558 -338.370164)
		(width 0.127)
		(layer "In5.Cu")
		(net "UART_RTS_RP5_L_N")
	)
	(segment
		(start 6.12521 -337.487514)
		(end 5.718048 -337.080352)
		(width 0.127)
		(layer "In5.Cu")
		(net "UART_RTS_RP5_L_N")
	)
	(segment
		(start 3.113278 -334.85709)
		(end 3.113278 -331.506576)
		(width 0.127)
		(layer "In5.Cu")
		(net "UART_RX_RP5_L")
	)
	(segment
		(start 8.99922 -338.782914)
		(end 7.9502 -338.782914)
		(width 0.127)
		(layer "In5.Cu")
		(net "UART_RX_RP5_L")
	)
	(segment
		(start 15.223998 -410.623512)
		(end 8.619744 -404.019258)
		(width 0.127)
		(layer "In5.Cu")
		(net "UART_RX_RP5_L")
	)
	(segment
		(start 8.619744 -404.019258)
		(end 8.619744 -394.095986)
		(width 0.127)
		(layer "In5.Cu")
		(net "UART_RX_RP5_L")
	)
	(segment
		(start 3.113278 -331.506576)
		(end 3.949954 -330.6699)
		(width 0.127)
		(layer "In5.Cu")
		(net "UART_RX_RP5_L")
	)
	(segment
		(start 7.034784 -337.867498)
		(end 6.013958 -337.867498)
		(width 0.127)
		(layer "In5.Cu")
		(net "UART_RX_RP5_L")
	)
	(segment
		(start 9.501632 -378.031248)
		(end 9.501632 -339.285326)
		(width 0.127)
		(layer "In5.Cu")
		(net "UART_RX_RP5_L")
	)
	(segment
		(start 15.223998 -462.310734)
		(end 15.223998 -410.623512)
		(width 0.127)
		(layer "In5.Cu")
		(net "UART_RX_RP5_L")
	)
	(segment
		(start 7.097522 -392.573764)
		(end 7.097522 -380.435358)
		(width 0.127)
		(layer "In5.Cu")
		(net "UART_RX_RP5_L")
	)
	(segment
		(start 7.097522 -380.435358)
		(end 9.501632 -378.031248)
		(width 0.127)
		(layer "In5.Cu")
		(net "UART_RX_RP5_L")
	)
	(segment
		(start 9.501632 -339.285326)
		(end 8.99922 -338.782914)
		(width 0.127)
		(layer "In5.Cu")
		(net "UART_RX_RP5_L")
	)
	(segment
		(start 7.04469 -470.490042)
		(end 15.223998 -462.310734)
		(width 0.127)
		(layer "In5.Cu")
		(net "UART_RX_RP5_L")
	)
	(segment
		(start 4.539742 -335.472786)
		(end 3.728974 -335.472786)
		(width 0.127)
		(layer "In5.Cu")
		(net "UART_RX_RP5_L")
	)
	(segment
		(start 5.260594 -337.114134)
		(end 5.260594 -336.193638)
		(width 0.127)
		(layer "In5.Cu")
		(net "UART_RX_RP5_L")
	)
	(segment
		(start 3.728974 -335.472786)
		(end 3.113278 -334.85709)
		(width 0.127)
		(layer "In5.Cu")
		(net "UART_RX_RP5_L")
	)
	(segment
		(start 8.619744 -394.095986)
		(end 7.097522 -392.573764)
		(width 0.127)
		(layer "In5.Cu")
		(net "UART_RX_RP5_L")
	)
	(segment
		(start 5.260594 -336.193638)
		(end 4.539742 -335.472786)
		(width 0.127)
		(layer "In5.Cu")
		(net "UART_RX_RP5_L")
	)
	(segment
		(start 7.9502 -338.782914)
		(end 7.034784 -337.867498)
		(width 0.127)
		(layer "In5.Cu")
		(net "UART_RX_RP5_L")
	)
	(segment
		(start 6.013958 -337.867498)
		(end 5.260594 -337.114134)
		(width 0.127)
		(layer "In5.Cu")
		(net "UART_RX_RP5_L")
	)
	(segment
		(start 7.04469 -494.611914)
		(end 7.04469 -470.490042)
		(width 0.127)
		(layer "In5.Cu")
		(net "UART_RX_RP5_L")
	)
	(segment
		(start 10.822432 -336.892646)
		(end 8.772906 -334.84312)
		(width 0.127)
		(layer "In5.Cu")
		(net "UART_DTR_RP5_L_N")
	)
	(segment
		(start 5.955284 -333.7941)
		(end 5.383276 -333.222092)
		(width 0.127)
		(layer "In5.Cu")
		(net "UART_DTR_RP5_L_N")
	)
	(segment
		(start 8.469122 -490.956346)
		(end 8.469122 -470.934034)
		(width 0.127)
		(layer "In5.Cu")
		(net "UART_DTR_RP5_L_N")
	)
	(segment
		(start 5.383276 -329.63993)
		(end 4.41325 -328.669904)
		(width 0.127)
		(layer "In5.Cu")
		(net "UART_DTR_RP5_L_N")
	)
	(segment
		(start 5.383276 -333.222092)
		(end 5.383276 -329.63993)
		(width 0.127)
		(layer "In5.Cu")
		(net "UART_DTR_RP5_L_N")
	)
	(segment
		(start 8.418322 -380.982982)
		(end 10.822432 -378.578872)
		(width 0.127)
		(layer "In5.Cu")
		(net "UART_DTR_RP5_L_N")
	)
	(segment
		(start 10.805922 -404.337012)
		(end 10.805922 -393.751054)
		(width 0.127)
		(layer "In5.Cu")
		(net "UART_DTR_RP5_L_N")
	)
	(segment
		(start 4.41325 -328.669904)
		(end 3.949954 -328.669904)
		(width 0.127)
		(layer "In5.Cu")
		(net "UART_DTR_RP5_L_N")
	)
	(segment
		(start 16.544798 -410.075888)
		(end 10.805922 -404.337012)
		(width 0.127)
		(layer "In5.Cu")
		(net "UART_DTR_RP5_L_N")
	)
	(segment
		(start 10.822432 -378.578872)
		(end 10.822432 -336.892646)
		(width 0.127)
		(layer "In5.Cu")
		(net "UART_DTR_RP5_L_N")
	)
	(segment
		(start 8.418322 -391.363454)
		(end 8.418322 -380.982982)
		(width 0.127)
		(layer "In5.Cu")
		(net "UART_DTR_RP5_L_N")
	)
	(segment
		(start 16.544798 -462.858358)
		(end 16.544798 -410.075888)
		(width 0.127)
		(layer "In5.Cu")
		(net "UART_DTR_RP5_L_N")
	)
	(segment
		(start 7.81304 -334.84312)
		(end 6.76402 -333.7941)
		(width 0.127)
		(layer "In5.Cu")
		(net "UART_DTR_RP5_L_N")
	)
	(segment
		(start 12.12469 -494.611914)
		(end 8.469122 -490.956346)
		(width 0.127)
		(layer "In5.Cu")
		(net "UART_DTR_RP5_L_N")
	)
	(segment
		(start 6.76402 -333.7941)
		(end 5.955284 -333.7941)
		(width 0.127)
		(layer "In5.Cu")
		(net "UART_DTR_RP5_L_N")
	)
	(segment
		(start 10.805922 -393.751054)
		(end 8.418322 -391.363454)
		(width 0.127)
		(layer "In5.Cu")
		(net "UART_DTR_RP5_L_N")
	)
	(segment
		(start 8.469122 -470.934034)
		(end 16.544798 -462.858358)
		(width 0.127)
		(layer "In5.Cu")
		(net "UART_DTR_RP5_L_N")
	)
	(segment
		(start 8.772906 -334.84312)
		(end 7.81304 -334.84312)
		(width 0.127)
		(layer "In5.Cu")
		(net "UART_DTR_RP5_L_N")
	)
	(segment
		(start 8.709152 -336.863182)
		(end 10.162032 -338.316062)
		(width 0.127)
		(layer "In5.Cu")
		(net "UART_TX_RP5_L")
	)
	(segment
		(start 5.174996 -334.949038)
		(end 6.118098 -335.89214)
		(width 0.127)
		(layer "In5.Cu")
		(net "UART_TX_RP5_L")
	)
	(segment
		(start 8.520684 -494.817908)
		(end 10.85469 -497.151914)
		(width 0.127)
		(layer "In5.Cu")
		(net "UART_TX_RP5_L")
	)
	(segment
		(start 9.712452 -394.027406)
		(end 9.712452 -404.177754)
		(width 0.127)
		(layer "In5.Cu")
		(net "UART_TX_RP5_L")
	)
	(segment
		(start 15.884398 -410.3497)
		(end 15.884398 -462.584546)
		(width 0.127)
		(layer "In5.Cu")
		(net "UART_TX_RP5_L")
	)
	(segment
		(start 5.174996 -334.230726)
		(end 5.174996 -334.949038)
		(width 0.127)
		(layer "In5.Cu")
		(net "UART_TX_RP5_L")
	)
	(segment
		(start 4.681982 -330.317094)
		(end 4.681982 -333.737712)
		(width 0.127)
		(layer "In5.Cu")
		(net "UART_TX_RP5_L")
	)
	(segment
		(start 7.808722 -470.660222)
		(end 7.808722 -492.792512)
		(width 0.127)
		(layer "In5.Cu")
		(net "UART_TX_RP5_L")
	)
	(segment
		(start 7.808722 -492.792512)
		(end 8.520684 -493.504474)
		(width 0.127)
		(layer "In5.Cu")
		(net "UART_TX_RP5_L")
	)
	(segment
		(start 3.320796 -329.669902)
		(end 3.398774 -329.74788)
		(width 0.127)
		(layer "In5.Cu")
		(net "UART_TX_RP5_L")
	)
	(segment
		(start 15.884398 -462.584546)
		(end 7.808722 -470.660222)
		(width 0.127)
		(layer "In5.Cu")
		(net "UART_TX_RP5_L")
	)
	(segment
		(start 7.757922 -380.70917)
		(end 7.757922 -392.072876)
		(width 0.127)
		(layer "In5.Cu")
		(net "UART_TX_RP5_L")
	)
	(segment
		(start 4.112768 -329.74788)
		(end 4.681982 -330.317094)
		(width 0.127)
		(layer "In5.Cu")
		(net "UART_TX_RP5_L")
	)
	(segment
		(start 3.398774 -329.74788)
		(end 4.112768 -329.74788)
		(width 0.127)
		(layer "In5.Cu")
		(net "UART_TX_RP5_L")
	)
	(segment
		(start 10.162032 -338.316062)
		(end 10.162032 -378.30506)
		(width 0.127)
		(layer "In5.Cu")
		(net "UART_TX_RP5_L")
	)
	(segment
		(start 4.681982 -333.737712)
		(end 5.174996 -334.230726)
		(width 0.127)
		(layer "In5.Cu")
		(net "UART_TX_RP5_L")
	)
	(segment
		(start 6.95706 -335.89214)
		(end 7.928102 -336.863182)
		(width 0.127)
		(layer "In5.Cu")
		(net "UART_TX_RP5_L")
	)
	(segment
		(start 7.928102 -336.863182)
		(end 8.709152 -336.863182)
		(width 0.127)
		(layer "In5.Cu")
		(net "UART_TX_RP5_L")
	)
	(segment
		(start 8.520684 -493.504474)
		(end 8.520684 -494.817908)
		(width 0.127)
		(layer "In5.Cu")
		(net "UART_TX_RP5_L")
	)
	(segment
		(start 7.757922 -392.072876)
		(end 9.712452 -394.027406)
		(width 0.127)
		(layer "In5.Cu")
		(net "UART_TX_RP5_L")
	)
	(segment
		(start 10.162032 -378.30506)
		(end 7.757922 -380.70917)
		(width 0.127)
		(layer "In5.Cu")
		(net "UART_TX_RP5_L")
	)
	(segment
		(start 6.118098 -335.89214)
		(end 6.95706 -335.89214)
		(width 0.127)
		(layer "In5.Cu")
		(net "UART_TX_RP5_L")
	)
	(segment
		(start 9.712452 -404.177754)
		(end 15.884398 -410.3497)
		(width 0.127)
		(layer "In5.Cu")
		(net "UART_TX_RP5_L")
	)
	(segment
		(start 1.949958 -329.669902)
		(end 3.320796 -329.669902)
		(width 0.127)
		(layer "In5.Cu")
		(net "UART_TX_RP5_L")
	)
	(segment
		(start 7.415022 -393.615926)
		(end 8.226552 -394.427456)
		(width 0.127)
		(layer "B.Cu")
		(net "LAN2_P3_N")
	)
	(segment
		(start 6.447536 -410.053282)
		(end 6.986778 -410.592524)
		(width 0.127)
		(layer "B.Cu")
		(net "LAN2_P3_N")
	)
	(segment
		(start 9.416542 -410.674566)
		(end 9.90473 -409.699968)
		(width 0.127)
		(layer "B.Cu")
		(net "LAN2_P3_N")
	)
	(segment
		(start 9.133078 -410.674566)
		(end 9.246108 -410.731208)
		(width 0.127)
		(layer "B.Cu")
		(net "LAN2_P3_N")
	)
	(segment
		(start 6.447536 -408.08529)
		(end 6.447536 -410.053282)
		(width 0.127)
		(layer "B.Cu")
		(net "LAN2_P3_N")
	)
	(segment
		(start 9.246108 -410.731208)
		(end 9.416542 -410.674566)
		(width 0.127)
		(layer "B.Cu")
		(net "LAN2_P3_N")
	)
	(segment
		(start 6.986778 -410.592524)
		(end 9.051036 -410.592524)
		(width 0.127)
		(layer "B.Cu")
		(net "LAN2_P3_N")
	)
	(segment
		(start 7.689088 -350.430592)
		(end 7.689088 -353.923346)
		(width 0.127)
		(layer "B.Cu")
		(net "LAN2_P3_N")
	)
	(segment
		(start 8.226552 -406.306274)
		(end 6.447536 -408.08529)
		(width 0.127)
		(layer "B.Cu")
		(net "LAN2_P3_N")
	)
	(segment
		(start 7.415022 -354.197412)
		(end 7.415022 -393.615926)
		(width 0.127)
		(layer "B.Cu")
		(net "LAN2_P3_N")
	)
	(segment
		(start 8.226552 -394.427456)
		(end 8.226552 -406.306274)
		(width 0.127)
		(layer "B.Cu")
		(net "LAN2_P3_N")
	)
	(segment
		(start 8.449818 -349.669862)
		(end 7.689088 -350.430592)
		(width 0.127)
		(layer "B.Cu")
		(net "LAN2_P3_N")
	)
	(segment
		(start 7.689088 -353.923346)
		(end 7.415022 -354.197412)
		(width 0.127)
		(layer "B.Cu")
		(net "LAN2_P3_N")
	)
	(segment
		(start 9.051036 -410.592524)
		(end 9.133078 -410.674566)
		(width 0.127)
		(layer "B.Cu")
		(net "LAN2_P3_N")
	)
	(segment
		(start 8.892032 -411.008576)
		(end 9.06399 -411.094682)
		(width 0.127)
		(layer "B.Cu")
		(net "LAN2_P3_P")
	)
	(segment
		(start 7.820152 -406.137872)
		(end 6.041136 -407.916888)
		(width 0.127)
		(layer "B.Cu")
		(net "LAN2_P3_P")
	)
	(segment
		(start 6.449822 -350.66986)
		(end 7.071106 -350.66986)
		(width 0.127)
		(layer "B.Cu")
		(net "LAN2_P3_P")
	)
	(segment
		(start 8.882634 -410.998924)
		(end 8.892032 -411.008576)
		(width 0.127)
		(layer "B.Cu")
		(net "LAN2_P3_P")
	)
	(segment
		(start 9.06399 -411.094682)
		(end 9.06526 -411.095444)
		(width 0.127)
		(layer "B.Cu")
		(net "LAN2_P3_P")
	)
	(segment
		(start 7.008622 -393.784328)
		(end 7.820152 -394.595858)
		(width 0.127)
		(layer "B.Cu")
		(net "LAN2_P3_P")
	)
	(segment
		(start 7.820152 -394.595858)
		(end 7.820152 -406.137872)
		(width 0.127)
		(layer "B.Cu")
		(net "LAN2_P3_P")
	)
	(segment
		(start 6.041136 -407.916888)
		(end 6.041136 -410.221684)
		(width 0.127)
		(layer "B.Cu")
		(net "LAN2_P3_P")
	)
	(segment
		(start 7.282688 -350.881442)
		(end 7.282688 -353.754944)
		(width 0.127)
		(layer "B.Cu")
		(net "LAN2_P3_P")
	)
	(segment
		(start 9.12241 -411.265878)
		(end 8.63473 -412.239968)
		(width 0.127)
		(layer "B.Cu")
		(net "LAN2_P3_P")
	)
	(segment
		(start 9.06526 -411.095444)
		(end 9.12241 -411.265878)
		(width 0.127)
		(layer "B.Cu")
		(net "LAN2_P3_P")
	)
	(segment
		(start 7.071106 -350.66986)
		(end 7.282688 -350.881442)
		(width 0.127)
		(layer "B.Cu")
		(net "LAN2_P3_P")
	)
	(segment
		(start 7.008622 -354.02901)
		(end 7.008622 -393.784328)
		(width 0.127)
		(layer "B.Cu")
		(net "LAN2_P3_P")
	)
	(segment
		(start 6.818376 -410.998924)
		(end 8.882634 -410.998924)
		(width 0.127)
		(layer "B.Cu")
		(net "LAN2_P3_P")
	)
	(segment
		(start 6.041136 -410.221684)
		(end 6.818376 -410.998924)
		(width 0.127)
		(layer "B.Cu")
		(net "LAN2_P3_P")
	)
	(segment
		(start 7.282688 -353.754944)
		(end 7.008622 -354.02901)
		(width 0.127)
		(layer "B.Cu")
		(net "LAN2_P3_P")
	)
	(segment
		(start 13.216382 -410.67482)
		(end 13.216128 -410.67482)
		(width 0.127)
		(layer "B.Cu")
		(net "LAN2_P4_P")
	)
	(segment
		(start 10.613898 -361.28071)
		(end 10.367264 -361.52709)
		(width 0.127)
		(layer "B.Cu")
		(net "LAN2_P4_P")
	)
	(segment
		(start 10.613898 -363.79023)
		(end 10.367264 -364.03661)
		(width 0.127)
		(layer "B.Cu")
		(net "LAN2_P4_P")
	)
	(segment
		(start 10.367264 -366.92713)
		(end 10.613898 -367.17351)
		(width 0.127)
		(layer "B.Cu")
		(net "LAN2_P4_P")
	)
	(segment
		(start 7.837932 -346.953586)
		(end 8.78459 -346.953586)
		(width 0.127)
		(layer "B.Cu")
		(net "LAN2_P4_P")
	)
	(segment
		(start 10.367264 -360.27233)
		(end 10.367264 -360.65333)
		(width 0.127)
		(layer "B.Cu")
		(net "LAN2_P4_P")
	)
	(segment
		(start 10.367264 -364.41761)
		(end 10.613898 -364.66399)
		(width 0.127)
		(layer "B.Cu")
		(net "LAN2_P4_P")
	)
	(segment
		(start 10.613898 -369.43284)
		(end 9.625584 -370.421154)
		(width 0.127)
		(layer "B.Cu")
		(net "LAN2_P4_P")
	)
	(segment
		(start 13.103352 -410.731208)
		(end 12.932918 -410.674566)
		(width 0.127)
		(layer "B.Cu")
		(net "LAN2_P4_P")
	)
	(segment
		(start 10.367264 -360.65333)
		(end 10.613898 -360.89971)
		(width 0.127)
		(layer "B.Cu")
		(net "LAN2_P4_P")
	)
	(segment
		(start 8.449818 -347.669866)
		(end 7.736078 -347.309948)
		(width 0.127)
		(layer "B.Cu")
		(net "LAN2_P4_P")
	)
	(segment
		(start 10.367264 -366.54613)
		(end 10.367264 -366.92713)
		(width 0.127)
		(layer "B.Cu")
		(net "LAN2_P4_P")
	)
	(segment
		(start 10.613898 -364.66399)
		(end 10.613898 -365.04499)
		(width 0.127)
		(layer "B.Cu")
		(net "LAN2_P4_P")
	)
	(segment
		(start 10.367264 -362.78185)
		(end 10.367264 -363.16285)
		(width 0.127)
		(layer "B.Cu")
		(net "LAN2_P4_P")
	)
	(segment
		(start 10.613898 -367.17351)
		(end 10.613898 -369.43284)
		(width 0.127)
		(layer "B.Cu")
		(net "LAN2_P4_P")
	)
	(segment
		(start 10.613898 -365.91875)
		(end 10.613898 -366.29975)
		(width 0.127)
		(layer "B.Cu")
		(net "LAN2_P4_P")
	)
	(segment
		(start 10.367264 -363.16285)
		(end 10.613898 -363.40923)
		(width 0.127)
		(layer "B.Cu")
		(net "LAN2_P4_P")
	)
	(segment
		(start 10.367264 -365.29137)
		(end 10.367264 -365.67237)
		(width 0.127)
		(layer "B.Cu")
		(net "LAN2_P4_P")
	)
	(segment
		(start 13.777722 -410.113226)
		(end 13.216382 -410.67482)
		(width 0.127)
		(layer "B.Cu")
		(net "LAN2_P4_P")
	)
	(segment
		(start 10.613898 -363.40923)
		(end 10.613898 -363.79023)
		(width 0.127)
		(layer "B.Cu")
		(net "LAN2_P4_P")
	)
	(segment
		(start 13.777722 -406.527)
		(end 13.777722 -410.113226)
		(width 0.127)
		(layer "B.Cu")
		(net "LAN2_P4_P")
	)
	(segment
		(start 10.613898 -362.15447)
		(end 10.613898 -362.53547)
		(width 0.127)
		(layer "B.Cu")
		(net "LAN2_P4_P")
	)
	(segment
		(start 13.216128 -410.67482)
		(end 13.103352 -410.731208)
		(width 0.127)
		(layer "B.Cu")
		(net "LAN2_P4_P")
	)
	(segment
		(start 10.367264 -365.67237)
		(end 10.613898 -365.91875)
		(width 0.127)
		(layer "B.Cu")
		(net "LAN2_P4_P")
	)
	(segment
		(start 10.367264 -361.90809)
		(end 10.613898 -362.15447)
		(width 0.127)
		(layer "B.Cu")
		(net "LAN2_P4_P")
	)
	(segment
		(start 7.679436 -347.139514)
		(end 7.706868 -347.08465)
		(width 0.127)
		(layer "B.Cu")
		(net "LAN2_P4_P")
	)
	(segment
		(start 10.367264 -364.03661)
		(end 10.367264 -364.41761)
		(width 0.127)
		(layer "B.Cu")
		(net "LAN2_P4_P")
	)
	(segment
		(start 10.613898 -360.89971)
		(end 10.613898 -361.28071)
		(width 0.127)
		(layer "B.Cu")
		(net "LAN2_P4_P")
	)
	(segment
		(start 9.625584 -370.421154)
		(end 9.625584 -389.59155)
		(width 0.127)
		(layer "B.Cu")
		(net "LAN2_P4_P")
	)
	(segment
		(start 9.625584 -389.59155)
		(end 11.58113 -391.547096)
		(width 0.127)
		(layer "B.Cu")
		(net "LAN2_P4_P")
	)
	(segment
		(start 11.58113 -391.547096)
		(end 11.58113 -404.330408)
		(width 0.127)
		(layer "B.Cu")
		(net "LAN2_P4_P")
	)
	(segment
		(start 10.613898 -360.02595)
		(end 10.367264 -360.27233)
		(width 0.127)
		(layer "B.Cu")
		(net "LAN2_P4_P")
	)
	(segment
		(start 12.932918 -410.674566)
		(end 12.44473 -409.699968)
		(width 0.127)
		(layer "B.Cu")
		(net "LAN2_P4_P")
	)
	(segment
		(start 10.613898 -348.782894)
		(end 10.613898 -360.02595)
		(width 0.127)
		(layer "B.Cu")
		(net "LAN2_P4_P")
	)
	(segment
		(start 10.613898 -365.04499)
		(end 10.367264 -365.29137)
		(width 0.127)
		(layer "B.Cu")
		(net "LAN2_P4_P")
	)
	(segment
		(start 10.613898 -362.53547)
		(end 10.367264 -362.78185)
		(width 0.127)
		(layer "B.Cu")
		(net "LAN2_P4_P")
	)
	(segment
		(start 7.736078 -347.309948)
		(end 7.679436 -347.139514)
		(width 0.127)
		(layer "B.Cu")
		(net "LAN2_P4_P")
	)
	(segment
		(start 10.613898 -366.29975)
		(end 10.367264 -366.54613)
		(width 0.127)
		(layer "B.Cu")
		(net "LAN2_P4_P")
	)
	(segment
		(start 11.58113 -404.330408)
		(end 13.777722 -406.527)
		(width 0.127)
		(layer "B.Cu")
		(net "LAN2_P4_P")
	)
	(segment
		(start 10.367264 -361.52709)
		(end 10.367264 -361.90809)
		(width 0.127)
		(layer "B.Cu")
		(net "LAN2_P4_P")
	)
	(segment
		(start 7.706868 -347.08465)
		(end 7.837932 -346.953586)
		(width 0.127)
		(layer "B.Cu")
		(net "LAN2_P4_P")
	)
	(segment
		(start 8.78459 -346.953586)
		(end 10.613898 -348.782894)
		(width 0.127)
		(layer "B.Cu")
		(net "LAN2_P4_P")
	)
	(segment
		(start 13.22705 -411.265878)
		(end 13.71473 -412.239968)
		(width 0.127)
		(layer "B.Cu")
		(net "LAN2_P4_N")
	)
	(segment
		(start 13.2842 -411.095444)
		(end 13.22705 -411.265878)
		(width 0.127)
		(layer "B.Cu")
		(net "LAN2_P4_N")
	)
	(segment
		(start 11.020298 -369.601242)
		(end 10.031984 -370.589556)
		(width 0.127)
		(layer "B.Cu")
		(net "LAN2_P4_N")
	)
	(segment
		(start 13.28547 -411.094682)
		(end 13.2842 -411.095444)
		(width 0.127)
		(layer "B.Cu")
		(net "LAN2_P4_N")
	)
	(segment
		(start 13.457428 -411.008576)
		(end 13.398246 -411.038294)
		(width 0.127)
		(layer "B.Cu")
		(net "LAN2_P4_N")
	)
	(segment
		(start 6.449822 -346.669868)
		(end 7.144766 -347.015308)
		(width 0.127)
		(layer "B.Cu")
		(net "LAN2_P4_N")
	)
	(segment
		(start 14.184122 -406.358598)
		(end 14.184122 -410.281628)
		(width 0.127)
		(layer "B.Cu")
		(net "LAN2_P4_N")
	)
	(segment
		(start 7.144766 -347.015308)
		(end 7.3152 -346.958158)
		(width 0.127)
		(layer "B.Cu")
		(net "LAN2_P4_N")
	)
	(segment
		(start 11.98753 -404.162006)
		(end 14.184122 -406.358598)
		(width 0.127)
		(layer "B.Cu")
		(net "LAN2_P4_N")
	)
	(segment
		(start 11.98753 -391.378694)
		(end 11.98753 -404.162006)
		(width 0.127)
		(layer "B.Cu")
		(net "LAN2_P4_N")
	)
	(segment
		(start 10.031984 -370.589556)
		(end 10.031984 -389.423148)
		(width 0.127)
		(layer "B.Cu")
		(net "LAN2_P4_N")
	)
	(segment
		(start 8.952992 -346.547186)
		(end 11.020298 -348.614492)
		(width 0.127)
		(layer "B.Cu")
		(net "LAN2_P4_N")
	)
	(segment
		(start 7.3152 -346.958158)
		(end 7.37235 -346.844366)
		(width 0.127)
		(layer "B.Cu")
		(net "LAN2_P4_N")
	)
	(segment
		(start 10.031984 -389.423148)
		(end 11.98753 -391.378694)
		(width 0.127)
		(layer "B.Cu")
		(net "LAN2_P4_N")
	)
	(segment
		(start 13.398246 -411.038294)
		(end 13.28547 -411.094682)
		(width 0.127)
		(layer "B.Cu")
		(net "LAN2_P4_N")
	)
	(segment
		(start 11.020298 -348.614492)
		(end 11.020298 -369.601242)
		(width 0.127)
		(layer "B.Cu")
		(net "LAN2_P4_N")
	)
	(segment
		(start 14.184122 -410.281628)
		(end 13.457428 -411.008576)
		(width 0.127)
		(layer "B.Cu")
		(net "LAN2_P4_N")
	)
	(segment
		(start 7.66953 -346.547186)
		(end 8.952992 -346.547186)
		(width 0.127)
		(layer "B.Cu")
		(net "LAN2_P4_N")
	)
	(segment
		(start 7.37235 -346.844366)
		(end 7.66953 -346.547186)
		(width 0.127)
		(layer "B.Cu")
		(net "LAN2_P4_N")
	)
	(segment
		(start 7.744714 -188.317886)
		(end 7.57428 -188.375036)
		(width 0.127)
		(layer "B.Cu")
		(net "LAN1_P1_P")
	)
	(segment
		(start 14.715236 -132.656072)
		(end 14.715236 -130.990594)
		(width 0.127)
		(layer "B.Cu")
		(net "LAN1_P1_P")
	)
	(segment
		(start 8.448802 -188.670438)
		(end 7.744714 -188.317886)
		(width 0.127)
		(layer "B.Cu")
		(net "LAN1_P1_P")
	)
	(segment
		(start 11.947652 -155.414726)
		(end 11.947652 -155.033726)
		(width 0.127)
		(layer "B.Cu")
		(net "LAN1_P1_P")
	)
	(segment
		(start 11.718036 -150.759414)
		(end 11.947652 -150.529798)
		(width 0.127)
		(layer "B.Cu")
		(net "LAN1_P1_P")
	)
	(segment
		(start 11.920474 -138.197082)
		(end 12.070334 -138.047222)
		(width 0.127)
		(layer "B.Cu")
		(net "LAN1_P1_P")
	)
	(segment
		(start 11.718036 -151.140414)
		(end 11.718036 -150.759414)
		(width 0.127)
		(layer "B.Cu")
		(net "LAN1_P1_P")
	)
	(segment
		(start 11.947652 -149.308566)
		(end 11.947652 -148.927566)
		(width 0.127)
		(layer "B.Cu")
		(net "LAN1_P1_P")
	)
	(segment
		(start 12.070334 -135.923782)
		(end 12.070334 -135.300974)
		(width 0.127)
		(layer "B.Cu")
		(net "LAN1_P1_P")
	)
	(segment
		(start 11.920474 -137.516362)
		(end 11.920474 -137.135362)
		(width 0.127)
		(layer "B.Cu")
		(net "LAN1_P1_P")
	)
	(segment
		(start 11.718036 -151.980646)
		(end 11.947652 -151.75103)
		(width 0.127)
		(layer "B.Cu")
		(net "LAN1_P1_P")
	)
	(segment
		(start 7.51713 -188.488828)
		(end 7.516876 -188.488828)
		(width 0.127)
		(layer "B.Cu")
		(net "LAN1_P1_P")
	)
	(segment
		(start 11.718036 -155.644342)
		(end 11.947652 -155.414726)
		(width 0.127)
		(layer "B.Cu")
		(net "LAN1_P1_P")
	)
	(segment
		(start 11.947652 -150.148798)
		(end 11.718036 -149.919182)
		(width 0.127)
		(layer "B.Cu")
		(net "LAN1_P1_P")
	)
	(segment
		(start 11.718036 -156.025342)
		(end 11.718036 -155.644342)
		(width 0.127)
		(layer "B.Cu")
		(net "LAN1_P1_P")
	)
	(segment
		(start 11.920474 -138.578082)
		(end 11.920474 -138.197082)
		(width 0.127)
		(layer "B.Cu")
		(net "LAN1_P1_P")
	)
	(segment
		(start 7.57428 -188.375036)
		(end 7.51713 -188.488828)
		(width 0.127)
		(layer "B.Cu")
		(net "LAN1_P1_P")
	)
	(segment
		(start 11.947652 -148.087334)
		(end 11.947652 -147.525994)
		(width 0.127)
		(layer "B.Cu")
		(net "LAN1_P1_P")
	)
	(segment
		(start 12.070334 -136.604502)
		(end 11.920474 -136.454642)
		(width 0.127)
		(layer "B.Cu")
		(net "LAN1_P1_P")
	)
	(segment
		(start 14.060932 -133.310376)
		(end 14.715236 -132.656072)
		(width 0.127)
		(layer "B.Cu")
		(net "LAN1_P1_P")
	)
	(segment
		(start 11.684508 -144.55521)
		(end 11.31951 -144.190212)
		(width 0.127)
		(layer "B.Cu")
		(net "LAN1_P1_P")
	)
	(segment
		(start 11.718036 -149.538182)
		(end 11.947652 -149.308566)
		(width 0.127)
		(layer "B.Cu")
		(net "LAN1_P1_P")
	)
	(segment
		(start 11.718036 -154.42311)
		(end 11.947652 -154.193494)
		(width 0.127)
		(layer "B.Cu")
		(net "LAN1_P1_P")
	)
	(segment
		(start 7.440676 -189.020704)
		(end 7.830566 -189.410594)
		(width 0.127)
		(layer "B.Cu")
		(net "LAN1_P1_P")
	)
	(segment
		(start 11.31951 -146.897852)
		(end 11.31951 -145.758408)
		(width 0.127)
		(layer "B.Cu")
		(net "LAN1_P1_P")
	)
	(segment
		(start 11.947652 -150.529798)
		(end 11.947652 -150.148798)
		(width 0.127)
		(layer "B.Cu")
		(net "LAN1_P1_P")
	)
	(segment
		(start 12.070334 -136.985502)
		(end 12.070334 -136.604502)
		(width 0.127)
		(layer "B.Cu")
		(net "LAN1_P1_P")
	)
	(segment
		(start 13.505434 -133.865874)
		(end 13.505434 -133.57987)
		(width 0.127)
		(layer "B.Cu")
		(net "LAN1_P1_P")
	)
	(segment
		(start 11.718036 -154.80411)
		(end 11.718036 -154.42311)
		(width 0.127)
		(layer "B.Cu")
		(net "LAN1_P1_P")
	)
	(segment
		(start 11.947652 -152.972262)
		(end 11.947652 -152.591262)
		(width 0.127)
		(layer "B.Cu")
		(net "LAN1_P1_P")
	)
	(segment
		(start 12.680442 -134.690866)
		(end 12.680442 -134.404862)
		(width 0.127)
		(layer "B.Cu")
		(net "LAN1_P1_P")
	)
	(segment
		(start 11.947652 -148.927566)
		(end 11.718036 -148.69795)
		(width 0.127)
		(layer "B.Cu")
		(net "LAN1_P1_P")
	)
	(segment
		(start 11.718036 -153.201878)
		(end 11.947652 -152.972262)
		(width 0.127)
		(layer "B.Cu")
		(net "LAN1_P1_P")
	)
	(segment
		(start 13.505434 -133.57987)
		(end 13.774928 -133.310376)
		(width 0.127)
		(layer "B.Cu")
		(net "LAN1_P1_P")
	)
	(segment
		(start 7.516876 -188.488828)
		(end 7.487412 -188.547756)
		(width 0.127)
		(layer "B.Cu")
		(net "LAN1_P1_P")
	)
	(segment
		(start 13.23594 -134.135368)
		(end 13.505434 -133.865874)
		(width 0.127)
		(layer "B.Cu")
		(net "LAN1_P1_P")
	)
	(segment
		(start 11.947652 -152.591262)
		(end 11.718036 -152.361646)
		(width 0.127)
		(layer "B.Cu")
		(net "LAN1_P1_P")
	)
	(segment
		(start 11.31951 -145.758408)
		(end 11.684508 -145.39341)
		(width 0.127)
		(layer "B.Cu")
		(net "LAN1_P1_P")
	)
	(segment
		(start 12.070334 -137.666222)
		(end 11.920474 -137.516362)
		(width 0.127)
		(layer "B.Cu")
		(net "LAN1_P1_P")
	)
	(segment
		(start 13.457428 -130.518662)
		(end 13.398246 -130.54838)
		(width 0.127)
		(layer "B.Cu")
		(net "LAN1_P1_P")
	)
	(segment
		(start 13.22705 -130.775964)
		(end 13.71473 -131.750054)
		(width 0.127)
		(layer "B.Cu")
		(net "LAN1_P1_P")
	)
	(segment
		(start 12.680442 -134.404862)
		(end 12.949936 -134.135368)
		(width 0.127)
		(layer "B.Cu")
		(net "LAN1_P1_P")
	)
	(segment
		(start 12.949936 -134.135368)
		(end 13.23594 -134.135368)
		(width 0.127)
		(layer "B.Cu")
		(net "LAN1_P1_P")
	)
	(segment
		(start 11.718036 -148.31695)
		(end 11.947652 -148.087334)
		(width 0.127)
		(layer "B.Cu")
		(net "LAN1_P1_P")
	)
	(segment
		(start 12.070334 -138.047222)
		(end 12.070334 -137.666222)
		(width 0.127)
		(layer "B.Cu")
		(net "LAN1_P1_P")
	)
	(segment
		(start 12.070334 -139.108942)
		(end 12.070334 -138.727942)
		(width 0.127)
		(layer "B.Cu")
		(net "LAN1_P1_P")
	)
	(segment
		(start 11.920474 -139.258802)
		(end 12.070334 -139.108942)
		(width 0.127)
		(layer "B.Cu")
		(net "LAN1_P1_P")
	)
	(segment
		(start 13.28547 -130.604768)
		(end 13.2842 -130.60553)
		(width 0.127)
		(layer "B.Cu")
		(net "LAN1_P1_P")
	)
	(segment
		(start 11.684508 -145.39341)
		(end 12.244324 -145.39341)
		(width 0.127)
		(layer "B.Cu")
		(net "LAN1_P1_P")
	)
	(segment
		(start 12.244324 -145.39341)
		(end 12.371324 -145.26641)
		(width 0.127)
		(layer "B.Cu")
		(net "LAN1_P1_P")
	)
	(segment
		(start 12.371324 -145.26641)
		(end 12.371324 -144.68221)
		(width 0.127)
		(layer "B.Cu")
		(net "LAN1_P1_P")
	)
	(segment
		(start 12.244324 -144.55521)
		(end 11.684508 -144.55521)
		(width 0.127)
		(layer "B.Cu")
		(net "LAN1_P1_P")
	)
	(segment
		(start 13.2842 -130.60553)
		(end 13.22705 -130.775964)
		(width 0.127)
		(layer "B.Cu")
		(net "LAN1_P1_P")
	)
	(segment
		(start 9.784588 -189.410594)
		(end 11.947652 -187.24753)
		(width 0.127)
		(layer "B.Cu")
		(net "LAN1_P1_P")
	)
	(segment
		(start 12.070334 -140.484098)
		(end 12.070334 -139.789662)
		(width 0.127)
		(layer "B.Cu")
		(net "LAN1_P1_P")
	)
	(segment
		(start 14.715236 -130.990594)
		(end 14.196822 -130.47218)
		(width 0.127)
		(layer "B.Cu")
		(net "LAN1_P1_P")
	)
	(segment
		(start 11.31951 -144.190212)
		(end 11.31951 -141.234922)
		(width 0.127)
		(layer "B.Cu")
		(net "LAN1_P1_P")
	)
	(segment
		(start 14.196822 -130.47218)
		(end 13.503656 -130.47218)
		(width 0.127)
		(layer "B.Cu")
		(net "LAN1_P1_P")
	)
	(segment
		(start 11.920474 -139.639802)
		(end 11.920474 -139.258802)
		(width 0.127)
		(layer "B.Cu")
		(net "LAN1_P1_P")
	)
	(segment
		(start 11.718036 -153.582878)
		(end 11.718036 -153.201878)
		(width 0.127)
		(layer "B.Cu")
		(net "LAN1_P1_P")
	)
	(segment
		(start 11.947652 -153.812494)
		(end 11.718036 -153.582878)
		(width 0.127)
		(layer "B.Cu")
		(net "LAN1_P1_P")
	)
	(segment
		(start 7.487412 -188.547756)
		(end 7.440676 -188.594492)
		(width 0.127)
		(layer "B.Cu")
		(net "LAN1_P1_P")
	)
	(segment
		(start 13.774928 -133.310376)
		(end 14.060932 -133.310376)
		(width 0.127)
		(layer "B.Cu")
		(net "LAN1_P1_P")
	)
	(segment
		(start 11.718036 -148.69795)
		(end 11.718036 -148.31695)
		(width 0.127)
		(layer "B.Cu")
		(net "LAN1_P1_P")
	)
	(segment
		(start 11.947652 -156.254958)
		(end 11.718036 -156.025342)
		(width 0.127)
		(layer "B.Cu")
		(net "LAN1_P1_P")
	)
	(segment
		(start 7.440676 -188.594492)
		(end 7.440676 -189.020704)
		(width 0.127)
		(layer "B.Cu")
		(net "LAN1_P1_P")
	)
	(segment
		(start 11.718036 -152.361646)
		(end 11.718036 -151.980646)
		(width 0.127)
		(layer "B.Cu")
		(net "LAN1_P1_P")
	)
	(segment
		(start 11.947652 -151.75103)
		(end 11.947652 -151.37003)
		(width 0.127)
		(layer "B.Cu")
		(net "LAN1_P1_P")
	)
	(segment
		(start 11.947652 -154.193494)
		(end 11.947652 -153.812494)
		(width 0.127)
		(layer "B.Cu")
		(net "LAN1_P1_P")
	)
	(segment
		(start 11.718036 -149.919182)
		(end 11.718036 -149.538182)
		(width 0.127)
		(layer "B.Cu")
		(net "LAN1_P1_P")
	)
	(segment
		(start 11.947652 -147.525994)
		(end 11.31951 -146.897852)
		(width 0.127)
		(layer "B.Cu")
		(net "LAN1_P1_P")
	)
	(segment
		(start 11.31951 -141.234922)
		(end 12.070334 -140.484098)
		(width 0.127)
		(layer "B.Cu")
		(net "LAN1_P1_P")
	)
	(segment
		(start 11.947652 -187.24753)
		(end 11.947652 -156.254958)
		(width 0.127)
		(layer "B.Cu")
		(net "LAN1_P1_P")
	)
	(segment
		(start 13.503656 -130.47218)
		(end 13.457428 -130.518662)
		(width 0.127)
		(layer "B.Cu")
		(net "LAN1_P1_P")
	)
	(segment
		(start 11.947652 -151.37003)
		(end 11.718036 -151.140414)
		(width 0.127)
		(layer "B.Cu")
		(net "LAN1_P1_P")
	)
	(segment
		(start 12.070334 -135.300974)
		(end 12.680442 -134.690866)
		(width 0.127)
		(layer "B.Cu")
		(net "LAN1_P1_P")
	)
	(segment
		(start 12.070334 -139.789662)
		(end 11.920474 -139.639802)
		(width 0.127)
		(layer "B.Cu")
		(net "LAN1_P1_P")
	)
	(segment
		(start 12.371324 -144.68221)
		(end 12.244324 -144.55521)
		(width 0.127)
		(layer "B.Cu")
		(net "LAN1_P1_P")
	)
	(segment
		(start 11.947652 -155.033726)
		(end 11.718036 -154.80411)
		(width 0.127)
		(layer "B.Cu")
		(net "LAN1_P1_P")
	)
	(segment
		(start 11.920474 -137.135362)
		(end 12.070334 -136.985502)
		(width 0.127)
		(layer "B.Cu")
		(net "LAN1_P1_P")
	)
	(segment
		(start 13.398246 -130.54838)
		(end 13.28547 -130.604768)
		(width 0.127)
		(layer "B.Cu")
		(net "LAN1_P1_P")
	)
	(segment
		(start 11.920474 -136.454642)
		(end 11.920474 -136.073642)
		(width 0.127)
		(layer "B.Cu")
		(net "LAN1_P1_P")
	)
	(segment
		(start 12.070334 -138.727942)
		(end 11.920474 -138.578082)
		(width 0.127)
		(layer "B.Cu")
		(net "LAN1_P1_P")
	)
	(segment
		(start 11.920474 -136.073642)
		(end 12.070334 -135.923782)
		(width 0.127)
		(layer "B.Cu")
		(net "LAN1_P1_P")
	)
	(segment
		(start 7.830566 -189.410594)
		(end 9.784588 -189.410594)
		(width 0.127)
		(layer "B.Cu")
		(net "LAN1_P1_P")
	)
	(segment
		(start 13.216382 -130.184652)
		(end 13.103352 -130.241294)
		(width 0.127)
		(layer "B.Cu")
		(net "LAN1_P1_N")
	)
	(segment
		(start 11.72591 -144.02181)
		(end 11.72591 -141.403324)
		(width 0.127)
		(layer "B.Cu")
		(net "LAN1_P1_N")
	)
	(segment
		(start 11.72591 -141.403324)
		(end 12.476734 -140.6525)
		(width 0.127)
		(layer "B.Cu")
		(net "LAN1_P1_N")
	)
	(segment
		(start 7.034276 -189.189106)
		(end 7.662164 -189.816994)
		(width 0.127)
		(layer "B.Cu")
		(net "LAN1_P1_N")
	)
	(segment
		(start 15.121636 -132.824474)
		(end 15.121636 -130.822192)
		(width 0.127)
		(layer "B.Cu")
		(net "LAN1_P1_N")
	)
	(segment
		(start 12.476734 -135.469376)
		(end 15.121636 -132.824474)
		(width 0.127)
		(layer "B.Cu")
		(net "LAN1_P1_N")
	)
	(segment
		(start 12.412726 -144.14881)
		(end 11.85291 -144.14881)
		(width 0.127)
		(layer "B.Cu")
		(net "LAN1_P1_N")
	)
	(segment
		(start 13.335254 -130.06578)
		(end 13.216382 -130.184652)
		(width 0.127)
		(layer "B.Cu")
		(net "LAN1_P1_N")
	)
	(segment
		(start 9.95299 -189.816994)
		(end 12.354052 -187.415932)
		(width 0.127)
		(layer "B.Cu")
		(net "LAN1_P1_N")
	)
	(segment
		(start 15.121636 -130.822192)
		(end 14.365224 -130.06578)
		(width 0.127)
		(layer "B.Cu")
		(net "LAN1_P1_N")
	)
	(segment
		(start 12.412726 -145.79981)
		(end 12.777724 -145.434812)
		(width 0.127)
		(layer "B.Cu")
		(net "LAN1_P1_N")
	)
	(segment
		(start 7.034276 -188.42609)
		(end 7.034276 -189.189106)
		(width 0.127)
		(layer "B.Cu")
		(net "LAN1_P1_N")
	)
	(segment
		(start 7.210044 -188.19368)
		(end 7.153402 -188.306964)
		(width 0.127)
		(layer "B.Cu")
		(net "LAN1_P1_N")
	)
	(segment
		(start 12.777724 -145.434812)
		(end 12.777724 -144.513808)
		(width 0.127)
		(layer "B.Cu")
		(net "LAN1_P1_N")
	)
	(segment
		(start 11.72591 -146.72945)
		(end 11.72591 -145.92681)
		(width 0.127)
		(layer "B.Cu")
		(net "LAN1_P1_N")
	)
	(segment
		(start 12.476734 -140.6525)
		(end 12.476734 -135.469376)
		(width 0.127)
		(layer "B.Cu")
		(net "LAN1_P1_N")
	)
	(segment
		(start 11.85291 -145.79981)
		(end 12.412726 -145.79981)
		(width 0.127)
		(layer "B.Cu")
		(net "LAN1_P1_N")
	)
	(segment
		(start 12.354052 -187.415932)
		(end 12.354052 -147.357592)
		(width 0.127)
		(layer "B.Cu")
		(net "LAN1_P1_N")
	)
	(segment
		(start 6.448806 -187.67044)
		(end 7.153402 -188.023246)
		(width 0.127)
		(layer "B.Cu")
		(net "LAN1_P1_N")
	)
	(segment
		(start 7.662164 -189.816994)
		(end 9.95299 -189.816994)
		(width 0.127)
		(layer "B.Cu")
		(net "LAN1_P1_N")
	)
	(segment
		(start 7.153402 -188.023246)
		(end 7.210044 -188.19368)
		(width 0.127)
		(layer "B.Cu")
		(net "LAN1_P1_N")
	)
	(segment
		(start 12.932918 -130.184652)
		(end 12.44473 -129.210054)
		(width 0.127)
		(layer "B.Cu")
		(net "LAN1_P1_N")
	)
	(segment
		(start 11.85291 -144.14881)
		(end 11.72591 -144.02181)
		(width 0.127)
		(layer "B.Cu")
		(net "LAN1_P1_N")
	)
	(segment
		(start 13.103352 -130.241294)
		(end 12.932918 -130.184652)
		(width 0.127)
		(layer "B.Cu")
		(net "LAN1_P1_N")
	)
	(segment
		(start 7.153402 -188.306964)
		(end 7.034276 -188.42609)
		(width 0.127)
		(layer "B.Cu")
		(net "LAN1_P1_N")
	)
	(segment
		(start 12.354052 -147.357592)
		(end 11.72591 -146.72945)
		(width 0.127)
		(layer "B.Cu")
		(net "LAN1_P1_N")
	)
	(segment
		(start 11.72591 -145.92681)
		(end 11.85291 -145.79981)
		(width 0.127)
		(layer "B.Cu")
		(net "LAN1_P1_N")
	)
	(segment
		(start 12.777724 -144.513808)
		(end 12.412726 -144.14881)
		(width 0.127)
		(layer "B.Cu")
		(net "LAN1_P1_N")
	)
	(segment
		(start 14.365224 -130.06578)
		(end 13.335254 -130.06578)
		(width 0.127)
		(layer "B.Cu")
		(net "LAN1_P1_N")
	)
	(segment
		(start 8.390128 -170.62069)
		(end 8.901684 -170.62069)
		(width 0.127)
		(layer "B.Cu")
		(net "LAN1_P2_P")
	)
	(segment
		(start 9.266682 -161.867088)
		(end 8.901684 -161.50209)
		(width 0.127)
		(layer "B.Cu")
		(net "LAN1_P2_P")
	)
	(segment
		(start 9.266682 -167.766492)
		(end 9.266682 -166.845488)
		(width 0.127)
		(layer "B.Cu")
		(net "LAN1_P2_P")
	)
	(segment
		(start 8.454898 -139.888214)
		(end 8.454898 -139.507214)
		(width 0.127)
		(layer "B.Cu")
		(net "LAN1_P2_P")
	)
	(segment
		(start 8.263128 -140.07973)
		(end 8.454898 -139.888214)
		(width 0.127)
		(layer "B.Cu")
		(net "LAN1_P2_P")
	)
	(segment
		(start 9.712198 -185.362342)
		(end 9.712198 -175.204374)
		(width 0.127)
		(layer "B.Cu")
		(net "LAN1_P2_P")
	)
	(segment
		(start 8.901684 -163.99129)
		(end 8.390128 -163.99129)
		(width 0.127)
		(layer "B.Cu")
		(net "LAN1_P2_P")
	)
	(segment
		(start 8.263128 -166.35349)
		(end 8.263128 -165.76929)
		(width 0.127)
		(layer "B.Cu")
		(net "LAN1_P2_P")
	)
	(segment
		(start 8.390128 -161.50209)
		(end 8.263128 -161.37509)
		(width 0.127)
		(layer "B.Cu")
		(net "LAN1_P2_P")
	)
	(segment
		(start 8.263128 -161.37509)
		(end 8.263128 -140.07973)
		(width 0.127)
		(layer "B.Cu")
		(net "LAN1_P2_P")
	)
	(segment
		(start 8.263128 -138.934698)
		(end 8.454898 -138.743182)
		(width 0.127)
		(layer "B.Cu")
		(net "LAN1_P2_P")
	)
	(segment
		(start 8.390128 -168.13149)
		(end 8.901684 -168.13149)
		(width 0.127)
		(layer "B.Cu")
		(net "LAN1_P2_P")
	)
	(segment
		(start 6.448806 -185.670444)
		(end 7.152894 -185.317892)
		(width 0.127)
		(layer "B.Cu")
		(net "LAN1_P2_P")
	)
	(segment
		(start 7.380478 -185.488834)
		(end 7.380732 -185.488834)
		(width 0.127)
		(layer "B.Cu")
		(net "LAN1_P2_P")
	)
	(segment
		(start 8.263128 -168.25849)
		(end 8.390128 -168.13149)
		(width 0.127)
		(layer "B.Cu")
		(net "LAN1_P2_P")
	)
	(segment
		(start 8.901684 -161.50209)
		(end 8.390128 -161.50209)
		(width 0.127)
		(layer "B.Cu")
		(net "LAN1_P2_P")
	)
	(segment
		(start 8.454898 -138.362182)
		(end 8.263128 -138.170666)
		(width 0.127)
		(layer "B.Cu")
		(net "LAN1_P2_P")
	)
	(segment
		(start 7.380732 -185.488834)
		(end 7.410196 -185.547762)
		(width 0.127)
		(layer "B.Cu")
		(net "LAN1_P2_P")
	)
	(segment
		(start 8.454898 -136.072118)
		(end 8.263128 -135.880602)
		(width 0.127)
		(layer "B.Cu")
		(net "LAN1_P2_P")
	)
	(segment
		(start 8.901684 -163.15309)
		(end 9.266682 -162.788092)
		(width 0.127)
		(layer "B.Cu")
		(net "LAN1_P2_P")
	)
	(segment
		(start 8.263128 -137.025634)
		(end 8.263128 -136.644634)
		(width 0.127)
		(layer "B.Cu")
		(net "LAN1_P2_P")
	)
	(segment
		(start 8.263128 -138.170666)
		(end 8.263128 -137.789666)
		(width 0.127)
		(layer "B.Cu")
		(net "LAN1_P2_P")
	)
	(segment
		(start 8.390128 -173.10989)
		(end 8.901684 -173.10989)
		(width 0.127)
		(layer "B.Cu")
		(net "LAN1_P2_P")
	)
	(segment
		(start 7.410196 -185.547762)
		(end 7.751318 -185.888884)
		(width 0.127)
		(layer "B.Cu")
		(net "LAN1_P2_P")
	)
	(segment
		(start 8.454898 -137.59815)
		(end 8.454898 -137.21715)
		(width 0.127)
		(layer "B.Cu")
		(net "LAN1_P2_P")
	)
	(segment
		(start 7.751318 -185.888884)
		(end 9.185656 -185.888884)
		(width 0.127)
		(layer "B.Cu")
		(net "LAN1_P2_P")
	)
	(segment
		(start 7.323328 -185.375042)
		(end 7.380478 -185.488834)
		(width 0.127)
		(layer "B.Cu")
		(net "LAN1_P2_P")
	)
	(segment
		(start 8.263128 -163.86429)
		(end 8.263128 -163.28009)
		(width 0.127)
		(layer "B.Cu")
		(net "LAN1_P2_P")
	)
	(segment
		(start 8.263128 -168.84269)
		(end 8.263128 -168.25849)
		(width 0.127)
		(layer "B.Cu")
		(net "LAN1_P2_P")
	)
	(segment
		(start 8.901684 -165.64229)
		(end 9.266682 -165.277292)
		(width 0.127)
		(layer "B.Cu")
		(net "LAN1_P2_P")
	)
	(segment
		(start 8.454898 -137.21715)
		(end 8.263128 -137.025634)
		(width 0.127)
		(layer "B.Cu")
		(net "LAN1_P2_P")
	)
	(segment
		(start 9.266682 -172.744892)
		(end 9.266682 -171.823888)
		(width 0.127)
		(layer "B.Cu")
		(net "LAN1_P2_P")
	)
	(segment
		(start 9.185656 -185.888884)
		(end 9.712198 -185.362342)
		(width 0.127)
		(layer "B.Cu")
		(net "LAN1_P2_P")
	)
	(segment
		(start 8.263128 -134.661656)
		(end 11.17473 -131.750054)
		(width 0.127)
		(layer "B.Cu")
		(net "LAN1_P2_P")
	)
	(segment
		(start 8.263128 -171.33189)
		(end 8.263128 -170.74769)
		(width 0.127)
		(layer "B.Cu")
		(net "LAN1_P2_P")
	)
	(segment
		(start 8.263128 -165.76929)
		(end 8.390128 -165.64229)
		(width 0.127)
		(layer "B.Cu")
		(net "LAN1_P2_P")
	)
	(segment
		(start 8.901684 -168.96969)
		(end 8.390128 -168.96969)
		(width 0.127)
		(layer "B.Cu")
		(net "LAN1_P2_P")
	)
	(segment
		(start 9.266682 -169.334688)
		(end 8.901684 -168.96969)
		(width 0.127)
		(layer "B.Cu")
		(net "LAN1_P2_P")
	)
	(segment
		(start 9.266682 -165.277292)
		(end 9.266682 -164.356288)
		(width 0.127)
		(layer "B.Cu")
		(net "LAN1_P2_P")
	)
	(segment
		(start 8.901684 -170.62069)
		(end 9.266682 -170.255692)
		(width 0.127)
		(layer "B.Cu")
		(net "LAN1_P2_P")
	)
	(segment
		(start 8.263128 -163.28009)
		(end 8.390128 -163.15309)
		(width 0.127)
		(layer "B.Cu")
		(net "LAN1_P2_P")
	)
	(segment
		(start 9.266682 -164.356288)
		(end 8.901684 -163.99129)
		(width 0.127)
		(layer "B.Cu")
		(net "LAN1_P2_P")
	)
	(segment
		(start 8.454898 -139.507214)
		(end 8.263128 -139.315698)
		(width 0.127)
		(layer "B.Cu")
		(net "LAN1_P2_P")
	)
	(segment
		(start 8.390128 -165.64229)
		(end 8.901684 -165.64229)
		(width 0.127)
		(layer "B.Cu")
		(net "LAN1_P2_P")
	)
	(segment
		(start 8.390128 -163.15309)
		(end 8.901684 -163.15309)
		(width 0.127)
		(layer "B.Cu")
		(net "LAN1_P2_P")
	)
	(segment
		(start 9.712198 -175.204374)
		(end 8.263128 -173.755304)
		(width 0.127)
		(layer "B.Cu")
		(net "LAN1_P2_P")
	)
	(segment
		(start 8.263128 -139.315698)
		(end 8.263128 -138.934698)
		(width 0.127)
		(layer "B.Cu")
		(net "LAN1_P2_P")
	)
	(segment
		(start 8.901684 -168.13149)
		(end 9.266682 -167.766492)
		(width 0.127)
		(layer "B.Cu")
		(net "LAN1_P2_P")
	)
	(segment
		(start 8.901684 -166.48049)
		(end 8.390128 -166.48049)
		(width 0.127)
		(layer "B.Cu")
		(net "LAN1_P2_P")
	)
	(segment
		(start 9.266682 -171.823888)
		(end 8.901684 -171.45889)
		(width 0.127)
		(layer "B.Cu")
		(net "LAN1_P2_P")
	)
	(segment
		(start 9.266682 -162.788092)
		(end 9.266682 -161.867088)
		(width 0.127)
		(layer "B.Cu")
		(net "LAN1_P2_P")
	)
	(segment
		(start 8.901684 -171.45889)
		(end 8.390128 -171.45889)
		(width 0.127)
		(layer "B.Cu")
		(net "LAN1_P2_P")
	)
	(segment
		(start 8.390128 -166.48049)
		(end 8.263128 -166.35349)
		(width 0.127)
		(layer "B.Cu")
		(net "LAN1_P2_P")
	)
	(segment
		(start 8.390128 -163.99129)
		(end 8.263128 -163.86429)
		(width 0.127)
		(layer "B.Cu")
		(net "LAN1_P2_P")
	)
	(segment
		(start 8.263128 -137.789666)
		(end 8.454898 -137.59815)
		(width 0.127)
		(layer "B.Cu")
		(net "LAN1_P2_P")
	)
	(segment
		(start 8.263128 -136.644634)
		(end 8.454898 -136.453118)
		(width 0.127)
		(layer "B.Cu")
		(net "LAN1_P2_P")
	)
	(segment
		(start 8.454898 -136.453118)
		(end 8.454898 -136.072118)
		(width 0.127)
		(layer "B.Cu")
		(net "LAN1_P2_P")
	)
	(segment
		(start 8.390128 -168.96969)
		(end 8.263128 -168.84269)
		(width 0.127)
		(layer "B.Cu")
		(net "LAN1_P2_P")
	)
	(segment
		(start 8.263128 -170.74769)
		(end 8.390128 -170.62069)
		(width 0.127)
		(layer "B.Cu")
		(net "LAN1_P2_P")
	)
	(segment
		(start 8.390128 -171.45889)
		(end 8.263128 -171.33189)
		(width 0.127)
		(layer "B.Cu")
		(net "LAN1_P2_P")
	)
	(segment
		(start 8.901684 -173.10989)
		(end 9.266682 -172.744892)
		(width 0.127)
		(layer "B.Cu")
		(net "LAN1_P2_P")
	)
	(segment
		(start 7.152894 -185.317892)
		(end 7.323328 -185.375042)
		(width 0.127)
		(layer "B.Cu")
		(net "LAN1_P2_P")
	)
	(segment
		(start 8.263128 -173.755304)
		(end 8.263128 -173.23689)
		(width 0.127)
		(layer "B.Cu")
		(net "LAN1_P2_P")
	)
	(segment
		(start 8.263128 -135.880602)
		(end 8.263128 -134.661656)
		(width 0.127)
		(layer "B.Cu")
		(net "LAN1_P2_P")
	)
	(segment
		(start 9.266682 -170.255692)
		(end 9.266682 -169.334688)
		(width 0.127)
		(layer "B.Cu")
		(net "LAN1_P2_P")
	)
	(segment
		(start 9.266682 -166.845488)
		(end 8.901684 -166.48049)
		(width 0.127)
		(layer "B.Cu")
		(net "LAN1_P2_P")
	)
	(segment
		(start 8.263128 -173.23689)
		(end 8.390128 -173.10989)
		(width 0.127)
		(layer "B.Cu")
		(net "LAN1_P2_P")
	)
	(segment
		(start 8.454898 -138.743182)
		(end 8.454898 -138.362182)
		(width 0.127)
		(layer "B.Cu")
		(net "LAN1_P2_P")
	)
	(segment
		(start 7.744206 -185.023252)
		(end 7.687564 -185.193686)
		(width 0.127)
		(layer "B.Cu")
		(net "LAN1_P2_N")
	)
	(segment
		(start 8.733282 -172.70349)
		(end 8.860282 -172.57649)
		(width 0.127)
		(layer "B.Cu")
		(net "LAN1_P2_N")
	)
	(segment
		(start 7.36473 -132.57022)
		(end 7.36473 -129.210054)
		(width 0.127)
		(layer "B.Cu")
		(net "LAN1_P2_N")
	)
	(segment
		(start 8.221726 -161.90849)
		(end 7.856728 -161.543492)
		(width 0.127)
		(layer "B.Cu")
		(net "LAN1_P2_N")
	)
	(segment
		(start 8.733282 -162.74669)
		(end 8.860282 -162.61969)
		(width 0.127)
		(layer "B.Cu")
		(net "LAN1_P2_N")
	)
	(segment
		(start 8.221726 -166.88689)
		(end 7.856728 -166.521892)
		(width 0.127)
		(layer "B.Cu")
		(net "LAN1_P2_N")
	)
	(segment
		(start 8.221726 -167.72509)
		(end 8.733282 -167.72509)
		(width 0.127)
		(layer "B.Cu")
		(net "LAN1_P2_N")
	)
	(segment
		(start 7.856728 -161.543492)
		(end 7.856728 -134.493254)
		(width 0.127)
		(layer "B.Cu")
		(net "LAN1_P2_N")
	)
	(segment
		(start 8.860282 -164.52469)
		(end 8.733282 -164.39769)
		(width 0.127)
		(layer "B.Cu")
		(net "LAN1_P2_N")
	)
	(segment
		(start 8.733282 -161.90849)
		(end 8.221726 -161.90849)
		(width 0.127)
		(layer "B.Cu")
		(net "LAN1_P2_N")
	)
	(segment
		(start 8.860282 -165.10889)
		(end 8.860282 -164.52469)
		(width 0.127)
		(layer "B.Cu")
		(net "LAN1_P2_N")
	)
	(segment
		(start 8.221726 -162.74669)
		(end 8.733282 -162.74669)
		(width 0.127)
		(layer "B.Cu")
		(net "LAN1_P2_N")
	)
	(segment
		(start 8.221726 -165.23589)
		(end 8.733282 -165.23589)
		(width 0.127)
		(layer "B.Cu")
		(net "LAN1_P2_N")
	)
	(segment
		(start 8.860282 -171.99229)
		(end 8.733282 -171.86529)
		(width 0.127)
		(layer "B.Cu")
		(net "LAN1_P2_N")
	)
	(segment
		(start 8.48233 -133.68782)
		(end 7.36473 -132.57022)
		(width 0.127)
		(layer "B.Cu")
		(net "LAN1_P2_N")
	)
	(segment
		(start 7.856728 -166.521892)
		(end 7.856728 -165.600888)
		(width 0.127)
		(layer "B.Cu")
		(net "LAN1_P2_N")
	)
	(segment
		(start 7.856728 -170.579288)
		(end 8.221726 -170.21429)
		(width 0.127)
		(layer "B.Cu")
		(net "LAN1_P2_N")
	)
	(segment
		(start 7.856728 -169.011092)
		(end 7.856728 -168.090088)
		(width 0.127)
		(layer "B.Cu")
		(net "LAN1_P2_N")
	)
	(segment
		(start 8.733282 -166.88689)
		(end 8.221726 -166.88689)
		(width 0.127)
		(layer "B.Cu")
		(net "LAN1_P2_N")
	)
	(segment
		(start 9.017254 -185.482484)
		(end 9.305798 -185.19394)
		(width 0.127)
		(layer "B.Cu")
		(net "LAN1_P2_N")
	)
	(segment
		(start 8.733282 -165.23589)
		(end 8.860282 -165.10889)
		(width 0.127)
		(layer "B.Cu")
		(net "LAN1_P2_N")
	)
	(segment
		(start 8.860282 -162.61969)
		(end 8.860282 -162.03549)
		(width 0.127)
		(layer "B.Cu")
		(net "LAN1_P2_N")
	)
	(segment
		(start 8.221726 -169.37609)
		(end 7.856728 -169.011092)
		(width 0.127)
		(layer "B.Cu")
		(net "LAN1_P2_N")
	)
	(segment
		(start 8.860282 -162.03549)
		(end 8.733282 -161.90849)
		(width 0.127)
		(layer "B.Cu")
		(net "LAN1_P2_N")
	)
	(segment
		(start 8.860282 -172.57649)
		(end 8.860282 -171.99229)
		(width 0.127)
		(layer "B.Cu")
		(net "LAN1_P2_N")
	)
	(segment
		(start 7.91972 -185.482484)
		(end 9.017254 -185.482484)
		(width 0.127)
		(layer "B.Cu")
		(net "LAN1_P2_N")
	)
	(segment
		(start 8.733282 -170.21429)
		(end 8.860282 -170.08729)
		(width 0.127)
		(layer "B.Cu")
		(net "LAN1_P2_N")
	)
	(segment
		(start 8.860282 -169.50309)
		(end 8.733282 -169.37609)
		(width 0.127)
		(layer "B.Cu")
		(net "LAN1_P2_N")
	)
	(segment
		(start 7.856728 -134.493254)
		(end 8.48233 -133.867652)
		(width 0.127)
		(layer "B.Cu")
		(net "LAN1_P2_N")
	)
	(segment
		(start 8.733282 -169.37609)
		(end 8.221726 -169.37609)
		(width 0.127)
		(layer "B.Cu")
		(net "LAN1_P2_N")
	)
	(segment
		(start 7.856728 -168.090088)
		(end 8.221726 -167.72509)
		(width 0.127)
		(layer "B.Cu")
		(net "LAN1_P2_N")
	)
	(segment
		(start 8.733282 -167.72509)
		(end 8.860282 -167.59809)
		(width 0.127)
		(layer "B.Cu")
		(net "LAN1_P2_N")
	)
	(segment
		(start 7.744206 -185.30697)
		(end 7.91972 -185.482484)
		(width 0.127)
		(layer "B.Cu")
		(net "LAN1_P2_N")
	)
	(segment
		(start 8.221726 -172.70349)
		(end 8.733282 -172.70349)
		(width 0.127)
		(layer "B.Cu")
		(net "LAN1_P2_N")
	)
	(segment
		(start 8.48233 -133.867652)
		(end 8.48233 -133.68782)
		(width 0.127)
		(layer "B.Cu")
		(net "LAN1_P2_N")
	)
	(segment
		(start 8.860282 -170.08729)
		(end 8.860282 -169.50309)
		(width 0.127)
		(layer "B.Cu")
		(net "LAN1_P2_N")
	)
	(segment
		(start 8.221726 -170.21429)
		(end 8.733282 -170.21429)
		(width 0.127)
		(layer "B.Cu")
		(net "LAN1_P2_N")
	)
	(segment
		(start 7.856728 -173.923706)
		(end 7.856728 -173.068488)
		(width 0.127)
		(layer "B.Cu")
		(net "LAN1_P2_N")
	)
	(segment
		(start 8.860282 -167.01389)
		(end 8.733282 -166.88689)
		(width 0.127)
		(layer "B.Cu")
		(net "LAN1_P2_N")
	)
	(segment
		(start 7.856728 -173.068488)
		(end 8.221726 -172.70349)
		(width 0.127)
		(layer "B.Cu")
		(net "LAN1_P2_N")
	)
	(segment
		(start 7.856728 -165.600888)
		(end 8.221726 -165.23589)
		(width 0.127)
		(layer "B.Cu")
		(net "LAN1_P2_N")
	)
	(segment
		(start 8.860282 -167.59809)
		(end 8.860282 -167.01389)
		(width 0.127)
		(layer "B.Cu")
		(net "LAN1_P2_N")
	)
	(segment
		(start 8.448802 -184.670446)
		(end 7.744206 -185.023252)
		(width 0.127)
		(layer "B.Cu")
		(net "LAN1_P2_N")
	)
	(segment
		(start 7.856728 -164.032692)
		(end 7.856728 -163.111688)
		(width 0.127)
		(layer "B.Cu")
		(net "LAN1_P2_N")
	)
	(segment
		(start 8.733282 -171.86529)
		(end 8.221726 -171.86529)
		(width 0.127)
		(layer "B.Cu")
		(net "LAN1_P2_N")
	)
	(segment
		(start 9.305798 -185.19394)
		(end 9.305798 -175.372776)
		(width 0.127)
		(layer "B.Cu")
		(net "LAN1_P2_N")
	)
	(segment
		(start 7.856728 -163.111688)
		(end 8.221726 -162.74669)
		(width 0.127)
		(layer "B.Cu")
		(net "LAN1_P2_N")
	)
	(segment
		(start 8.221726 -164.39769)
		(end 7.856728 -164.032692)
		(width 0.127)
		(layer "B.Cu")
		(net "LAN1_P2_N")
	)
	(segment
		(start 7.687564 -185.193686)
		(end 7.744206 -185.30697)
		(width 0.127)
		(layer "B.Cu")
		(net "LAN1_P2_N")
	)
	(segment
		(start 8.733282 -164.39769)
		(end 8.221726 -164.39769)
		(width 0.127)
		(layer "B.Cu")
		(net "LAN1_P2_N")
	)
	(segment
		(start 9.305798 -175.372776)
		(end 7.856728 -173.923706)
		(width 0.127)
		(layer "B.Cu")
		(net "LAN1_P2_N")
	)
	(segment
		(start 7.856728 -171.500292)
		(end 7.856728 -170.579288)
		(width 0.127)
		(layer "B.Cu")
		(net "LAN1_P2_N")
	)
	(segment
		(start 8.221726 -171.86529)
		(end 7.856728 -171.500292)
		(width 0.127)
		(layer "B.Cu")
		(net "LAN1_P2_N")
	)
	(segment
		(start 10.571226 -115.532916)
		(end 16.293846 -109.810296)
		(width 0.127)
		(layer "In5.Cu")
		(net "UART_DSR_P2_L_N")
	)
	(segment
		(start 19.005042 -56.919114)
		(end 12.845288 -50.75936)
		(width 0.127)
		(layer "In5.Cu")
		(net "UART_DSR_P2_L_N")
	)
	(segment
		(start 11.978386 -101.277928)
		(end 11.978386 -79.27213)
		(width 0.127)
		(layer "In5.Cu")
		(net "UART_DSR_P2_L_N")
	)
	(segment
		(start 10.571226 -120.404128)
		(end 10.571226 -115.532916)
		(width 0.127)
		(layer "In5.Cu")
		(net "UART_DSR_P2_L_N")
	)
	(segment
		(start 14.21003 -176.064926)
		(end 23.70455 -166.570406)
		(width 0.127)
		(layer "In5.Cu")
		(net "UART_DSR_P2_L_N")
	)
	(segment
		(start 18.767552 -127.147828)
		(end 17.314926 -127.147828)
		(width 0.127)
		(layer "In5.Cu")
		(net "UART_DSR_P2_L_N")
	)
	(segment
		(start 16.293846 -105.593388)
		(end 11.978386 -101.277928)
		(width 0.127)
		(layer "In5.Cu")
		(net "UART_DSR_P2_L_N")
	)
	(segment
		(start 17.314926 -127.147828)
		(end 10.571226 -120.404128)
		(width 0.127)
		(layer "In5.Cu")
		(net "UART_DSR_P2_L_N")
	)
	(segment
		(start 12.845288 -50.75936)
		(end 7.271512 -50.75936)
		(width 0.127)
		(layer "In5.Cu")
		(net "UART_DSR_P2_L_N")
	)
	(segment
		(start 7.271512 -50.75936)
		(end 5.77469 -52.256182)
		(width 0.127)
		(layer "In5.Cu")
		(net "UART_DSR_P2_L_N")
	)
	(segment
		(start 6.448806 -199.67067)
		(end 8.486394 -199.67067)
		(width 0.127)
		(layer "In5.Cu")
		(net "UART_DSR_P2_L_N")
	)
	(segment
		(start 19.005042 -72.245474)
		(end 19.005042 -56.919114)
		(width 0.127)
		(layer "In5.Cu")
		(net "UART_DSR_P2_L_N")
	)
	(segment
		(start 14.21003 -193.947034)
		(end 14.21003 -176.064926)
		(width 0.127)
		(layer "In5.Cu")
		(net "UART_DSR_P2_L_N")
	)
	(segment
		(start 16.293846 -109.810296)
		(end 16.293846 -105.593388)
		(width 0.127)
		(layer "In5.Cu")
		(net "UART_DSR_P2_L_N")
	)
	(segment
		(start 23.70455 -132.084826)
		(end 18.767552 -127.147828)
		(width 0.127)
		(layer "In5.Cu")
		(net "UART_DSR_P2_L_N")
	)
	(segment
		(start 23.70455 -166.570406)
		(end 23.70455 -132.084826)
		(width 0.127)
		(layer "In5.Cu")
		(net "UART_DSR_P2_L_N")
	)
	(segment
		(start 5.77469 -52.256182)
		(end 5.77469 -55.111904)
		(width 0.127)
		(layer "In5.Cu")
		(net "UART_DSR_P2_L_N")
	)
	(segment
		(start 11.978386 -79.27213)
		(end 19.005042 -72.245474)
		(width 0.127)
		(layer "In5.Cu")
		(net "UART_DSR_P2_L_N")
	)
	(segment
		(start 8.486394 -199.67067)
		(end 14.21003 -193.947034)
		(width 0.127)
		(layer "In5.Cu")
		(net "UART_DSR_P2_L_N")
	)
	(segment
		(start 22.63775 -166.128446)
		(end 22.63775 -132.66166)
		(width 0.127)
		(layer "In5.Cu")
		(net "UART_DTR_P2_L_N")
	)
	(segment
		(start 10.911586 -78.83017)
		(end 17.938242 -71.803514)
		(width 0.127)
		(layer "In5.Cu")
		(net "UART_DTR_P2_L_N")
	)
	(segment
		(start 9.580626 -115.014756)
		(end 15.227046 -109.368336)
		(width 0.127)
		(layer "In5.Cu")
		(net "UART_DTR_P2_L_N")
	)
	(segment
		(start 16.904208 -128.138428)
		(end 9.580626 -120.814846)
		(width 0.127)
		(layer "In5.Cu")
		(net "UART_DTR_P2_L_N")
	)
	(segment
		(start 10.911586 -101.719888)
		(end 10.911586 -78.83017)
		(width 0.127)
		(layer "In5.Cu")
		(net "UART_DTR_P2_L_N")
	)
	(segment
		(start 18.114518 -128.138428)
		(end 16.904208 -128.138428)
		(width 0.127)
		(layer "In5.Cu")
		(net "UART_DTR_P2_L_N")
	)
	(segment
		(start 15.227046 -109.368336)
		(end 15.227046 -106.035348)
		(width 0.127)
		(layer "In5.Cu")
		(net "UART_DTR_P2_L_N")
	)
	(segment
		(start 22.63775 -132.66166)
		(end 18.114518 -128.138428)
		(width 0.127)
		(layer "In5.Cu")
		(net "UART_DTR_P2_L_N")
	)
	(segment
		(start 17.938242 -71.803514)
		(end 17.938242 -58.07202)
		(width 0.127)
		(layer "In5.Cu")
		(net "UART_DTR_P2_L_N")
	)
	(segment
		(start 8.448802 -196.670422)
		(end 13.14323 -191.975994)
		(width 0.127)
		(layer "In5.Cu")
		(net "UART_DTR_P2_L_N")
	)
	(segment
		(start 17.938242 -58.07202)
		(end 13.803376 -53.937154)
		(width 0.127)
		(layer "In5.Cu")
		(net "UART_DTR_P2_L_N")
	)
	(segment
		(start 13.14323 -191.975994)
		(end 13.14323 -175.622966)
		(width 0.127)
		(layer "In5.Cu")
		(net "UART_DTR_P2_L_N")
	)
	(segment
		(start 15.227046 -106.035348)
		(end 10.911586 -101.719888)
		(width 0.127)
		(layer "In5.Cu")
		(net "UART_DTR_P2_L_N")
	)
	(segment
		(start 13.14323 -175.622966)
		(end 22.63775 -166.128446)
		(width 0.127)
		(layer "In5.Cu")
		(net "UART_DTR_P2_L_N")
	)
	(segment
		(start 13.803376 -53.937154)
		(end 13.48994 -53.937154)
		(width 0.127)
		(layer "In5.Cu")
		(net "UART_DTR_P2_L_N")
	)
	(segment
		(start 13.48994 -53.937154)
		(end 12.12469 -52.571904)
		(width 0.127)
		(layer "In5.Cu")
		(net "UART_DTR_P2_L_N")
	)
	(segment
		(start 9.580626 -120.814846)
		(end 9.580626 -115.014756)
		(width 0.127)
		(layer "In5.Cu")
		(net "UART_DTR_P2_L_N")
	)
	(segment
		(start 11.267186 -78.97749)
		(end 18.293842 -71.950834)
		(width 0.127)
		(layer "In5.Cu")
		(net "UART_TX_P2_L")
	)
	(segment
		(start 18.293842 -71.950834)
		(end 18.293842 -57.213754)
		(width 0.127)
		(layer "In5.Cu")
		(net "UART_TX_P2_L")
	)
	(segment
		(start 11.537442 -51.47056)
		(end 10.85469 -52.153312)
		(width 0.127)
		(layer "In5.Cu")
		(net "UART_TX_P2_L")
	)
	(segment
		(start 13.49883 -193.087498)
		(end 13.49883 -175.770286)
		(width 0.127)
		(layer "In5.Cu")
		(net "UART_TX_P2_L")
	)
	(segment
		(start 6.448806 -197.670674)
		(end 8.915654 -197.670674)
		(width 0.127)
		(layer "In5.Cu")
		(net "UART_TX_P2_L")
	)
	(segment
		(start 12.550648 -51.47056)
		(end 11.537442 -51.47056)
		(width 0.127)
		(layer "In5.Cu")
		(net "UART_TX_P2_L")
	)
	(segment
		(start 15.582646 -105.888028)
		(end 11.267186 -101.572568)
		(width 0.127)
		(layer "In5.Cu")
		(net "UART_TX_P2_L")
	)
	(segment
		(start 18.391886 -127.808228)
		(end 17.041114 -127.808228)
		(width 0.127)
		(layer "In5.Cu")
		(net "UART_TX_P2_L")
	)
	(segment
		(start 9.910826 -115.187476)
		(end 15.582646 -109.515656)
		(width 0.127)
		(layer "In5.Cu")
		(net "UART_TX_P2_L")
	)
	(segment
		(start 9.910826 -120.67794)
		(end 9.910826 -115.187476)
		(width 0.127)
		(layer "In5.Cu")
		(net "UART_TX_P2_L")
	)
	(segment
		(start 17.041114 -127.808228)
		(end 9.910826 -120.67794)
		(width 0.127)
		(layer "In5.Cu")
		(net "UART_TX_P2_L")
	)
	(segment
		(start 18.293842 -57.213754)
		(end 12.550648 -51.47056)
		(width 0.127)
		(layer "In5.Cu")
		(net "UART_TX_P2_L")
	)
	(segment
		(start 11.267186 -101.572568)
		(end 11.267186 -78.97749)
		(width 0.127)
		(layer "In5.Cu")
		(net "UART_TX_P2_L")
	)
	(segment
		(start 10.85469 -52.153312)
		(end 10.85469 -55.111904)
		(width 0.127)
		(layer "In5.Cu")
		(net "UART_TX_P2_L")
	)
	(segment
		(start 13.49883 -175.770286)
		(end 22.99335 -166.275766)
		(width 0.127)
		(layer "In5.Cu")
		(net "UART_TX_P2_L")
	)
	(segment
		(start 22.99335 -166.275766)
		(end 22.99335 -132.409692)
		(width 0.127)
		(layer "In5.Cu")
		(net "UART_TX_P2_L")
	)
	(segment
		(start 15.582646 -109.515656)
		(end 15.582646 -105.888028)
		(width 0.127)
		(layer "In5.Cu")
		(net "UART_TX_P2_L")
	)
	(segment
		(start 22.99335 -132.409692)
		(end 18.391886 -127.808228)
		(width 0.127)
		(layer "In5.Cu")
		(net "UART_TX_P2_L")
	)
	(segment
		(start 8.915654 -197.670674)
		(end 13.49883 -193.087498)
		(width 0.127)
		(layer "In5.Cu")
		(net "UART_TX_P2_L")
	)
	(segment
		(start 24.06015 -166.717726)
		(end 24.06015 -131.868418)
		(width 0.127)
		(layer "In5.Cu")
		(net "UART_RTS_P2_L_N")
	)
	(segment
		(start 19.360642 -56.77154)
		(end 12.992862 -50.40376)
		(width 0.127)
		(layer "In5.Cu")
		(net "UART_RTS_P2_L_N")
	)
	(segment
		(start 12.333986 -79.41945)
		(end 19.360642 -72.392794)
		(width 0.127)
		(layer "In5.Cu")
		(net "UART_RTS_P2_L_N")
	)
	(segment
		(start 8.448802 -200.670414)
		(end 14.56563 -194.553586)
		(width 0.127)
		(layer "In5.Cu")
		(net "UART_RTS_P2_L_N")
	)
	(segment
		(start 12.992862 -50.40376)
		(end 6.672834 -50.40376)
		(width 0.127)
		(layer "In5.Cu")
		(net "UART_RTS_P2_L_N")
	)
	(segment
		(start 10.901426 -120.267222)
		(end 10.901426 -115.705636)
		(width 0.127)
		(layer "In5.Cu")
		(net "UART_RTS_P2_L_N")
	)
	(segment
		(start 16.649446 -109.957616)
		(end 16.649446 -105.446068)
		(width 0.127)
		(layer "In5.Cu")
		(net "UART_RTS_P2_L_N")
	)
	(segment
		(start 6.672834 -50.40376)
		(end 4.50469 -52.571904)
		(width 0.127)
		(layer "In5.Cu")
		(net "UART_RTS_P2_L_N")
	)
	(segment
		(start 16.649446 -105.446068)
		(end 12.333986 -101.130608)
		(width 0.127)
		(layer "In5.Cu")
		(net "UART_RTS_P2_L_N")
	)
	(segment
		(start 24.06015 -131.868418)
		(end 19.00936 -126.817628)
		(width 0.127)
		(layer "In5.Cu")
		(net "UART_RTS_P2_L_N")
	)
	(segment
		(start 14.56563 -194.553586)
		(end 14.56563 -176.212246)
		(width 0.127)
		(layer "In5.Cu")
		(net "UART_RTS_P2_L_N")
	)
	(segment
		(start 12.333986 -101.130608)
		(end 12.333986 -79.41945)
		(width 0.127)
		(layer "In5.Cu")
		(net "UART_RTS_P2_L_N")
	)
	(segment
		(start 10.901426 -115.705636)
		(end 16.649446 -109.957616)
		(width 0.127)
		(layer "In5.Cu")
		(net "UART_RTS_P2_L_N")
	)
	(segment
		(start 14.56563 -176.212246)
		(end 24.06015 -166.717726)
		(width 0.127)
		(layer "In5.Cu")
		(net "UART_RTS_P2_L_N")
	)
	(segment
		(start 17.451832 -126.817628)
		(end 10.901426 -120.267222)
		(width 0.127)
		(layer "In5.Cu")
		(net "UART_RTS_P2_L_N")
	)
	(segment
		(start 19.360642 -72.392794)
		(end 19.360642 -56.77154)
		(width 0.127)
		(layer "In5.Cu")
		(net "UART_RTS_P2_L_N")
	)
	(segment
		(start 19.00936 -126.817628)
		(end 17.451832 -126.817628)
		(width 0.127)
		(layer "In5.Cu")
		(net "UART_RTS_P2_L_N")
	)
	(segment
		(start 10.555986 -101.867208)
		(end 10.555986 -78.68285)
		(width 0.127)
		(layer "In5.Cu")
		(net "UART_CTS_P2_L_N")
	)
	(segment
		(start 6.448806 -195.670678)
		(end 8.860536 -195.670678)
		(width 0.127)
		(layer "In5.Cu")
		(net "UART_CTS_P2_L_N")
	)
	(segment
		(start 14.871446 -109.221016)
		(end 14.871446 -106.182668)
		(width 0.127)
		(layer "In5.Cu")
		(net "UART_CTS_P2_L_N")
	)
	(segment
		(start 16.767302 -128.468628)
		(end 9.250426 -120.951752)
		(width 0.127)
		(layer "In5.Cu")
		(net "UART_CTS_P2_L_N")
	)
	(segment
		(start 17.582642 -59.299856)
		(end 13.39469 -55.111904)
		(width 0.127)
		(layer "In5.Cu")
		(net "UART_CTS_P2_L_N")
	)
	(segment
		(start 10.555986 -78.68285)
		(end 17.582642 -71.656194)
		(width 0.127)
		(layer "In5.Cu")
		(net "UART_CTS_P2_L_N")
	)
	(segment
		(start 12.78763 -175.475646)
		(end 22.28215 -165.981126)
		(width 0.127)
		(layer "In5.Cu")
		(net "UART_CTS_P2_L_N")
	)
	(segment
		(start 17.582642 -71.656194)
		(end 17.582642 -59.299856)
		(width 0.127)
		(layer "In5.Cu")
		(net "UART_CTS_P2_L_N")
	)
	(segment
		(start 17.941798 -128.468628)
		(end 16.767302 -128.468628)
		(width 0.127)
		(layer "In5.Cu")
		(net "UART_CTS_P2_L_N")
	)
	(segment
		(start 9.250426 -120.951752)
		(end 9.250426 -114.842036)
		(width 0.127)
		(layer "In5.Cu")
		(net "UART_CTS_P2_L_N")
	)
	(segment
		(start 22.28215 -165.981126)
		(end 22.28215 -132.80898)
		(width 0.127)
		(layer "In5.Cu")
		(net "UART_CTS_P2_L_N")
	)
	(segment
		(start 12.78763 -191.743584)
		(end 12.78763 -175.475646)
		(width 0.127)
		(layer "In5.Cu")
		(net "UART_CTS_P2_L_N")
	)
	(segment
		(start 14.871446 -106.182668)
		(end 10.555986 -101.867208)
		(width 0.127)
		(layer "In5.Cu")
		(net "UART_CTS_P2_L_N")
	)
	(segment
		(start 22.28215 -132.80898)
		(end 17.941798 -128.468628)
		(width 0.127)
		(layer "In5.Cu")
		(net "UART_CTS_P2_L_N")
	)
	(segment
		(start 8.860536 -195.670678)
		(end 12.78763 -191.743584)
		(width 0.127)
		(layer "In5.Cu")
		(net "UART_CTS_P2_L_N")
	)
	(segment
		(start 9.250426 -114.842036)
		(end 14.871446 -109.221016)
		(width 0.127)
		(layer "In5.Cu")
		(net "UART_CTS_P2_L_N")
	)
	(segment
		(start 15.938246 -109.662976)
		(end 15.938246 -105.740708)
		(width 0.127)
		(layer "In5.Cu")
		(net "UART_RX_P2_L")
	)
	(segment
		(start 23.34895 -132.196332)
		(end 18.630646 -127.478028)
		(width 0.127)
		(layer "In5.Cu")
		(net "UART_RX_P2_L")
	)
	(segment
		(start 23.34895 -166.423086)
		(end 23.34895 -132.196332)
		(width 0.127)
		(layer "In5.Cu")
		(net "UART_RX_P2_L")
	)
	(segment
		(start 8.501634 -51.11496)
		(end 7.04469 -52.571904)
		(width 0.127)
		(layer "In5.Cu")
		(net "UART_RX_P2_L")
	)
	(segment
		(start 11.622786 -79.12481)
		(end 18.649442 -72.098154)
		(width 0.127)
		(layer "In5.Cu")
		(net "UART_RX_P2_L")
	)
	(segment
		(start 15.938246 -105.740708)
		(end 11.622786 -101.425248)
		(width 0.127)
		(layer "In5.Cu")
		(net "UART_RX_P2_L")
	)
	(segment
		(start 12.697968 -51.11496)
		(end 8.501634 -51.11496)
		(width 0.127)
		(layer "In5.Cu")
		(net "UART_RX_P2_L")
	)
	(segment
		(start 8.448802 -198.670418)
		(end 13.85443 -193.26479)
		(width 0.127)
		(layer "In5.Cu")
		(net "UART_RX_P2_L")
	)
	(segment
		(start 18.649442 -57.066434)
		(end 12.697968 -51.11496)
		(width 0.127)
		(layer "In5.Cu")
		(net "UART_RX_P2_L")
	)
	(segment
		(start 18.649442 -72.098154)
		(end 18.649442 -57.066434)
		(width 0.127)
		(layer "In5.Cu")
		(net "UART_RX_P2_L")
	)
	(segment
		(start 18.630646 -127.478028)
		(end 17.17802 -127.478028)
		(width 0.127)
		(layer "In5.Cu")
		(net "UART_RX_P2_L")
	)
	(segment
		(start 10.241026 -120.541034)
		(end 10.241026 -115.360196)
		(width 0.127)
		(layer "In5.Cu")
		(net "UART_RX_P2_L")
	)
	(segment
		(start 13.85443 -175.917606)
		(end 23.34895 -166.423086)
		(width 0.127)
		(layer "In5.Cu")
		(net "UART_RX_P2_L")
	)
	(segment
		(start 10.241026 -115.360196)
		(end 15.938246 -109.662976)
		(width 0.127)
		(layer "In5.Cu")
		(net "UART_RX_P2_L")
	)
	(segment
		(start 17.17802 -127.478028)
		(end 10.241026 -120.541034)
		(width 0.127)
		(layer "In5.Cu")
		(net "UART_RX_P2_L")
	)
	(segment
		(start 11.622786 -101.425248)
		(end 11.622786 -79.12481)
		(width 0.127)
		(layer "In5.Cu")
		(net "UART_RX_P2_L")
	)
	(segment
		(start 13.85443 -193.26479)
		(end 13.85443 -175.917606)
		(width 0.127)
		(layer "In5.Cu")
		(net "UART_RX_P2_L")
	)
	(segment
		(start 10.659872 -106.618278)
		(end 11.128248 -106.618278)
		(width 0.1524)
		(layer "B.Cu")
		(net "UART_DTR_P6_L_N")
	)
	(segment
		(start 9.554718 -203.564744)
		(end 9.554718 -202.691746)
		(width 0.1524)
		(layer "B.Cu")
		(net "UART_DTR_P6_L_N")
	)
	(segment
		(start 7.429246 -120.83161)
		(end 7.429246 -114.614198)
		(width 0.1524)
		(layer "B.Cu")
		(net "UART_DTR_P6_L_N")
	)
	(segment
		(start 11.128248 -106.618278)
		(end 12.12469 -105.621836)
		(width 0.1524)
		(layer "B.Cu")
		(net "UART_DTR_P6_L_N")
	)
	(segment
		(start 8.448802 -204.67066)
		(end 9.554718 -203.564744)
		(width 0.1524)
		(layer "B.Cu")
		(net "UART_DTR_P6_L_N")
	)
	(segment
		(start 18.166588 -142.406624)
		(end 19.985228 -140.587984)
		(width 0.1524)
		(layer "B.Cu")
		(net "UART_DTR_P6_L_N")
	)
	(segment
		(start 19.985228 -133.387592)
		(end 7.429246 -120.83161)
		(width 0.1524)
		(layer "B.Cu")
		(net "UART_DTR_P6_L_N")
	)
	(segment
		(start 9.63295 -112.410494)
		(end 9.63295 -107.6452)
		(width 0.1524)
		(layer "B.Cu")
		(net "UART_DTR_P6_L_N")
	)
	(segment
		(start 7.429246 -114.614198)
		(end 9.63295 -112.410494)
		(width 0.1524)
		(layer "B.Cu")
		(net "UART_DTR_P6_L_N")
	)
	(segment
		(start 9.554718 -202.691746)
		(end 18.166588 -194.079876)
		(width 0.1524)
		(layer "B.Cu")
		(net "UART_DTR_P6_L_N")
	)
	(segment
		(start 9.63295 -107.6452)
		(end 10.659872 -106.618278)
		(width 0.1524)
		(layer "B.Cu")
		(net "UART_DTR_P6_L_N")
	)
	(segment
		(start 18.166588 -194.079876)
		(end 18.166588 -142.406624)
		(width 0.1524)
		(layer "B.Cu")
		(net "UART_DTR_P6_L_N")
	)
	(segment
		(start 19.985228 -140.587984)
		(end 19.985228 -133.387592)
		(width 0.1524)
		(layer "B.Cu")
		(net "UART_DTR_P6_L_N")
	)
	(segment
		(start 9.910318 -204.419708)
		(end 9.910318 -202.839066)
		(width 0.1524)
		(layer "B.Cu")
		(net "UART_TX_P6_L")
	)
	(segment
		(start 6.448806 -205.670658)
		(end 8.659368 -205.670658)
		(width 0.1524)
		(layer "B.Cu")
		(net "UART_TX_P6_L")
	)
	(segment
		(start 8.659368 -205.670658)
		(end 9.910318 -204.419708)
		(width 0.1524)
		(layer "B.Cu")
		(net "UART_TX_P6_L")
	)
	(segment
		(start 7.784846 -115.023138)
		(end 10.85469 -111.953294)
		(width 0.1524)
		(layer "B.Cu")
		(net "UART_TX_P6_L")
	)
	(segment
		(start 9.910318 -202.839066)
		(end 18.522188 -194.227196)
		(width 0.1524)
		(layer "B.Cu")
		(net "UART_TX_P6_L")
	)
	(segment
		(start 18.522188 -194.227196)
		(end 18.522188 -142.553944)
		(width 0.1524)
		(layer "B.Cu")
		(net "UART_TX_P6_L")
	)
	(segment
		(start 7.784846 -120.68429)
		(end 7.784846 -115.023138)
		(width 0.1524)
		(layer "B.Cu")
		(net "UART_TX_P6_L")
	)
	(segment
		(start 20.340828 -133.240272)
		(end 7.784846 -120.68429)
		(width 0.1524)
		(layer "B.Cu")
		(net "UART_TX_P6_L")
	)
	(segment
		(start 18.522188 -142.553944)
		(end 20.340828 -140.735304)
		(width 0.1524)
		(layer "B.Cu")
		(net "UART_TX_P6_L")
	)
	(segment
		(start 10.85469 -111.953294)
		(end 10.85469 -108.161836)
		(width 0.1524)
		(layer "B.Cu")
		(net "UART_TX_P6_L")
	)
	(segment
		(start 20.340828 -140.735304)
		(end 20.340828 -133.240272)
		(width 0.1524)
		(layer "B.Cu")
		(net "UART_TX_P6_L")
	)
	(segment
		(start 8.448802 -208.670652)
		(end 10.977118 -206.142336)
		(width 0.1524)
		(layer "B.Cu")
		(net "UART_RTS_P6_L_N")
	)
	(segment
		(start 15.261336 -104.955594)
		(end 13.512038 -103.206296)
		(width 0.1524)
		(layer "B.Cu")
		(net "UART_RTS_P6_L_N")
	)
	(segment
		(start 8.851646 -120.24233)
		(end 8.851646 -115.67414)
		(width 0.1524)
		(layer "B.Cu")
		(net "UART_RTS_P6_L_N")
	)
	(segment
		(start 10.977118 -206.142336)
		(end 10.977118 -203.281026)
		(width 0.1524)
		(layer "B.Cu")
		(net "UART_RTS_P6_L_N")
	)
	(segment
		(start 19.588988 -142.995904)
		(end 21.407628 -141.177264)
		(width 0.1524)
		(layer "B.Cu")
		(net "UART_RTS_P6_L_N")
	)
	(segment
		(start 8.851646 -115.67414)
		(end 15.261336 -109.26445)
		(width 0.1524)
		(layer "B.Cu")
		(net "UART_RTS_P6_L_N")
	)
	(segment
		(start 13.512038 -103.206296)
		(end 6.92023 -103.206296)
		(width 0.1524)
		(layer "B.Cu")
		(net "UART_RTS_P6_L_N")
	)
	(segment
		(start 19.588988 -194.669156)
		(end 19.588988 -142.995904)
		(width 0.1524)
		(layer "B.Cu")
		(net "UART_RTS_P6_L_N")
	)
	(segment
		(start 21.407628 -141.177264)
		(end 21.407628 -132.798312)
		(width 0.1524)
		(layer "B.Cu")
		(net "UART_RTS_P6_L_N")
	)
	(segment
		(start 21.407628 -132.798312)
		(end 8.851646 -120.24233)
		(width 0.1524)
		(layer "B.Cu")
		(net "UART_RTS_P6_L_N")
	)
	(segment
		(start 6.92023 -103.206296)
		(end 4.50469 -105.621836)
		(width 0.1524)
		(layer "B.Cu")
		(net "UART_RTS_P6_L_N")
	)
	(segment
		(start 15.261336 -109.26445)
		(end 15.261336 -104.955594)
		(width 0.1524)
		(layer "B.Cu")
		(net "UART_RTS_P6_L_N")
	)
	(segment
		(start 10.977118 -203.281026)
		(end 19.588988 -194.669156)
		(width 0.1524)
		(layer "B.Cu")
		(net "UART_RTS_P6_L_N")
	)
	(segment
		(start 18.877788 -142.701264)
		(end 20.696428 -140.882624)
		(width 0.1524)
		(layer "B.Cu")
		(net "UART_RX_P6_L")
	)
	(segment
		(start 18.877788 -194.374516)
		(end 18.877788 -142.701264)
		(width 0.1524)
		(layer "B.Cu")
		(net "UART_RX_P6_L")
	)
	(segment
		(start 20.696428 -133.092952)
		(end 8.140446 -120.53697)
		(width 0.1524)
		(layer "B.Cu")
		(net "UART_RX_P6_L")
	)
	(segment
		(start 10.265918 -204.842364)
		(end 10.265918 -202.986386)
		(width 0.1524)
		(layer "B.Cu")
		(net "UART_RX_P6_L")
	)
	(segment
		(start 8.448802 -206.670656)
		(end 9.129522 -205.989936)
		(width 0.1524)
		(layer "B.Cu")
		(net "UART_RX_P6_L")
	)
	(segment
		(start 10.265918 -202.986386)
		(end 18.877788 -194.374516)
		(width 0.1524)
		(layer "B.Cu")
		(net "UART_RX_P6_L")
	)
	(segment
		(start 8.140446 -115.202462)
		(end 14.402054 -108.940854)
		(width 0.1524)
		(layer "B.Cu")
		(net "UART_RX_P6_L")
	)
	(segment
		(start 12.858496 -103.917496)
		(end 8.74903 -103.917496)
		(width 0.1524)
		(layer "B.Cu")
		(net "UART_RX_P6_L")
	)
	(segment
		(start 14.402054 -108.940854)
		(end 14.402054 -105.461054)
		(width 0.1524)
		(layer "B.Cu")
		(net "UART_RX_P6_L")
	)
	(segment
		(start 8.140446 -120.53697)
		(end 8.140446 -115.202462)
		(width 0.1524)
		(layer "B.Cu")
		(net "UART_RX_P6_L")
	)
	(segment
		(start 14.402054 -105.461054)
		(end 12.858496 -103.917496)
		(width 0.1524)
		(layer "B.Cu")
		(net "UART_RX_P6_L")
	)
	(segment
		(start 9.129522 -205.97876)
		(end 10.265918 -204.842364)
		(width 0.1524)
		(layer "B.Cu")
		(net "UART_RX_P6_L")
	)
	(segment
		(start 8.74903 -103.917496)
		(end 7.04469 -105.621836)
		(width 0.1524)
		(layer "B.Cu")
		(net "UART_RX_P6_L")
	)
	(segment
		(start 9.129522 -205.989936)
		(end 9.129522 -205.97876)
		(width 0.1524)
		(layer "B.Cu")
		(net "UART_RX_P6_L")
	)
	(segment
		(start 20.696428 -140.882624)
		(end 20.696428 -133.092952)
		(width 0.1524)
		(layer "B.Cu")
		(net "UART_RX_P6_L")
	)
	(segment
		(start 16.455644 -130.449828)
		(end 15.945866 -130.449828)
		(width 0.127)
		(layer "In5.Cu")
		(net "UART_RI_P5_L_N")
	)
	(segment
		(start 1.948942 -202.67041)
		(end 2.920238 -201.699114)
		(width 0.127)
		(layer "In5.Cu")
		(net "UART_RI_P5_L_N")
	)
	(segment
		(start 6.210046 -190.397384)
		(end 7.099554 -190.397384)
		(width 0.127)
		(layer "In5.Cu")
		(net "UART_RI_P5_L_N")
	)
	(segment
		(start 2.920238 -201.699114)
		(end 2.920238 -201.2442)
		(width 0.127)
		(layer "In5.Cu")
		(net "UART_RI_P5_L_N")
	)
	(segment
		(start 4.20116 -192.40627)
		(end 6.210046 -190.397384)
		(width 0.127)
		(layer "In5.Cu")
		(net "UART_RI_P5_L_N")
	)
	(segment
		(start 7.099554 -190.397384)
		(end 8.052054 -189.444884)
		(width 0.127)
		(layer "In5.Cu")
		(net "UART_RI_P5_L_N")
	)
	(segment
		(start 7.29234 -61.680344)
		(end 9.58469 -59.387994)
		(width 0.127)
		(layer "In5.Cu")
		(net "UART_RI_P5_L_N")
	)
	(segment
		(start 5.323586 -102.12959)
		(end 7.9756 -99.477576)
		(width 0.127)
		(layer "In5.Cu")
		(net "UART_RI_P5_L_N")
	)
	(segment
		(start 3.758184 -192.40627)
		(end 4.20116 -192.40627)
		(width 0.127)
		(layer "In5.Cu")
		(net "UART_RI_P5_L_N")
	)
	(segment
		(start 3.01117 -198.188072)
		(end 2.828798 -198.0057)
		(width 0.127)
		(layer "In5.Cu")
		(net "UART_RI_P5_L_N")
	)
	(segment
		(start 15.945866 -130.449828)
		(end 7.269226 -121.773188)
		(width 0.127)
		(layer "In5.Cu")
		(net "UART_RI_P5_L_N")
	)
	(segment
		(start 2.856738 -199.307704)
		(end 3.01117 -199.153272)
		(width 0.127)
		(layer "In5.Cu")
		(net "UART_RI_P5_L_N")
	)
	(segment
		(start 3.03911 -200.216008)
		(end 2.856738 -200.033636)
		(width 0.127)
		(layer "In5.Cu")
		(net "UART_RI_P5_L_N")
	)
	(segment
		(start 19.549364 -133.543548)
		(end 16.455644 -130.449828)
		(width 0.127)
		(layer "In5.Cu")
		(net "UART_RI_P5_L_N")
	)
	(segment
		(start 1.727454 -110.25505)
		(end 1.727454 -104.38892)
		(width 0.127)
		(layer "In5.Cu")
		(net "UART_RI_P5_L_N")
	)
	(segment
		(start 3.083814 -194.260724)
		(end 2.920238 -194.097148)
		(width 0.127)
		(layer "In5.Cu")
		(net "UART_RI_P5_L_N")
	)
	(segment
		(start 8.052054 -189.444884)
		(end 8.662416 -189.444884)
		(width 0.127)
		(layer "In5.Cu")
		(net "UART_RI_P5_L_N")
	)
	(segment
		(start 11.229594 -169.972482)
		(end 19.549364 -161.652712)
		(width 0.127)
		(layer "In5.Cu")
		(net "UART_RI_P5_L_N")
	)
	(segment
		(start 2.828798 -197.335648)
		(end 3.03911 -197.125336)
		(width 0.127)
		(layer "In5.Cu")
		(net "UART_RI_P5_L_N")
	)
	(segment
		(start 2.856738 -200.033636)
		(end 2.856738 -199.307704)
		(width 0.127)
		(layer "In5.Cu")
		(net "UART_RI_P5_L_N")
	)
	(segment
		(start 3.986784 -102.12959)
		(end 5.323586 -102.12959)
		(width 0.127)
		(layer "In5.Cu")
		(net "UART_RI_P5_L_N")
	)
	(segment
		(start 8.662416 -189.444884)
		(end 10.109708 -187.997592)
		(width 0.127)
		(layer "In5.Cu")
		(net "UART_RI_P5_L_N")
	)
	(segment
		(start 2.920238 -193.244216)
		(end 3.758184 -192.40627)
		(width 0.127)
		(layer "In5.Cu")
		(net "UART_RI_P5_L_N")
	)
	(segment
		(start 7.269226 -121.773188)
		(end 7.269226 -115.796822)
		(width 0.127)
		(layer "In5.Cu")
		(net "UART_RI_P5_L_N")
	)
	(segment
		(start 7.9756 -63.048134)
		(end 7.29234 -62.364874)
		(width 0.127)
		(layer "In5.Cu")
		(net "UART_RI_P5_L_N")
	)
	(segment
		(start 2.828798 -198.0057)
		(end 2.828798 -197.335648)
		(width 0.127)
		(layer "In5.Cu")
		(net "UART_RI_P5_L_N")
	)
	(segment
		(start 3.03911 -196.216016)
		(end 2.815082 -195.991988)
		(width 0.127)
		(layer "In5.Cu")
		(net "UART_RI_P5_L_N")
	)
	(segment
		(start 3.083814 -195.080636)
		(end 3.083814 -194.260724)
		(width 0.127)
		(layer "In5.Cu")
		(net "UART_RI_P5_L_N")
	)
	(segment
		(start 3.01117 -199.153272)
		(end 3.01117 -198.188072)
		(width 0.127)
		(layer "In5.Cu")
		(net "UART_RI_P5_L_N")
	)
	(segment
		(start 2.920238 -201.2442)
		(end 3.03911 -201.125328)
		(width 0.127)
		(layer "In5.Cu")
		(net "UART_RI_P5_L_N")
	)
	(segment
		(start 3.03911 -201.125328)
		(end 3.03911 -200.216008)
		(width 0.127)
		(layer "In5.Cu")
		(net "UART_RI_P5_L_N")
	)
	(segment
		(start 2.815082 -195.349368)
		(end 3.083814 -195.080636)
		(width 0.127)
		(layer "In5.Cu")
		(net "UART_RI_P5_L_N")
	)
	(segment
		(start 10.109708 -187.997592)
		(end 10.109708 -171.092622)
		(width 0.127)
		(layer "In5.Cu")
		(net "UART_RI_P5_L_N")
	)
	(segment
		(start 2.815082 -195.991988)
		(end 2.815082 -195.349368)
		(width 0.127)
		(layer "In5.Cu")
		(net "UART_RI_P5_L_N")
	)
	(segment
		(start 10.109708 -171.092622)
		(end 11.229594 -169.972482)
		(width 0.127)
		(layer "In5.Cu")
		(net "UART_RI_P5_L_N")
	)
	(segment
		(start 7.29234 -62.364874)
		(end 7.29234 -61.680344)
		(width 0.127)
		(layer "In5.Cu")
		(net "UART_RI_P5_L_N")
	)
	(segment
		(start 3.03911 -197.125336)
		(end 3.03911 -196.216016)
		(width 0.127)
		(layer "In5.Cu")
		(net "UART_RI_P5_L_N")
	)
	(segment
		(start 1.727454 -104.38892)
		(end 3.986784 -102.12959)
		(width 0.127)
		(layer "In5.Cu")
		(net "UART_RI_P5_L_N")
	)
	(segment
		(start 7.9756 -99.477576)
		(end 7.9756 -63.048134)
		(width 0.127)
		(layer "In5.Cu")
		(net "UART_RI_P5_L_N")
	)
	(segment
		(start 19.549364 -161.652712)
		(end 19.549364 -133.543548)
		(width 0.127)
		(layer "In5.Cu")
		(net "UART_RI_P5_L_N")
	)
	(segment
		(start 7.269226 -115.796822)
		(end 1.727454 -110.25505)
		(width 0.127)
		(layer "In5.Cu")
		(net "UART_RI_P5_L_N")
	)
	(segment
		(start 2.920238 -194.097148)
		(end 2.920238 -193.244216)
		(width 0.127)
		(layer "In5.Cu")
		(net "UART_RI_P5_L_N")
	)
	(segment
		(start 19.274028 -133.682232)
		(end 6.718046 -121.12625)
		(width 0.1524)
		(layer "B.Cu")
		(net "UART_RI_P6_L_N")
	)
	(segment
		(start 6.718046 -121.12625)
		(end 6.718046 -114.130074)
		(width 0.1524)
		(layer "B.Cu")
		(net "UART_RI_P6_L_N")
	)
	(segment
		(start 17.455388 -193.663824)
		(end 17.455388 -142.111984)
		(width 0.1524)
		(layer "B.Cu")
		(net "UART_RI_P6_L_N")
	)
	(segment
		(start 6.718046 -114.130074)
		(end 8.31469 -112.53343)
		(width 0.1524)
		(layer "B.Cu")
		(net "UART_RI_P6_L_N")
	)
	(segment
		(start 19.274028 -140.293344)
		(end 19.274028 -133.682232)
		(width 0.1524)
		(layer "B.Cu")
		(net "UART_RI_P6_L_N")
	)
	(segment
		(start 8.448802 -202.67041)
		(end 17.455388 -193.663824)
		(width 0.1524)
		(layer "B.Cu")
		(net "UART_RI_P6_L_N")
	)
	(segment
		(start 8.31469 -112.53343)
		(end 8.31469 -108.161836)
		(width 0.1524)
		(layer "B.Cu")
		(net "UART_RI_P6_L_N")
	)
	(segment
		(start 17.455388 -142.111984)
		(end 19.274028 -140.293344)
		(width 0.1524)
		(layer "B.Cu")
		(net "UART_RI_P6_L_N")
	)
	(segment
		(start 29.657294 -21.168614)
		(end 34.1757 -21.168614)
		(width 0.508)
		(layer "F.Cu")
		(net "P12V_STBY")
	)
	(segment
		(start 27.741626 -179.640484)
		(end 36.849558 -179.640484)
		(width 0.508)
		(layer "F.Cu")
		(net "P12V_STBY")
	)
	(segment
		(start 23.875238 -445.63538)
		(end 28.767278 -440.74334)
		(width 0.508)
		(layer "F.Cu")
		(net "P12V_STBY")
	)
	(segment
		(start 24.011382 -183.64962)
		(end 24.011382 -181.147212)
		(width 0.508)
		(layer "F.Cu")
		(net "P12V_STBY")
	)
	(segment
		(start 24.62784 -184.266078)
		(end 24.011382 -183.64962)
		(width 0.508)
		(layer "F.Cu")
		(net "P12V_STBY")
	)
	(segment
		(start 23.015448 -197.410578)
		(end 28.245562 -202.640692)
		(width 0.508)
		(layer "F.Cu")
		(net "P12V_STBY")
	)
	(segment
		(start 23.830534 -358.909366)
		(end 27.558492 -355.181408)
		(width 0.508)
		(layer "F.Cu")
		(net "P12V_STBY")
	)
	(segment
		(start 24.570944 -96.872044)
		(end 23.662386 -95.963486)
		(width 0.508)
		(layer "F.Cu")
		(net "P12V_STBY")
	)
	(segment
		(start 23.82774 -456.592178)
		(end 23.82774 -451.913498)
		(width 0.508)
		(layer "F.Cu")
		(net "P12V_STBY")
	)
	(segment
		(start 28.245562 -260.847586)
		(end 33.994598 -266.596622)
		(width 0.508)
		(layer "F.Cu")
		(net "P12V_STBY")
	)
	(segment
		(start 32.058864 -91.124532)
		(end 33.268412 -92.33408)
		(width 0.508)
		(layer "F.Cu")
		(net "P12V_STBY")
	)
	(segment
		(start 39.398702 -195.88353)
		(end 39.398702 -197.274942)
		(width 0.508)
		(layer "F.Cu")
		(net "P12V_STBY")
	)
	(segment
		(start 35.51428 -19.830034)
		(end 35.53968 -19.830034)
		(width 0.508)
		(layer "F.Cu")
		(net "P12V_STBY")
	)
	(segment
		(start 28.417266 -458.940154)
		(end 26.175716 -458.940154)
		(width 0.508)
		(layer "F.Cu")
		(net "P12V_STBY")
	)
	(segment
		(start 28.732226 -90.075004)
		(end 28.732226 -22.093682)
		(width 0.508)
		(layer "F.Cu")
		(net "P12V_STBY")
	)
	(segment
		(start 31.679896 -355.181408)
		(end 27.558492 -355.181408)
		(width 0.508)
		(layer "F.Cu")
		(net "P12V_STBY")
	)
	(segment
		(start 39.534592 -374.14708)
		(end 36.256722 -374.14708)
		(width 0.508)
		(layer "F.Cu")
		(net "P12V_STBY")
	)
	(segment
		(start 42.218356 -190.186564)
		(end 42.218356 -194.86499)
		(width 0.508)
		(layer "F.Cu")
		(net "P12V_STBY")
	)
	(segment
		(start 24.760682 -450.980556)
		(end 25.825958 -450.980556)
		(width 0.508)
		(layer "F.Cu")
		(net "P12V_STBY")
	)
	(segment
		(start 25.825958 -449.713858)
		(end 25.825958 -450.980556)
		(width 0.508)
		(layer "F.Cu")
		(net "P12V_STBY")
	)
	(segment
		(start 37.547296 -106.222292)
		(end 35.53968 -108.229908)
		(width 0.508)
		(layer "F.Cu")
		(net "P12V_STBY")
	)
	(segment
		(start 24.482044 -363.01553)
		(end 23.830534 -362.36402)
		(width 0.508)
		(layer "F.Cu")
		(net "P12V_STBY")
	)
	(segment
		(start 24.278082 -7.19328)
		(end 25.597612 -7.19328)
		(width 0.508)
		(layer "F.Cu")
		(net "P12V_STBY")
	)
	(segment
		(start 39.653718 -283.496258)
		(end 37.073332 -283.496258)
		(width 0.508)
		(layer "F.Cu")
		(net "P12V_STBY")
	)
	(segment
		(start 36.955476 -18.414238)
		(end 35.53968 -19.830034)
		(width 0.508)
		(layer "F.Cu")
		(net "P12V_STBY")
	)
	(segment
		(start 28.767278 -440.74334)
		(end 28.767278 -380.704598)
		(width 0.508)
		(layer "F.Cu")
		(net "P12V_STBY")
	)
	(segment
		(start 34.271712 -18.562066)
		(end 29.408628 -18.562066)
		(width 0.508)
		(layer "F.Cu")
		(net "P12V_STBY")
	)
	(segment
		(start 29.656786 -379.81509)
		(end 31.328868 -379.81509)
		(width 0.508)
		(layer "F.Cu")
		(net "P12V_STBY")
	)
	(segment
		(start 34.289746 -286.279844)
		(end 35.53968 -285.02991)
		(width 0.508)
		(layer "F.Cu")
		(net "P12V_STBY")
	)
	(segment
		(start 25.531572 -98.10369)
		(end 25.531572 -96.872044)
		(width 0.508)
		(layer "F.Cu")
		(net "P12V_STBY")
	)
	(segment
		(start 35.53968 -461.829912)
		(end 31.751778 -458.04201)
		(width 0.508)
		(layer "F.Cu")
		(net "P12V_STBY")
	)
	(segment
		(start 31.328868 -379.81509)
		(end 32.60979 -378.534168)
		(width 0.508)
		(layer "F.Cu")
		(net "P12V_STBY")
	)
	(segment
		(start 36.081208 -462.37144)
		(end 35.53968 -461.829912)
		(width 0.508)
		(layer "F.Cu")
		(net "P12V_STBY")
	)
	(segment
		(start 25.531572 -96.872044)
		(end 24.570944 -96.872044)
		(width 0.508)
		(layer "F.Cu")
		(net "P12V_STBY")
	)
	(segment
		(start 38.755066 -181.545992)
		(end 38.755066 -186.723274)
		(width 0.508)
		(layer "F.Cu")
		(net "P12V_STBY")
	)
	(segment
		(start 33.490154 -356.991666)
		(end 31.679896 -355.181408)
		(width 0.508)
		(layer "F.Cu")
		(net "P12V_STBY")
	)
	(segment
		(start 28.767278 -380.704598)
		(end 29.656786 -379.81509)
		(width 0.508)
		(layer "F.Cu")
		(net "P12V_STBY")
	)
	(segment
		(start 22.339046 -108.177838)
		(end 22.339046 -104.90454)
		(width 0.508)
		(layer "F.Cu")
		(net "P12V_STBY")
	)
	(segment
		(start 35.53968 -373.430038)
		(end 33.490154 -371.380512)
		(width 0.508)
		(layer "F.Cu")
		(net "P12V_STBY")
	)
	(segment
		(start 29.31541 -458.04201)
		(end 28.417266 -458.940154)
		(width 0.508)
		(layer "F.Cu")
		(net "P12V_STBY")
	)
	(segment
		(start 27.914346 -17.067784)
		(end 25.192482 -17.067784)
		(width 0.508)
		(layer "F.Cu")
		(net "P12V_STBY")
	)
	(segment
		(start 27.741626 -179.640484)
		(end 27.741626 -178.395376)
		(width 0.508)
		(layer "F.Cu")
		(net "P12V_STBY")
	)
	(segment
		(start 27.558492 -355.181408)
		(end 27.558492 -311.419748)
		(width 0.508)
		(layer "F.Cu")
		(net "P12V_STBY")
	)
	(segment
		(start 23.662386 -95.963486)
		(end 23.662386 -94.041976)
		(width 0.508)
		(layer "F.Cu")
		(net "P12V_STBY")
	)
	(segment
		(start 29.781754 -91.124532)
		(end 28.732226 -90.075004)
		(width 0.508)
		(layer "F.Cu")
		(net "P12V_STBY")
	)
	(segment
		(start 36.256722 -374.14708)
		(end 35.53968 -373.430038)
		(width 0.508)
		(layer "F.Cu")
		(net "P12V_STBY")
	)
	(segment
		(start 28.245562 -202.640692)
		(end 28.245562 -260.847586)
		(width 0.508)
		(layer "F.Cu")
		(net "P12V_STBY")
	)
	(segment
		(start 22.339046 -104.90454)
		(end 23.12162 -104.121966)
		(width 0.508)
		(layer "F.Cu")
		(net "P12V_STBY")
	)
	(segment
		(start 33.994598 -266.596622)
		(end 33.994598 -283.484828)
		(width 0.508)
		(layer "F.Cu")
		(net "P12V_STBY")
	)
	(segment
		(start 39.708328 -195.573904)
		(end 39.398702 -195.88353)
		(width 0.508)
		(layer "F.Cu")
		(net "P12V_STBY")
	)
	(segment
		(start 42.218356 -194.86499)
		(end 41.509442 -195.573904)
		(width 0.508)
		(layer "F.Cu")
		(net "P12V_STBY")
	)
	(segment
		(start 23.875238 -448.37477)
		(end 23.875238 -445.63538)
		(width 0.508)
		(layer "F.Cu")
		(net "P12V_STBY")
	)
	(segment
		(start 32.60979 -378.534168)
		(end 32.60979 -376.359928)
		(width 0.508)
		(layer "F.Cu")
		(net "P12V_STBY")
	)
	(segment
		(start 25.214326 -449.713858)
		(end 23.875238 -448.37477)
		(width 0.508)
		(layer "F.Cu")
		(net "P12V_STBY")
	)
	(segment
		(start 37.073332 -283.496258)
		(end 35.53968 -285.02991)
		(width 0.508)
		(layer "F.Cu")
		(net "P12V_STBY")
	)
	(segment
		(start 25.51811 -179.640484)
		(end 27.741626 -179.640484)
		(width 0.508)
		(layer "F.Cu")
		(net "P12V_STBY")
	)
	(segment
		(start 25.702006 -274.774914)
		(end 25.702006 -273.532854)
		(width 0.4572)
		(layer "F.Cu")
		(net "P12V_STBY")
	)
	(segment
		(start 35.53968 -19.830034)
		(end 34.271712 -18.562066)
		(width 0.508)
		(layer "F.Cu")
		(net "P12V_STBY")
	)
	(segment
		(start 27.391106 -178.044856)
		(end 27.391106 -113.229898)
		(width 0.508)
		(layer "F.Cu")
		(net "P12V_STBY")
	)
	(segment
		(start 39.473886 -462.37144)
		(end 36.081208 -462.37144)
		(width 0.508)
		(layer "F.Cu")
		(net "P12V_STBY")
	)
	(segment
		(start 33.490154 -371.380512)
		(end 33.490154 -356.991666)
		(width 0.508)
		(layer "F.Cu")
		(net "P12V_STBY")
	)
	(segment
		(start 27.741626 -178.395376)
		(end 27.391106 -178.044856)
		(width 0.508)
		(layer "F.Cu")
		(net "P12V_STBY")
	)
	(segment
		(start 39.398702 -197.274942)
		(end 36.184586 -197.274942)
		(width 0.508)
		(layer "F.Cu")
		(net "P12V_STBY")
	)
	(segment
		(start 36.184586 -197.274942)
		(end 35.53968 -196.630036)
		(width 0.508)
		(layer "F.Cu")
		(net "P12V_STBY")
	)
	(segment
		(start 25.825958 -449.713858)
		(end 25.214326 -449.713858)
		(width 0.508)
		(layer "F.Cu")
		(net "P12V_STBY")
	)
	(segment
		(start 25.668224 -184.266078)
		(end 24.62784 -184.266078)
		(width 0.508)
		(layer "F.Cu")
		(net "P12V_STBY")
	)
	(segment
		(start 33.994598 -283.484828)
		(end 35.53968 -285.02991)
		(width 0.508)
		(layer "F.Cu")
		(net "P12V_STBY")
	)
	(segment
		(start 38.755066 -186.723274)
		(end 42.218356 -190.186564)
		(width 0.508)
		(layer "F.Cu")
		(net "P12V_STBY")
	)
	(segment
		(start 24.011382 -181.147212)
		(end 25.51811 -179.640484)
		(width 0.508)
		(layer "F.Cu")
		(net "P12V_STBY")
	)
	(segment
		(start 33.268412 -107.383834)
		(end 34.114486 -108.229908)
		(width 0.508)
		(layer "F.Cu")
		(net "P12V_STBY")
	)
	(segment
		(start 24.100028 -98.09099)
		(end 25.518872 -98.09099)
		(width 0.508)
		(layer "F.Cu")
		(net "P12V_STBY")
	)
	(segment
		(start 24.0538 -93.650562)
		(end 27.255724 -93.650562)
		(width 0.508)
		(layer "F.Cu")
		(net "P12V_STBY")
	)
	(segment
		(start 29.106368 -309.871872)
		(end 29.106368 -287.184846)
		(width 0.508)
		(layer "F.Cu")
		(net "P12V_STBY")
	)
	(segment
		(start 34.1757 -21.168614)
		(end 35.51428 -19.830034)
		(width 0.508)
		(layer "F.Cu")
		(net "P12V_STBY")
	)
	(segment
		(start 23.82774 -451.913498)
		(end 24.760682 -450.980556)
		(width 0.508)
		(layer "F.Cu")
		(net "P12V_STBY")
	)
	(segment
		(start 25.702006 -274.774914)
		(end 24.557736 -274.774914)
		(width 0.4572)
		(layer "F.Cu")
		(net "P12V_STBY")
	)
	(segment
		(start 25.597612 -7.19328)
		(end 25.597612 -6.169152)
		(width 0.508)
		(layer "F.Cu")
		(net "P12V_STBY")
	)
	(segment
		(start 23.12162 -99.069398)
		(end 24.100028 -98.09099)
		(width 0.508)
		(layer "F.Cu")
		(net "P12V_STBY")
	)
	(segment
		(start 27.558492 -311.419748)
		(end 29.106368 -309.871872)
		(width 0.508)
		(layer "F.Cu")
		(net "P12V_STBY")
	)
	(segment
		(start 28.732226 -22.093682)
		(end 29.657294 -21.168614)
		(width 0.508)
		(layer "F.Cu")
		(net "P12V_STBY")
	)
	(segment
		(start 27.391106 -113.229898)
		(end 22.339046 -108.177838)
		(width 0.508)
		(layer "F.Cu")
		(net "P12V_STBY")
	)
	(segment
		(start 32.60979 -376.359928)
		(end 35.53968 -373.430038)
		(width 0.508)
		(layer "F.Cu")
		(net "P12V_STBY")
	)
	(segment
		(start 23.82266 -15.697962)
		(end 23.82266 -7.648702)
		(width 0.508)
		(layer "F.Cu")
		(net "P12V_STBY")
	)
	(segment
		(start 39.421308 -18.414238)
		(end 36.955476 -18.414238)
		(width 0.508)
		(layer "F.Cu")
		(net "P12V_STBY")
	)
	(segment
		(start 27.255724 -93.650562)
		(end 29.781754 -91.124532)
		(width 0.508)
		(layer "F.Cu")
		(net "P12V_STBY")
	)
	(segment
		(start 25.192482 -17.067784)
		(end 23.82266 -15.697962)
		(width 0.508)
		(layer "F.Cu")
		(net "P12V_STBY")
	)
	(segment
		(start 39.705534 -106.222292)
		(end 37.547296 -106.222292)
		(width 0.508)
		(layer "F.Cu")
		(net "P12V_STBY")
	)
	(segment
		(start 30.01137 -286.279844)
		(end 34.289746 -286.279844)
		(width 0.508)
		(layer "F.Cu")
		(net "P12V_STBY")
	)
	(segment
		(start 31.751778 -458.04201)
		(end 29.31541 -458.04201)
		(width 0.508)
		(layer "F.Cu")
		(net "P12V_STBY")
	)
	(segment
		(start 23.12162 -104.121966)
		(end 23.12162 -99.069398)
		(width 0.508)
		(layer "F.Cu")
		(net "P12V_STBY")
	)
	(segment
		(start 23.662386 -94.041976)
		(end 24.0538 -93.650562)
		(width 0.508)
		(layer "F.Cu")
		(net "P12V_STBY")
	)
	(segment
		(start 34.114486 -108.229908)
		(end 35.53968 -108.229908)
		(width 0.508)
		(layer "F.Cu")
		(net "P12V_STBY")
	)
	(segment
		(start 25.668224 -185.521092)
		(end 25.668224 -184.266078)
		(width 0.508)
		(layer "F.Cu")
		(net "P12V_STBY")
	)
	(segment
		(start 36.849558 -179.640484)
		(end 38.755066 -181.545992)
		(width 0.508)
		(layer "F.Cu")
		(net "P12V_STBY")
	)
	(segment
		(start 23.82266 -7.648702)
		(end 24.278082 -7.19328)
		(width 0.508)
		(layer "F.Cu")
		(net "P12V_STBY")
	)
	(segment
		(start 24.319992 -185.521092)
		(end 23.015448 -186.825636)
		(width 0.508)
		(layer "F.Cu")
		(net "P12V_STBY")
	)
	(segment
		(start 25.597612 -6.169152)
		(end 25.576022 -6.147562)
		(width 0.508)
		(layer "F.Cu")
		(net "P12V_STBY")
	)
	(segment
		(start 29.106368 -287.184846)
		(end 30.01137 -286.279844)
		(width 0.508)
		(layer "F.Cu")
		(net "P12V_STBY")
	)
	(segment
		(start 25.668224 -185.521092)
		(end 24.319992 -185.521092)
		(width 0.508)
		(layer "F.Cu")
		(net "P12V_STBY")
	)
	(segment
		(start 33.268412 -92.33408)
		(end 33.268412 -107.383834)
		(width 0.508)
		(layer "F.Cu")
		(net "P12V_STBY")
	)
	(segment
		(start 23.015448 -186.825636)
		(end 23.015448 -197.410578)
		(width 0.508)
		(layer "F.Cu")
		(net "P12V_STBY")
	)
	(segment
		(start 23.830534 -362.36402)
		(end 23.830534 -358.909366)
		(width 0.508)
		(layer "F.Cu")
		(net "P12V_STBY")
	)
	(segment
		(start 25.518872 -98.09099)
		(end 25.531572 -98.10369)
		(width 0.508)
		(layer "F.Cu")
		(net "P12V_STBY")
	)
	(segment
		(start 25.457658 -363.01553)
		(end 24.482044 -363.01553)
		(width 0.508)
		(layer "F.Cu")
		(net "P12V_STBY")
	)
	(segment
		(start 29.408628 -18.562066)
		(end 27.914346 -17.067784)
		(width 0.508)
		(layer "F.Cu")
		(net "P12V_STBY")
	)
	(segment
		(start 25.457658 -364.246414)
		(end 25.457658 -363.01553)
		(width 0.508)
		(layer "F.Cu")
		(net "P12V_STBY")
	)
	(segment
		(start 26.175716 -458.940154)
		(end 23.82774 -456.592178)
		(width 0.508)
		(layer "F.Cu")
		(net "P12V_STBY")
	)
	(segment
		(start 29.781754 -91.124532)
		(end 32.058864 -91.124532)
		(width 0.508)
		(layer "F.Cu")
		(net "P12V_STBY")
	)
	(segment
		(start 41.509442 -195.573904)
		(end 39.708328 -195.573904)
		(width 0.508)
		(layer "F.Cu")
		(net "P12V_STBY")
	)
	(via
		(at 24.557736 -274.774914)
		(size 0.508)
		(drill 0.254)
		(layers "F.Cu" "B.Cu")
		(net "P12V_STBY")
	)
	(segment
		(start 8.015986 -334.452722)
		(end 7.005574 -333.44231)
		(width 0.127)
		(layer "In5.Cu")
		(net "UART_RI_RP5_L_N")
	)
	(segment
		(start 6.213856 -333.44231)
		(end 5.738114 -332.966568)
		(width 0.127)
		(layer "In5.Cu")
		(net "UART_RI_RP5_L_N")
	)
	(segment
		(start 8.799322 -489.843318)
		(end 8.799322 -471.07094)
		(width 0.127)
		(layer "In5.Cu")
		(net "UART_RI_RP5_L_N")
	)
	(segment
		(start 11.216894 -404.280878)
		(end 11.216894 -393.497816)
		(width 0.127)
		(layer "In5.Cu")
		(net "UART_RI_RP5_L_N")
	)
	(segment
		(start 8.799322 -471.07094)
		(end 16.874998 -462.995264)
		(width 0.127)
		(layer "In5.Cu")
		(net "UART_RI_RP5_L_N")
	)
	(segment
		(start 16.874998 -462.995264)
		(end 16.874998 -409.938982)
		(width 0.127)
		(layer "In5.Cu")
		(net "UART_RI_RP5_L_N")
	)
	(segment
		(start 8.953754 -334.452722)
		(end 8.015986 -334.452722)
		(width 0.127)
		(layer "In5.Cu")
		(net "UART_RI_RP5_L_N")
	)
	(segment
		(start 5.37464 -329.106784)
		(end 5.37464 -328.094594)
		(width 0.127)
		(layer "In5.Cu")
		(net "UART_RI_RP5_L_N")
	)
	(segment
		(start 5.738114 -329.470258)
		(end 5.37464 -329.106784)
		(width 0.127)
		(layer "In5.Cu")
		(net "UART_RI_RP5_L_N")
	)
	(segment
		(start 5.738114 -332.966568)
		(end 5.738114 -329.470258)
		(width 0.127)
		(layer "In5.Cu")
		(net "UART_RI_RP5_L_N")
	)
	(segment
		(start 7.005574 -333.44231)
		(end 6.213856 -333.44231)
		(width 0.127)
		(layer "In5.Cu")
		(net "UART_RI_RP5_L_N")
	)
	(segment
		(start 5.37464 -328.094594)
		(end 3.949954 -326.669908)
		(width 0.127)
		(layer "In5.Cu")
		(net "UART_RI_RP5_L_N")
	)
	(segment
		(start 14.402308 -497.555774)
		(end 14.402308 -495.446304)
		(width 0.127)
		(layer "In5.Cu")
		(net "UART_RI_RP5_L_N")
	)
	(segment
		(start 16.874998 -409.938982)
		(end 11.216894 -404.280878)
		(width 0.127)
		(layer "In5.Cu")
		(net "UART_RI_RP5_L_N")
	)
	(segment
		(start 11.152632 -336.6516)
		(end 8.953754 -334.452722)
		(width 0.127)
		(layer "In5.Cu")
		(net "UART_RI_RP5_L_N")
	)
	(segment
		(start 13.721588 -498.236494)
		(end 14.402308 -497.555774)
		(width 0.127)
		(layer "In5.Cu")
		(net "UART_RI_RP5_L_N")
	)
	(segment
		(start 8.748522 -391.029444)
		(end 8.748522 -381.119888)
		(width 0.127)
		(layer "In5.Cu")
		(net "UART_RI_RP5_L_N")
	)
	(segment
		(start 8.748522 -381.119888)
		(end 11.152632 -378.715778)
		(width 0.127)
		(layer "In5.Cu")
		(net "UART_RI_RP5_L_N")
	)
	(segment
		(start 9.39927 -498.236494)
		(end 13.721588 -498.236494)
		(width 0.127)
		(layer "In5.Cu")
		(net "UART_RI_RP5_L_N")
	)
	(segment
		(start 8.31469 -497.151914)
		(end 9.39927 -498.236494)
		(width 0.127)
		(layer "In5.Cu")
		(net "UART_RI_RP5_L_N")
	)
	(segment
		(start 14.402308 -495.446304)
		(end 8.799322 -489.843318)
		(width 0.127)
		(layer "In5.Cu")
		(net "UART_RI_RP5_L_N")
	)
	(segment
		(start 11.152632 -378.715778)
		(end 11.152632 -336.6516)
		(width 0.127)
		(layer "In5.Cu")
		(net "UART_RI_RP5_L_N")
	)
	(segment
		(start 11.216894 -393.497816)
		(end 8.748522 -391.029444)
		(width 0.127)
		(layer "In5.Cu")
		(net "UART_RI_RP5_L_N")
	)
	(segment
		(start 10.514838 -382.01473)
		(end 13.744702 -378.784866)
		(width 0.127)
		(layer "In5.Cu")
		(net "UART_RI_RP6_L_N")
	)
	(segment
		(start 5.70484 -328.938128)
		(end 5.70484 -328.308462)
		(width 0.127)
		(layer "In5.Cu")
		(net "UART_RI_RP6_L_N")
	)
	(segment
		(start 20.189952 -399.470372)
		(end 10.514838 -389.795258)
		(width 0.127)
		(layer "In5.Cu")
		(net "UART_RI_RP6_L_N")
	)
	(segment
		(start 20.189952 -410.181044)
		(end 20.189952 -399.470372)
		(width 0.127)
		(layer "In5.Cu")
		(net "UART_RI_RP6_L_N")
	)
	(segment
		(start 8.31469 -522.084808)
		(end 8.55218 -521.847318)
		(width 0.127)
		(layer "In5.Cu")
		(net "UART_RI_RP6_L_N")
	)
	(segment
		(start 13.744702 -333.00416)
		(end 11.315954 -330.575412)
		(width 0.127)
		(layer "In5.Cu")
		(net "UART_RI_RP6_L_N")
	)
	(segment
		(start 18.925286 -465.708238)
		(end 18.925286 -411.44571)
		(width 0.127)
		(layer "In5.Cu")
		(net "UART_RI_RP6_L_N")
	)
	(segment
		(start 8.31469 -523.661894)
		(end 8.31469 -522.084808)
		(width 0.127)
		(layer "In5.Cu")
		(net "UART_RI_RP6_L_N")
	)
	(segment
		(start 6.348984 -329.582272)
		(end 5.70484 -328.938128)
		(width 0.127)
		(layer "In5.Cu")
		(net "UART_RI_RP6_L_N")
	)
	(segment
		(start 10.514838 -389.795258)
		(end 10.514838 -382.01473)
		(width 0.127)
		(layer "In5.Cu")
		(net "UART_RI_RP6_L_N")
	)
	(segment
		(start 5.70484 -328.308462)
		(end 6.343396 -327.669906)
		(width 0.127)
		(layer "In5.Cu")
		(net "UART_RI_RP6_L_N")
	)
	(segment
		(start 11.315954 -330.575412)
		(end 8.102854 -330.575412)
		(width 0.127)
		(layer "In5.Cu")
		(net "UART_RI_RP6_L_N")
	)
	(segment
		(start 13.744702 -378.784866)
		(end 13.744702 -333.00416)
		(width 0.127)
		(layer "In5.Cu")
		(net "UART_RI_RP6_L_N")
	)
	(segment
		(start 8.55218 -513.04698)
		(end 24.043132 -497.556028)
		(width 0.127)
		(layer "In5.Cu")
		(net "UART_RI_RP6_L_N")
	)
	(segment
		(start 24.043132 -497.556028)
		(end 24.043132 -470.826084)
		(width 0.127)
		(layer "In5.Cu")
		(net "UART_RI_RP6_L_N")
	)
	(segment
		(start 24.043132 -470.826084)
		(end 18.925286 -465.708238)
		(width 0.127)
		(layer "In5.Cu")
		(net "UART_RI_RP6_L_N")
	)
	(segment
		(start 6.343396 -327.669906)
		(end 8.449818 -327.669906)
		(width 0.127)
		(layer "In5.Cu")
		(net "UART_RI_RP6_L_N")
	)
	(segment
		(start 8.102854 -330.575412)
		(end 7.109714 -329.582272)
		(width 0.127)
		(layer "In5.Cu")
		(net "UART_RI_RP6_L_N")
	)
	(segment
		(start 18.925286 -411.44571)
		(end 20.189952 -410.181044)
		(width 0.127)
		(layer "In5.Cu")
		(net "UART_RI_RP6_L_N")
	)
	(segment
		(start 8.55218 -521.847318)
		(end 8.55218 -513.04698)
		(width 0.127)
		(layer "In5.Cu")
		(net "UART_RI_RP6_L_N")
	)
	(segment
		(start 7.109714 -329.582272)
		(end 6.348984 -329.582272)
		(width 0.127)
		(layer "In5.Cu")
		(net "UART_RI_RP6_L_N")
	)
	(segment
		(start 27.699716 -14.7955)
		(end 26.892758 -14.7955)
		(width 0.1524)
		(layer "F.Cu")
		(net "PSU1_CSAHRE")
	)
	(segment
		(start 28.4353 -14.750034)
		(end 28.389834 -14.7955)
		(width 0.1524)
		(layer "F.Cu")
		(net "PSU1_CSAHRE")
	)
	(segment
		(start 30.45968 -14.750034)
		(end 28.4353 -14.750034)
		(width 0.1524)
		(layer "F.Cu")
		(net "PSU1_CSAHRE")
	)
	(segment
		(start 28.389834 -14.7955)
		(end 27.699716 -14.7955)
		(width 0.1524)
		(layer "F.Cu")
		(net "PSU1_CSAHRE")
	)
	(via
		(at 27.699716 -14.7955)
		(size 0.508)
		(drill 0.254)
		(layers "F.Cu" "B.Cu")
		(net "PSU1_CSAHRE")
	)
	(segment
		(start 27.76601 -191.548004)
		(end 26.58618 -190.368174)
		(width 0.1524)
		(layer "F.Cu")
		(net "PSU3_CSAHRE")
	)
	(segment
		(start 30.443932 -191.550036)
		(end 30.4419 -191.548004)
		(width 0.1524)
		(layer "F.Cu")
		(net "PSU3_CSAHRE")
	)
	(segment
		(start 30.4419 -191.548004)
		(end 27.76601 -191.548004)
		(width 0.1524)
		(layer "F.Cu")
		(net "PSU3_CSAHRE")
	)
	(segment
		(start 30.45968 -191.550036)
		(end 30.443932 -191.550036)
		(width 0.1524)
		(layer "F.Cu")
		(net "PSU3_CSAHRE")
	)
	(segment
		(start 29.442664 -456.748896)
		(end 28.14955 -456.748896)
		(width 0.1524)
		(layer "F.Cu")
		(net "PSU6_CSAHRE")
	)
	(segment
		(start 27.132534 -457.766928)
		(end 27.132534 -456.748896)
		(width 0.1524)
		(layer "F.Cu")
		(net "PSU6_CSAHRE")
	)
	(segment
		(start 27.132026 -457.76642)
		(end 27.132534 -457.766928)
		(width 0.1524)
		(layer "F.Cu")
		(net "PSU6_CSAHRE")
	)
	(segment
		(start 30.45968 -456.749912)
		(end 29.44368 -456.749912)
		(width 0.1524)
		(layer "F.Cu")
		(net "PSU6_CSAHRE")
	)
	(segment
		(start 29.44368 -456.749912)
		(end 29.442664 -456.748896)
		(width 0.1524)
		(layer "F.Cu")
		(net "PSU6_CSAHRE")
	)
	(segment
		(start 28.14955 -456.748896)
		(end 27.132026 -457.76642)
		(width 0.1524)
		(layer "F.Cu")
		(net "PSU6_CSAHRE")
	)
	(via
		(at 27.132026 -457.76642)
		(size 0.508)
		(drill 0.254)
		(layers "F.Cu" "B.Cu")
		(net "PSU6_CSAHRE")
	)
	(segment
		(start 29.185616 -279.94991)
		(end 30.45968 -279.94991)
		(width 0.1524)
		(layer "F.Cu")
		(net "PSU4_CSAHRE")
	)
	(segment
		(start 27.69362 -280.04389)
		(end 29.091636 -280.04389)
		(width 0.1524)
		(layer "F.Cu")
		(net "PSU4_CSAHRE")
	)
	(segment
		(start 29.091636 -280.04389)
		(end 29.185616 -279.94991)
		(width 0.1524)
		(layer "F.Cu")
		(net "PSU4_CSAHRE")
	)
	(segment
		(start 30.443932 -103.149908)
		(end 30.45968 -103.149908)
		(width 0.1524)
		(layer "F.Cu")
		(net "PSU2_CSAHRE")
	)
	(segment
		(start 28.983432 -101.689408)
		(end 30.443932 -103.149908)
		(width 0.1524)
		(layer "F.Cu")
		(net "PSU2_CSAHRE")
	)
	(segment
		(start 26.401776 -101.689408)
		(end 28.983432 -101.689408)
		(width 0.1524)
		(layer "F.Cu")
		(net "PSU2_CSAHRE")
	)
	(segment
		(start 26.204926 -369.095274)
		(end 27.057604 -369.095274)
		(width 0.1524)
		(layer "F.Cu")
		(net "PSU5_CSAHRE")
	)
	(segment
		(start 27.179524 -368.973354)
		(end 27.804364 -368.348514)
		(width 0.1524)
		(layer "F.Cu")
		(net "PSU5_CSAHRE")
	)
	(segment
		(start 27.057604 -369.095274)
		(end 27.179524 -368.973354)
		(width 0.1524)
		(layer "F.Cu")
		(net "PSU5_CSAHRE")
	)
	(segment
		(start 27.804364 -368.348514)
		(end 30.442408 -368.348514)
		(width 0.1524)
		(layer "F.Cu")
		(net "PSU5_CSAHRE")
	)
	(segment
		(start 30.443932 -368.350038)
		(end 30.45968 -368.350038)
		(width 0.1524)
		(layer "F.Cu")
		(net "PSU5_CSAHRE")
	)
	(segment
		(start 30.442408 -368.348514)
		(end 30.443932 -368.350038)
		(width 0.1524)
		(layer "F.Cu")
		(net "PSU5_CSAHRE")
	)
	(via
		(at 27.179524 -368.973354)
		(size 0.508)
		(drill 0.254)
		(layers "F.Cu" "B.Cu")
		(net "PSU5_CSAHRE")
	)
	(segment
		(start 39.512494 -463.572098)
		(end 40.40505 -463.572098)
		(width 0.4572)
		(layer "F.Cu")
		(net "PSU6_REMOTE_R2_P")
	)
	(segment
		(start 72.532748 -473.59951)
		(end 71.113904 -473.59951)
		(width 0.4572)
		(layer "F.Cu")
		(net "PSU6_REMOTE_R2_P")
	)
	(via
		(at 40.40505 -463.572098)
		(size 0.508)
		(drill 0.254)
		(layers "F.Cu" "B.Cu")
		(net "PSU6_REMOTE_R2_P")
	)
	(via
		(at 71.113904 -473.59951)
		(size 0.508)
		(drill 0.254)
		(layers "F.Cu" "B.Cu")
		(net "PSU6_REMOTE_R2_P")
	)
	(segment
		(start 71.113904 -473.59951)
		(end 70.788022 -473.273628)
		(width 0.4572)
		(layer "In5.Cu")
		(net "PSU6_REMOTE_R2_P")
	)
	(segment
		(start 58.853324 -467.00821)
		(end 47.170594 -467.00821)
		(width 0.4572)
		(layer "In5.Cu")
		(net "PSU6_REMOTE_R2_P")
	)
	(segment
		(start 47.170594 -467.00821)
		(end 43.734482 -463.572098)
		(width 0.4572)
		(layer "In5.Cu")
		(net "PSU6_REMOTE_R2_P")
	)
	(segment
		(start 70.788022 -473.273628)
		(end 65.118742 -473.273628)
		(width 0.4572)
		(layer "In5.Cu")
		(net "PSU6_REMOTE_R2_P")
	)
	(segment
		(start 65.118742 -473.273628)
		(end 58.853324 -467.00821)
		(width 0.4572)
		(layer "In5.Cu")
		(net "PSU6_REMOTE_R2_P")
	)
	(segment
		(start 43.734482 -463.572098)
		(end 40.40505 -463.572098)
		(width 0.4572)
		(layer "In5.Cu")
		(net "PSU6_REMOTE_R2_P")
	)
	(segment
		(start 72.553576 -472.101672)
		(end 71.18096 -472.101672)
		(width 0.4572)
		(layer "F.Cu")
		(net "PSU6_REMOTE_R2_N")
	)
	(segment
		(start 27.640026 -461.029812)
		(end 27.640026 -460.277972)
		(width 0.4572)
		(layer "F.Cu")
		(net "PSU6_REMOTE_R2_N")
	)
	(via
		(at 27.640026 -460.277972)
		(size 0.508)
		(drill 0.254)
		(layers "F.Cu" "B.Cu")
		(net "PSU6_REMOTE_R2_N")
	)
	(via
		(at 71.18096 -472.101672)
		(size 0.508)
		(drill 0.254)
		(layers "F.Cu" "B.Cu")
		(net "PSU6_REMOTE_R2_N")
	)
	(segment
		(start 28.528518 -460.556864)
		(end 28.249626 -460.277972)
		(width 0.4572)
		(layer "In5.Cu")
		(net "PSU6_REMOTE_R2_N")
	)
	(segment
		(start 70.87616 -472.406472)
		(end 65.478152 -472.406472)
		(width 0.4572)
		(layer "In5.Cu")
		(net "PSU6_REMOTE_R2_N")
	)
	(segment
		(start 28.249626 -460.277972)
		(end 27.640026 -460.277972)
		(width 0.4572)
		(layer "In5.Cu")
		(net "PSU6_REMOTE_R2_N")
	)
	(segment
		(start 65.478152 -472.406472)
		(end 59.212734 -466.141054)
		(width 0.4572)
		(layer "In5.Cu")
		(net "PSU6_REMOTE_R2_N")
	)
	(segment
		(start 71.18096 -472.101672)
		(end 70.87616 -472.406472)
		(width 0.4572)
		(layer "In5.Cu")
		(net "PSU6_REMOTE_R2_N")
	)
	(segment
		(start 42.436034 -460.556864)
		(end 28.528518 -460.556864)
		(width 0.4572)
		(layer "In5.Cu")
		(net "PSU6_REMOTE_R2_N")
	)
	(segment
		(start 48.020224 -466.141054)
		(end 42.436034 -460.556864)
		(width 0.4572)
		(layer "In5.Cu")
		(net "PSU6_REMOTE_R2_N")
	)
	(segment
		(start 59.212734 -466.141054)
		(end 48.020224 -466.141054)
		(width 0.4572)
		(layer "In5.Cu")
		(net "PSU6_REMOTE_R2_N")
	)
	(segment
		(start 27.577796 -372.632478)
		(end 27.577796 -371.700806)
		(width 0.4572)
		(layer "F.Cu")
		(net "PSU5_REMOTE_R2_N")
	)
	(segment
		(start 77.593444 -384.526282)
		(end 76.640436 -384.526282)
		(width 0.4572)
		(layer "F.Cu")
		(net "PSU5_REMOTE_R2_N")
	)
	(via
		(at 76.640436 -384.526282)
		(size 0.508)
		(drill 0.254)
		(layers "F.Cu" "B.Cu")
		(net "PSU5_REMOTE_R2_N")
	)
	(via
		(at 27.577796 -371.700806)
		(size 0.508)
		(drill 0.254)
		(layers "F.Cu" "B.Cu")
		(net "PSU5_REMOTE_R2_N")
	)
	(segment
		(start 38.619176 -374.378728)
		(end 38.272466 -374.725438)
		(width 0.4572)
		(layer "In5.Cu")
		(net "PSU5_REMOTE_R2_N")
	)
	(segment
		(start 28.965652 -372.102888)
		(end 27.577796 -371.700806)
		(width 0.4572)
		(layer "In5.Cu")
		(net "PSU5_REMOTE_R2_N")
	)
	(segment
		(start 75.690984 -385.475734)
		(end 63.145162 -385.475734)
		(width 0.4572)
		(layer "In5.Cu")
		(net "PSU5_REMOTE_R2_N")
	)
	(segment
		(start 38.272466 -374.725438)
		(end 34.612834 -374.725438)
		(width 0.4572)
		(layer "In5.Cu")
		(net "PSU5_REMOTE_R2_N")
	)
	(segment
		(start 42.217594 -374.378728)
		(end 38.619176 -374.378728)
		(width 0.4572)
		(layer "In5.Cu")
		(net "PSU5_REMOTE_R2_N")
	)
	(segment
		(start 63.145162 -385.475734)
		(end 56.379364 -378.709936)
		(width 0.4572)
		(layer "In5.Cu")
		(net "PSU5_REMOTE_R2_N")
	)
	(segment
		(start 46.548802 -378.709936)
		(end 42.217594 -374.378728)
		(width 0.4572)
		(layer "In5.Cu")
		(net "PSU5_REMOTE_R2_N")
	)
	(segment
		(start 31.990284 -372.102888)
		(end 28.965652 -372.102888)
		(width 0.4572)
		(layer "In5.Cu")
		(net "PSU5_REMOTE_R2_N")
	)
	(segment
		(start 34.612834 -374.725438)
		(end 31.990284 -372.102888)
		(width 0.4572)
		(layer "In5.Cu")
		(net "PSU5_REMOTE_R2_N")
	)
	(segment
		(start 56.379364 -378.709936)
		(end 46.548802 -378.709936)
		(width 0.4572)
		(layer "In5.Cu")
		(net "PSU5_REMOTE_R2_N")
	)
	(segment
		(start 76.640436 -384.526282)
		(end 75.690984 -385.475734)
		(width 0.4572)
		(layer "In5.Cu")
		(net "PSU5_REMOTE_R2_N")
	)
	(segment
		(start 77.662024 -387.197854)
		(end 76.775818 -387.197854)
		(width 0.4572)
		(layer "F.Cu")
		(net "PSU5_REMOTE_R2_P")
	)
	(segment
		(start 39.577264 -375.189496)
		(end 40.440864 -375.189496)
		(width 0.4572)
		(layer "F.Cu")
		(net "PSU5_REMOTE_R2_P")
	)
	(via
		(at 40.440864 -375.189496)
		(size 0.508)
		(drill 0.254)
		(layers "F.Cu" "B.Cu")
		(net "PSU5_REMOTE_R2_P")
	)
	(via
		(at 76.775818 -387.197854)
		(size 0.508)
		(drill 0.254)
		(layers "F.Cu" "B.Cu")
		(net "PSU5_REMOTE_R2_P")
	)
	(segment
		(start 75.864212 -386.286248)
		(end 76.775818 -387.197854)
		(width 0.4572)
		(layer "In5.Cu")
		(net "PSU5_REMOTE_R2_P")
	)
	(segment
		(start 62.80912 -386.286248)
		(end 75.864212 -386.286248)
		(width 0.4572)
		(layer "In5.Cu")
		(net "PSU5_REMOTE_R2_P")
	)
	(segment
		(start 56.164226 -379.641354)
		(end 62.80912 -386.286248)
		(width 0.4572)
		(layer "In5.Cu")
		(net "PSU5_REMOTE_R2_P")
	)
	(segment
		(start 46.177962 -379.641354)
		(end 56.164226 -379.641354)
		(width 0.4572)
		(layer "In5.Cu")
		(net "PSU5_REMOTE_R2_P")
	)
	(segment
		(start 41.726104 -375.189496)
		(end 46.177962 -379.641354)
		(width 0.4572)
		(layer "In5.Cu")
		(net "PSU5_REMOTE_R2_P")
	)
	(segment
		(start 40.440864 -375.189496)
		(end 41.726104 -375.189496)
		(width 0.4572)
		(layer "In5.Cu")
		(net "PSU5_REMOTE_R2_P")
	)
	(segment
		(start 39.436802 -286.77743)
		(end 40.247824 -286.77743)
		(width 0.4572)
		(layer "F.Cu")
		(net "PSU4_REMOTE_R2_P")
	)
	(segment
		(start 80.546956 -297.892216)
		(end 79.425292 -297.892216)
		(width 0.4572)
		(layer "F.Cu")
		(net "PSU4_REMOTE_R2_P")
	)
	(via
		(at 79.425292 -297.892216)
		(size 0.508)
		(drill 0.254)
		(layers "F.Cu" "B.Cu")
		(net "PSU4_REMOTE_R2_P")
	)
	(via
		(at 40.247824 -286.77743)
		(size 0.508)
		(drill 0.254)
		(layers "F.Cu" "B.Cu")
		(net "PSU4_REMOTE_R2_P")
	)
	(segment
		(start 60.010294 -296.921174)
		(end 78.45425 -296.921174)
		(width 0.4572)
		(layer "In2.Cu")
		(net "PSU4_REMOTE_R2_P")
	)
	(segment
		(start 40.247824 -286.77743)
		(end 41.414192 -287.943798)
		(width 0.4572)
		(layer "In2.Cu")
		(net "PSU4_REMOTE_R2_P")
	)
	(segment
		(start 51.032918 -287.943798)
		(end 60.010294 -296.921174)
		(width 0.4572)
		(layer "In2.Cu")
		(net "PSU4_REMOTE_R2_P")
	)
	(segment
		(start 41.414192 -287.943798)
		(end 51.032918 -287.943798)
		(width 0.4572)
		(layer "In2.Cu")
		(net "PSU4_REMOTE_R2_P")
	)
	(segment
		(start 78.45425 -296.921174)
		(end 79.425292 -297.892216)
		(width 0.4572)
		(layer "In2.Cu")
		(net "PSU4_REMOTE_R2_P")
	)
	(segment
		(start 80.532732 -295.215564)
		(end 79.381858 -295.215564)
		(width 0.4572)
		(layer "F.Cu")
		(net "PSU4_REMOTE_R2_N")
	)
	(segment
		(start 27.774392 -284.22981)
		(end 28.575762 -283.42844)
		(width 0.4572)
		(layer "F.Cu")
		(net "PSU4_REMOTE_R2_N")
	)
	(segment
		(start 27.640026 -284.22981)
		(end 27.774392 -284.22981)
		(width 0.4572)
		(layer "F.Cu")
		(net "PSU4_REMOTE_R2_N")
	)
	(via
		(at 28.575762 -283.42844)
		(size 0.508)
		(drill 0.254)
		(layers "F.Cu" "B.Cu")
		(net "PSU4_REMOTE_R2_N")
	)
	(via
		(at 79.381858 -295.215564)
		(size 0.508)
		(drill 0.254)
		(layers "F.Cu" "B.Cu")
		(net "PSU4_REMOTE_R2_N")
	)
	(segment
		(start 37.686996 -286.24911)
		(end 38.142164 -285.793942)
		(width 0.4572)
		(layer "In2.Cu")
		(net "PSU4_REMOTE_R2_N")
	)
	(segment
		(start 51.363372 -286.883348)
		(end 60.41771 -295.937686)
		(width 0.4572)
		(layer "In2.Cu")
		(net "PSU4_REMOTE_R2_N")
	)
	(segment
		(start 28.86075 -283.713428)
		(end 32.01289 -283.713428)
		(width 0.4572)
		(layer "In2.Cu")
		(net "PSU4_REMOTE_R2_N")
	)
	(segment
		(start 34.548572 -286.24911)
		(end 37.686996 -286.24911)
		(width 0.4572)
		(layer "In2.Cu")
		(net "PSU4_REMOTE_R2_N")
	)
	(segment
		(start 32.01289 -283.713428)
		(end 34.548572 -286.24911)
		(width 0.4572)
		(layer "In2.Cu")
		(net "PSU4_REMOTE_R2_N")
	)
	(segment
		(start 60.41771 -295.937686)
		(end 78.659736 -295.937686)
		(width 0.4572)
		(layer "In2.Cu")
		(net "PSU4_REMOTE_R2_N")
	)
	(segment
		(start 28.575762 -283.42844)
		(end 28.86075 -283.713428)
		(width 0.4572)
		(layer "In2.Cu")
		(net "PSU4_REMOTE_R2_N")
	)
	(segment
		(start 42.145966 -286.883348)
		(end 51.363372 -286.883348)
		(width 0.4572)
		(layer "In2.Cu")
		(net "PSU4_REMOTE_R2_N")
	)
	(segment
		(start 41.05656 -285.793942)
		(end 42.145966 -286.883348)
		(width 0.4572)
		(layer "In2.Cu")
		(net "PSU4_REMOTE_R2_N")
	)
	(segment
		(start 38.142164 -285.793942)
		(end 41.05656 -285.793942)
		(width 0.4572)
		(layer "In2.Cu")
		(net "PSU4_REMOTE_R2_N")
	)
	(segment
		(start 78.659736 -295.937686)
		(end 79.381858 -295.215564)
		(width 0.4572)
		(layer "In2.Cu")
		(net "PSU4_REMOTE_R2_N")
	)
	(segment
		(start 64.944498 -206.296768)
		(end 66.335402 -206.296768)
		(width 0.4572)
		(layer "F.Cu")
		(net "PSU3_REMOTE_R2_N")
	)
	(segment
		(start 27.334718 -195.834254)
		(end 28.183078 -195.834254)
		(width 0.4572)
		(layer "F.Cu")
		(net "PSU3_REMOTE_R2_N")
	)
	(segment
		(start 66.335402 -206.296768)
		(end 66.34099 -206.29118)
		(width 0.4572)
		(layer "F.Cu")
		(net "PSU3_REMOTE_R2_N")
	)
	(segment
		(start 28.183078 -195.834254)
		(end 28.660344 -195.356988)
		(width 0.4572)
		(layer "F.Cu")
		(net "PSU3_REMOTE_R2_N")
	)
	(via
		(at 64.944498 -206.296768)
		(size 0.508)
		(drill 0.254)
		(layers "F.Cu" "B.Cu")
		(net "PSU3_REMOTE_R2_N")
	)
	(via
		(at 28.660344 -195.356988)
		(size 0.508)
		(drill 0.254)
		(layers "F.Cu" "B.Cu")
		(net "PSU3_REMOTE_R2_N")
	)
	(segment
		(start 34.941256 -197.881494)
		(end 37.968682 -197.881494)
		(width 0.4572)
		(layer "In5.Cu")
		(net "PSU3_REMOTE_R2_N")
	)
	(segment
		(start 28.660344 -195.356988)
		(end 32.41675 -195.356988)
		(width 0.4572)
		(layer "In5.Cu")
		(net "PSU3_REMOTE_R2_N")
	)
	(segment
		(start 64.222122 -207.019144)
		(end 64.944498 -206.296768)
		(width 0.4572)
		(layer "In5.Cu")
		(net "PSU3_REMOTE_R2_N")
	)
	(segment
		(start 38.336982 -197.513194)
		(end 45.033946 -197.513194)
		(width 0.4572)
		(layer "In5.Cu")
		(net "PSU3_REMOTE_R2_N")
	)
	(segment
		(start 60.037218 -207.019144)
		(end 64.222122 -207.019144)
		(width 0.4572)
		(layer "In5.Cu")
		(net "PSU3_REMOTE_R2_N")
	)
	(segment
		(start 54.801008 -201.782934)
		(end 60.037218 -207.019144)
		(width 0.4572)
		(layer "In5.Cu")
		(net "PSU3_REMOTE_R2_N")
	)
	(segment
		(start 49.303686 -201.782934)
		(end 54.801008 -201.782934)
		(width 0.4572)
		(layer "In5.Cu")
		(net "PSU3_REMOTE_R2_N")
	)
	(segment
		(start 45.033946 -197.513194)
		(end 49.303686 -201.782934)
		(width 0.4572)
		(layer "In5.Cu")
		(net "PSU3_REMOTE_R2_N")
	)
	(segment
		(start 32.41675 -195.356988)
		(end 34.941256 -197.881494)
		(width 0.4572)
		(layer "In5.Cu")
		(net "PSU3_REMOTE_R2_N")
	)
	(segment
		(start 37.968682 -197.881494)
		(end 38.336982 -197.513194)
		(width 0.4572)
		(layer "In5.Cu")
		(net "PSU3_REMOTE_R2_N")
	)
	(segment
		(start 66.294762 -209.201004)
		(end 66.30035 -209.195416)
		(width 0.4572)
		(layer "F.Cu")
		(net "PSU3_REMOTE_R2_P")
	)
	(segment
		(start 39.460424 -198.369428)
		(end 40.374824 -198.369428)
		(width 0.4572)
		(layer "F.Cu")
		(net "PSU3_REMOTE_R2_P")
	)
	(segment
		(start 64.982598 -209.201004)
		(end 66.294762 -209.201004)
		(width 0.4572)
		(layer "F.Cu")
		(net "PSU3_REMOTE_R2_P")
	)
	(via
		(at 40.374824 -198.369428)
		(size 0.508)
		(drill 0.254)
		(layers "F.Cu" "B.Cu")
		(net "PSU3_REMOTE_R2_P")
	)
	(via
		(at 64.982598 -209.201004)
		(size 0.508)
		(drill 0.254)
		(layers "F.Cu" "B.Cu")
		(net "PSU3_REMOTE_R2_P")
	)
	(segment
		(start 64.232282 -208.450688)
		(end 60.25769 -208.450688)
		(width 0.4572)
		(layer "In5.Cu")
		(net "PSU3_REMOTE_R2_P")
	)
	(segment
		(start 48.825912 -202.728576)
		(end 44.466764 -198.369428)
		(width 0.4572)
		(layer "In5.Cu")
		(net "PSU3_REMOTE_R2_P")
	)
	(segment
		(start 44.466764 -198.369428)
		(end 40.374824 -198.369428)
		(width 0.4572)
		(layer "In5.Cu")
		(net "PSU3_REMOTE_R2_P")
	)
	(segment
		(start 54.535578 -202.728576)
		(end 48.825912 -202.728576)
		(width 0.4572)
		(layer "In5.Cu")
		(net "PSU3_REMOTE_R2_P")
	)
	(segment
		(start 60.25769 -208.450688)
		(end 54.535578 -202.728576)
		(width 0.4572)
		(layer "In5.Cu")
		(net "PSU3_REMOTE_R2_P")
	)
	(segment
		(start 64.982598 -209.201004)
		(end 64.232282 -208.450688)
		(width 0.4572)
		(layer "In5.Cu")
		(net "PSU3_REMOTE_R2_P")
	)
	(segment
		(start 67.497198 -120.31472)
		(end 68.29679 -120.31472)
		(width 0.4572)
		(layer "F.Cu")
		(net "PSU2_REMOTE_R2_P")
	)
	(segment
		(start 39.458392 -109.974126)
		(end 40.336978 -109.974126)
		(width 0.4572)
		(layer "F.Cu")
		(net "PSU2_REMOTE_R2_P")
	)
	(segment
		(start 68.29679 -120.31472)
		(end 68.297552 -120.313958)
		(width 0.4572)
		(layer "F.Cu")
		(net "PSU2_REMOTE_R2_P")
	)
	(via
		(at 40.336978 -109.974126)
		(size 0.508)
		(drill 0.254)
		(layers "F.Cu" "B.Cu")
		(net "PSU2_REMOTE_R2_P")
	)
	(via
		(at 67.497198 -120.31472)
		(size 0.508)
		(drill 0.254)
		(layers "F.Cu" "B.Cu")
		(net "PSU2_REMOTE_R2_P")
	)
	(segment
		(start 65.311274 -119.46001)
		(end 66.642488 -119.46001)
		(width 0.508)
		(layer "In5.Cu")
		(net "PSU2_REMOTE_R2_P")
	)
	(segment
		(start 66.642488 -119.46001)
		(end 67.497198 -120.31472)
		(width 0.508)
		(layer "In5.Cu")
		(net "PSU2_REMOTE_R2_P")
	)
	(segment
		(start 55.82539 -109.974126)
		(end 65.311274 -119.46001)
		(width 0.508)
		(layer "In5.Cu")
		(net "PSU2_REMOTE_R2_P")
	)
	(segment
		(start 40.336978 -109.974126)
		(end 55.82539 -109.974126)
		(width 0.508)
		(layer "In5.Cu")
		(net "PSU2_REMOTE_R2_P")
	)
	(segment
		(start 27.347672 -107.42041)
		(end 27.347672 -107.430316)
		(width 0.4572)
		(layer "F.Cu")
		(net "PSU2_REMOTE_R2_N")
	)
	(segment
		(start 68.315332 -117.627908)
		(end 68.316094 -117.627146)
		(width 0.4572)
		(layer "F.Cu")
		(net "PSU2_REMOTE_R2_N")
	)
	(segment
		(start 28.198318 -106.569764)
		(end 27.347672 -107.42041)
		(width 0.4572)
		(layer "F.Cu")
		(net "PSU2_REMOTE_R2_N")
	)
	(segment
		(start 67.493388 -117.627908)
		(end 68.315332 -117.627908)
		(width 0.4572)
		(layer "F.Cu")
		(net "PSU2_REMOTE_R2_N")
	)
	(via
		(at 67.493388 -117.627908)
		(size 0.508)
		(drill 0.254)
		(layers "F.Cu" "B.Cu")
		(net "PSU2_REMOTE_R2_N")
	)
	(via
		(at 28.198318 -106.569764)
		(size 0.508)
		(drill 0.254)
		(layers "F.Cu" "B.Cu")
		(net "PSU2_REMOTE_R2_N")
	)
	(segment
		(start 28.198318 -107.87126)
		(end 29.846524 -109.519466)
		(width 0.508)
		(layer "In5.Cu")
		(net "PSU2_REMOTE_R2_N")
	)
	(segment
		(start 66.69405 -118.427246)
		(end 67.493388 -117.627908)
		(width 0.508)
		(layer "In5.Cu")
		(net "PSU2_REMOTE_R2_N")
	)
	(segment
		(start 28.198318 -106.569764)
		(end 28.198318 -107.87126)
		(width 0.508)
		(layer "In5.Cu")
		(net "PSU2_REMOTE_R2_N")
	)
	(segment
		(start 29.846524 -109.519466)
		(end 37.627306 -109.519466)
		(width 0.508)
		(layer "In5.Cu")
		(net "PSU2_REMOTE_R2_N")
	)
	(segment
		(start 65.772284 -118.427246)
		(end 66.69405 -118.427246)
		(width 0.508)
		(layer "In5.Cu")
		(net "PSU2_REMOTE_R2_N")
	)
	(segment
		(start 56.263032 -108.917994)
		(end 65.772284 -118.427246)
		(width 0.508)
		(layer "In5.Cu")
		(net "PSU2_REMOTE_R2_N")
	)
	(segment
		(start 37.627306 -109.519466)
		(end 38.228778 -108.917994)
		(width 0.508)
		(layer "In5.Cu")
		(net "PSU2_REMOTE_R2_N")
	)
	(segment
		(start 38.228778 -108.917994)
		(end 56.263032 -108.917994)
		(width 0.508)
		(layer "In5.Cu")
		(net "PSU2_REMOTE_R2_N")
	)
	(segment
		(start 66.491866 -29.351986)
		(end 65.30975 -29.351986)
		(width 0.4572)
		(layer "F.Cu")
		(net "PSU1_REMOTE_R2_N")
	)
	(segment
		(start 27.244802 -19.06397)
		(end 27.244802 -18.349976)
		(width 0.1524)
		(layer "F.Cu")
		(net "PSU1_REMOTE_R2_N")
	)
	(via
		(at 27.244802 -18.349976)
		(size 0.508)
		(drill 0.254)
		(layers "F.Cu" "B.Cu")
		(net "PSU1_REMOTE_R2_N")
	)
	(via
		(at 65.30975 -29.351986)
		(size 0.508)
		(drill 0.254)
		(layers "F.Cu" "B.Cu")
		(net "PSU1_REMOTE_R2_N")
	)
	(segment
		(start 28.78963 -18.349976)
		(end 27.244802 -18.349976)
		(width 0.4572)
		(layer "In5.Cu")
		(net "PSU1_REMOTE_R2_N")
	)
	(segment
		(start 29.044392 -18.604738)
		(end 28.78963 -18.349976)
		(width 0.4572)
		(layer "In5.Cu")
		(net "PSU1_REMOTE_R2_N")
	)
	(segment
		(start 32.470344 -18.604738)
		(end 29.044392 -18.604738)
		(width 0.4572)
		(layer "In5.Cu")
		(net "PSU1_REMOTE_R2_N")
	)
	(segment
		(start 50.78857 -20.76704)
		(end 39.637716 -20.76704)
		(width 0.4572)
		(layer "In5.Cu")
		(net "PSU1_REMOTE_R2_N")
	)
	(segment
		(start 34.914332 -21.048726)
		(end 32.470344 -18.604738)
		(width 0.4572)
		(layer "In5.Cu")
		(net "PSU1_REMOTE_R2_N")
	)
	(segment
		(start 39.35603 -21.048726)
		(end 34.914332 -21.048726)
		(width 0.4572)
		(layer "In5.Cu")
		(net "PSU1_REMOTE_R2_N")
	)
	(segment
		(start 64.282066 -30.37967)
		(end 60.4012 -30.37967)
		(width 0.4572)
		(layer "In5.Cu")
		(net "PSU1_REMOTE_R2_N")
	)
	(segment
		(start 39.637716 -20.76704)
		(end 39.35603 -21.048726)
		(width 0.4572)
		(layer "In5.Cu")
		(net "PSU1_REMOTE_R2_N")
	)
	(segment
		(start 65.30975 -29.351986)
		(end 64.282066 -30.37967)
		(width 0.4572)
		(layer "In5.Cu")
		(net "PSU1_REMOTE_R2_N")
	)
	(segment
		(start 60.4012 -30.37967)
		(end 50.78857 -20.76704)
		(width 0.4572)
		(layer "In5.Cu")
		(net "PSU1_REMOTE_R2_N")
	)
	(segment
		(start 65.767458 -32.582104)
		(end 65.264538 -32.582104)
		(width 0.4572)
		(layer "F.Cu")
		(net "PSU1_REMOTE_R2_P")
	)
	(segment
		(start 66.42989 -32.569912)
		(end 65.77965 -32.569912)
		(width 0.4572)
		(layer "F.Cu")
		(net "PSU1_REMOTE_R2_P")
	)
	(segment
		(start 65.77965 -32.569912)
		(end 65.767458 -32.582104)
		(width 0.4572)
		(layer "F.Cu")
		(net "PSU1_REMOTE_R2_P")
	)
	(segment
		(start 39.462964 -21.594318)
		(end 40.360854 -21.594318)
		(width 0.4572)
		(layer "F.Cu")
		(net "PSU1_REMOTE_R2_P")
	)
	(via
		(at 40.360854 -21.594318)
		(size 0.508)
		(drill 0.254)
		(layers "F.Cu" "B.Cu")
		(net "PSU1_REMOTE_R2_P")
	)
	(via
		(at 65.264538 -32.582104)
		(size 0.508)
		(drill 0.254)
		(layers "F.Cu" "B.Cu")
		(net "PSU1_REMOTE_R2_P")
	)
	(segment
		(start 60.0583 -31.206948)
		(end 63.889382 -31.206948)
		(width 0.4572)
		(layer "In5.Cu")
		(net "PSU1_REMOTE_R2_P")
	)
	(segment
		(start 50.44567 -21.594318)
		(end 60.0583 -31.206948)
		(width 0.4572)
		(layer "In5.Cu")
		(net "PSU1_REMOTE_R2_P")
	)
	(segment
		(start 63.889382 -31.206948)
		(end 65.264538 -32.582104)
		(width 0.4572)
		(layer "In5.Cu")
		(net "PSU1_REMOTE_R2_P")
	)
	(segment
		(start 40.360854 -21.594318)
		(end 50.44567 -21.594318)
		(width 0.4572)
		(layer "In5.Cu")
		(net "PSU1_REMOTE_R2_P")
	)
	(segment
		(start 27.640026 -462.630012)
		(end 27.640026 -463.41538)
		(width 0.4572)
		(layer "F.Cu")
		(net "PSU6_REMOTE_R_N")
	)
	(segment
		(start 44.564046 -253.399544)
		(end 44.837858 -253.125732)
		(width 0.4572)
		(layer "F.Cu")
		(net "PSU6_REMOTE_R_N")
	)
	(segment
		(start 44.564046 -253.40564)
		(end 44.564046 -253.399544)
		(width 0.4572)
		(layer "F.Cu")
		(net "PSU6_REMOTE_R_N")
	)
	(segment
		(start 44.837858 -253.125732)
		(end 46.025562 -253.125732)
		(width 0.4572)
		(layer "F.Cu")
		(net "PSU6_REMOTE_R_N")
	)
	(via
		(at 27.640026 -463.41538)
		(size 0.508)
		(drill 0.254)
		(layers "F.Cu" "B.Cu")
		(net "PSU6_REMOTE_R_N")
	)
	(via
		(at 44.564046 -253.40564)
		(size 0.508)
		(drill 0.254)
		(layers "F.Cu" "B.Cu")
		(net "PSU6_REMOTE_R_N")
	)
	(via
		(at 16.148558 -258.85521)
		(size 0.508)
		(drill 0.254)
		(layers "F.Cu" "B.Cu")
		(net "PSU6_REMOTE_R_N")
	)
	(segment
		(start 16.148558 -258.85521)
		(end 16.148558 -276.849078)
		(width 0.4572)
		(layer "B.Cu")
		(net "PSU6_REMOTE_R_N")
	)
	(segment
		(start 25.232614 -290.312856)
		(end 25.232614 -318.439292)
		(width 0.4572)
		(layer "B.Cu")
		(net "PSU6_REMOTE_R_N")
	)
	(segment
		(start 16.148558 -276.849078)
		(end 19.958304 -280.658824)
		(width 0.4572)
		(layer "B.Cu")
		(net "PSU6_REMOTE_R_N")
	)
	(segment
		(start 25.026366 -445.001396)
		(end 24.116538 -445.911224)
		(width 0.4572)
		(layer "B.Cu")
		(net "PSU6_REMOTE_R_N")
	)
	(segment
		(start 22.674326 -379.09627)
		(end 25.026366 -381.44831)
		(width 0.4572)
		(layer "B.Cu")
		(net "PSU6_REMOTE_R_N")
	)
	(segment
		(start 20.854924 -358.176322)
		(end 22.674326 -359.995724)
		(width 0.4572)
		(layer "B.Cu")
		(net "PSU6_REMOTE_R_N")
	)
	(segment
		(start 19.958304 -285.038546)
		(end 25.232614 -290.312856)
		(width 0.4572)
		(layer "B.Cu")
		(net "PSU6_REMOTE_R_N")
	)
	(segment
		(start 25.232614 -318.439292)
		(end 20.854924 -322.816982)
		(width 0.4572)
		(layer "B.Cu")
		(net "PSU6_REMOTE_R_N")
	)
	(segment
		(start 22.674326 -359.995724)
		(end 22.674326 -379.09627)
		(width 0.4572)
		(layer "B.Cu")
		(net "PSU6_REMOTE_R_N")
	)
	(segment
		(start 24.116538 -445.911224)
		(end 24.116538 -459.891892)
		(width 0.4572)
		(layer "B.Cu")
		(net "PSU6_REMOTE_R_N")
	)
	(segment
		(start 25.026366 -381.44831)
		(end 25.026366 -445.001396)
		(width 0.4572)
		(layer "B.Cu")
		(net "PSU6_REMOTE_R_N")
	)
	(segment
		(start 24.116538 -459.891892)
		(end 27.640026 -463.41538)
		(width 0.4572)
		(layer "B.Cu")
		(net "PSU6_REMOTE_R_N")
	)
	(segment
		(start 19.958304 -280.658824)
		(end 19.958304 -285.038546)
		(width 0.4572)
		(layer "B.Cu")
		(net "PSU6_REMOTE_R_N")
	)
	(segment
		(start 20.854924 -322.816982)
		(end 20.854924 -358.176322)
		(width 0.4572)
		(layer "B.Cu")
		(net "PSU6_REMOTE_R_N")
	)
	(segment
		(start 28.947618 -253.836932)
		(end 44.132754 -253.836932)
		(width 0.4572)
		(layer "In5.Cu")
		(net "PSU6_REMOTE_R_N")
	)
	(segment
		(start 19.025362 -253.17196)
		(end 28.282646 -253.17196)
		(width 0.4572)
		(layer "In5.Cu")
		(net "PSU6_REMOTE_R_N")
	)
	(segment
		(start 16.148558 -258.85521)
		(end 16.148558 -256.048764)
		(width 0.4572)
		(layer "In5.Cu")
		(net "PSU6_REMOTE_R_N")
	)
	(segment
		(start 44.132754 -253.836932)
		(end 44.564046 -253.40564)
		(width 0.4572)
		(layer "In5.Cu")
		(net "PSU6_REMOTE_R_N")
	)
	(segment
		(start 28.282646 -253.17196)
		(end 28.947618 -253.836932)
		(width 0.4572)
		(layer "In5.Cu")
		(net "PSU6_REMOTE_R_N")
	)
	(segment
		(start 16.148558 -256.048764)
		(end 19.025362 -253.17196)
		(width 0.4572)
		(layer "In5.Cu")
		(net "PSU6_REMOTE_R_N")
	)
	(segment
		(start 44.892468 -251.703332)
		(end 46.036738 -251.703332)
		(width 0.4572)
		(layer "F.Cu")
		(net "PSU6_REMOTE_R_P")
	)
	(segment
		(start 39.51478 -465.17052)
		(end 40.594788 -465.17052)
		(width 0.4572)
		(layer "F.Cu")
		(net "PSU6_REMOTE_R_P")
	)
	(segment
		(start 44.638468 -251.449332)
		(end 44.892468 -251.703332)
		(width 0.4572)
		(layer "F.Cu")
		(net "PSU6_REMOTE_R_P")
	)
	(via
		(at 40.594788 -465.17052)
		(size 0.508)
		(drill 0.254)
		(layers "F.Cu" "B.Cu")
		(net "PSU6_REMOTE_R_P")
	)
	(via
		(at 15.44701 -258.832604)
		(size 0.508)
		(drill 0.254)
		(layers "F.Cu" "B.Cu")
		(net "PSU6_REMOTE_R_P")
	)
	(via
		(at 44.638468 -251.449332)
		(size 0.508)
		(drill 0.254)
		(layers "F.Cu" "B.Cu")
		(net "PSU6_REMOTE_R_P")
	)
	(segment
		(start 24.531066 -318.148462)
		(end 20.153376 -322.526152)
		(width 0.4572)
		(layer "B.Cu")
		(net "PSU6_REMOTE_R_P")
	)
	(segment
		(start 20.153376 -322.526152)
		(end 20.153376 -358.467152)
		(width 0.4572)
		(layer "B.Cu")
		(net "PSU6_REMOTE_R_P")
	)
	(segment
		(start 37.480748 -465.71662)
		(end 38.026848 -465.17052)
		(width 0.4572)
		(layer "B.Cu")
		(net "PSU6_REMOTE_R_P")
	)
	(segment
		(start 21.972778 -379.3871)
		(end 24.324818 -381.73914)
		(width 0.4572)
		(layer "B.Cu")
		(net "PSU6_REMOTE_R_P")
	)
	(segment
		(start 15.44701 -277.139908)
		(end 19.256756 -280.949654)
		(width 0.4572)
		(layer "B.Cu")
		(net "PSU6_REMOTE_R_P")
	)
	(segment
		(start 19.256756 -280.949654)
		(end 19.256756 -285.329376)
		(width 0.4572)
		(layer "B.Cu")
		(net "PSU6_REMOTE_R_P")
	)
	(segment
		(start 20.153376 -358.467152)
		(end 21.972778 -360.286554)
		(width 0.4572)
		(layer "B.Cu")
		(net "PSU6_REMOTE_R_P")
	)
	(segment
		(start 28.150312 -465.71662)
		(end 37.480748 -465.71662)
		(width 0.4572)
		(layer "B.Cu")
		(net "PSU6_REMOTE_R_P")
	)
	(segment
		(start 24.324818 -444.710566)
		(end 23.41499 -445.620394)
		(width 0.4572)
		(layer "B.Cu")
		(net "PSU6_REMOTE_R_P")
	)
	(segment
		(start 15.44701 -258.832604)
		(end 15.44701 -277.139908)
		(width 0.4572)
		(layer "B.Cu")
		(net "PSU6_REMOTE_R_P")
	)
	(segment
		(start 19.256756 -285.329376)
		(end 24.531066 -290.603686)
		(width 0.4572)
		(layer "B.Cu")
		(net "PSU6_REMOTE_R_P")
	)
	(segment
		(start 38.026848 -465.17052)
		(end 40.594788 -465.17052)
		(width 0.4572)
		(layer "B.Cu")
		(net "PSU6_REMOTE_R_P")
	)
	(segment
		(start 23.41499 -460.981298)
		(end 28.150312 -465.71662)
		(width 0.4572)
		(layer "B.Cu")
		(net "PSU6_REMOTE_R_P")
	)
	(segment
		(start 24.324818 -381.73914)
		(end 24.324818 -444.710566)
		(width 0.4572)
		(layer "B.Cu")
		(net "PSU6_REMOTE_R_P")
	)
	(segment
		(start 21.972778 -360.286554)
		(end 21.972778 -379.3871)
		(width 0.4572)
		(layer "B.Cu")
		(net "PSU6_REMOTE_R_P")
	)
	(segment
		(start 24.531066 -290.603686)
		(end 24.531066 -318.148462)
		(width 0.4572)
		(layer "B.Cu")
		(net "PSU6_REMOTE_R_P")
	)
	(segment
		(start 23.41499 -445.620394)
		(end 23.41499 -460.981298)
		(width 0.4572)
		(layer "B.Cu")
		(net "PSU6_REMOTE_R_P")
	)
	(segment
		(start 29.493972 -251.164344)
		(end 43.74388 -251.164344)
		(width 0.4572)
		(layer "In5.Cu")
		(net "PSU6_REMOTE_R_P")
	)
	(segment
		(start 43.74388 -251.164344)
		(end 44.028868 -251.449332)
		(width 0.4572)
		(layer "In5.Cu")
		(net "PSU6_REMOTE_R_P")
	)
	(segment
		(start 15.44701 -258.832604)
		(end 15.44701 -255.746758)
		(width 0.4572)
		(layer "In5.Cu")
		(net "PSU6_REMOTE_R_P")
	)
	(segment
		(start 28.147772 -252.510544)
		(end 29.493972 -251.164344)
		(width 0.4572)
		(layer "In5.Cu")
		(net "PSU6_REMOTE_R_P")
	)
	(segment
		(start 15.44701 -255.746758)
		(end 18.683224 -252.510544)
		(width 0.4572)
		(layer "In5.Cu")
		(net "PSU6_REMOTE_R_P")
	)
	(segment
		(start 18.683224 -252.510544)
		(end 28.147772 -252.510544)
		(width 0.4572)
		(layer "In5.Cu")
		(net "PSU6_REMOTE_R_P")
	)
	(segment
		(start 44.028868 -251.449332)
		(end 44.638468 -251.449332)
		(width 0.4572)
		(layer "In5.Cu")
		(net "PSU6_REMOTE_R_P")
	)
	(segment
		(start 44.455588 -248.991374)
		(end 44.741846 -248.705116)
		(width 0.4572)
		(layer "F.Cu")
		(net "PSU3_REMOTE_R_N")
	)
	(segment
		(start 44.741846 -248.705116)
		(end 46.096428 -248.705116)
		(width 0.4572)
		(layer "F.Cu")
		(net "PSU3_REMOTE_R_N")
	)
	(segment
		(start 28.879038 -198.978774)
		(end 27.33421 -197.433946)
		(width 0.4572)
		(layer "F.Cu")
		(net "PSU3_REMOTE_R_N")
	)
	(segment
		(start 28.879038 -201.750422)
		(end 28.879038 -198.978774)
		(width 0.4572)
		(layer "F.Cu")
		(net "PSU3_REMOTE_R_N")
	)
	(via
		(at 44.455588 -248.991374)
		(size 0.508)
		(drill 0.254)
		(layers "F.Cu" "B.Cu")
		(net "PSU3_REMOTE_R_N")
	)
	(via
		(at 28.879038 -201.750422)
		(size 0.508)
		(drill 0.254)
		(layers "F.Cu" "B.Cu")
		(net "PSU3_REMOTE_R_N")
	)
	(via
		(at 26.063194 -246.94388)
		(size 0.508)
		(drill 0.254)
		(layers "F.Cu" "B.Cu")
		(net "PSU3_REMOTE_R_N")
	)
	(segment
		(start 25.606248 -246.486934)
		(end 25.606248 -205.023212)
		(width 0.4572)
		(layer "B.Cu")
		(net "PSU3_REMOTE_R_N")
	)
	(segment
		(start 26.063194 -246.94388)
		(end 25.606248 -246.486934)
		(width 0.4572)
		(layer "B.Cu")
		(net "PSU3_REMOTE_R_N")
	)
	(segment
		(start 25.606248 -205.023212)
		(end 28.879038 -201.750422)
		(width 0.4572)
		(layer "B.Cu")
		(net "PSU3_REMOTE_R_N")
	)
	(segment
		(start 27.226514 -248.723404)
		(end 43.578018 -248.723404)
		(width 0.4572)
		(layer "In5.Cu")
		(net "PSU3_REMOTE_R_N")
	)
	(segment
		(start 26.063194 -247.560084)
		(end 27.226514 -248.723404)
		(width 0.4572)
		(layer "In5.Cu")
		(net "PSU3_REMOTE_R_N")
	)
	(segment
		(start 43.845988 -248.991374)
		(end 44.455588 -248.991374)
		(width 0.4572)
		(layer "In5.Cu")
		(net "PSU3_REMOTE_R_N")
	)
	(segment
		(start 26.063194 -246.94388)
		(end 26.063194 -247.560084)
		(width 0.4572)
		(layer "In5.Cu")
		(net "PSU3_REMOTE_R_N")
	)
	(segment
		(start 43.578018 -248.723404)
		(end 43.845988 -248.991374)
		(width 0.4572)
		(layer "In5.Cu")
		(net "PSU3_REMOTE_R_N")
	)
	(segment
		(start 40.399462 -199.96912)
		(end 39.461948 -199.96912)
		(width 0.4572)
		(layer "F.Cu")
		(net "PSU3_REMOTE_R_P")
	)
	(segment
		(start 44.48429 -247.01246)
		(end 44.754546 -247.282716)
		(width 0.4572)
		(layer "F.Cu")
		(net "PSU3_REMOTE_R_P")
	)
	(segment
		(start 44.754546 -247.282716)
		(end 46.072806 -247.282716)
		(width 0.4572)
		(layer "F.Cu")
		(net "PSU3_REMOTE_R_P")
	)
	(via
		(at 26.77033 -246.89816)
		(size 0.508)
		(drill 0.254)
		(layers "F.Cu" "B.Cu")
		(net "PSU3_REMOTE_R_P")
	)
	(via
		(at 44.48429 -247.01246)
		(size 0.508)
		(drill 0.254)
		(layers "F.Cu" "B.Cu")
		(net "PSU3_REMOTE_R_P")
	)
	(via
		(at 40.399462 -199.96912)
		(size 0.508)
		(drill 0.254)
		(layers "F.Cu" "B.Cu")
		(net "PSU3_REMOTE_R_P")
	)
	(segment
		(start 26.310336 -246.16664)
		(end 26.77033 -246.626634)
		(width 0.4572)
		(layer "B.Cu")
		(net "PSU3_REMOTE_R_P")
	)
	(segment
		(start 29.925264 -203.007214)
		(end 26.310336 -206.622142)
		(width 0.4572)
		(layer "B.Cu")
		(net "PSU3_REMOTE_R_P")
	)
	(segment
		(start 37.361368 -203.007214)
		(end 29.925264 -203.007214)
		(width 0.4572)
		(layer "B.Cu")
		(net "PSU3_REMOTE_R_P")
	)
	(segment
		(start 26.77033 -246.626634)
		(end 26.77033 -246.89816)
		(width 0.4572)
		(layer "B.Cu")
		(net "PSU3_REMOTE_R_P")
	)
	(segment
		(start 26.310336 -206.622142)
		(end 26.310336 -246.16664)
		(width 0.4572)
		(layer "B.Cu")
		(net "PSU3_REMOTE_R_P")
	)
	(segment
		(start 40.399462 -199.96912)
		(end 37.361368 -203.007214)
		(width 0.4572)
		(layer "B.Cu")
		(net "PSU3_REMOTE_R_P")
	)
	(segment
		(start 26.77033 -246.89816)
		(end 28.752546 -246.89816)
		(width 0.4572)
		(layer "In5.Cu")
		(net "PSU3_REMOTE_R_P")
	)
	(segment
		(start 29.459682 -246.191024)
		(end 43.662854 -246.191024)
		(width 0.4572)
		(layer "In5.Cu")
		(net "PSU3_REMOTE_R_P")
	)
	(segment
		(start 28.752546 -246.89816)
		(end 29.459682 -246.191024)
		(width 0.4572)
		(layer "In5.Cu")
		(net "PSU3_REMOTE_R_P")
	)
	(segment
		(start 43.662854 -246.191024)
		(end 44.48429 -247.01246)
		(width 0.4572)
		(layer "In5.Cu")
		(net "PSU3_REMOTE_R_P")
	)
	(segment
		(start 44.873672 -243.096034)
		(end 46.00829 -243.096034)
		(width 0.4572)
		(layer "F.Cu")
		(net "PSU2_REMOTE_R_P")
	)
	(segment
		(start 39.459154 -111.574072)
		(end 40.390826 -111.574072)
		(width 0.4572)
		(layer "F.Cu")
		(net "PSU2_REMOTE_R_P")
	)
	(segment
		(start 44.592494 -242.814856)
		(end 44.873672 -243.096034)
		(width 0.4572)
		(layer "F.Cu")
		(net "PSU2_REMOTE_R_P")
	)
	(via
		(at 40.390826 -111.574072)
		(size 0.508)
		(drill 0.254)
		(layers "F.Cu" "B.Cu")
		(net "PSU2_REMOTE_R_P")
	)
	(via
		(at 44.592494 -242.814856)
		(size 0.508)
		(drill 0.254)
		(layers "F.Cu" "B.Cu")
		(net "PSU2_REMOTE_R_P")
	)
	(segment
		(start 36.654994 -179.030884)
		(end 33.143698 -179.030884)
		(width 0.4572)
		(layer "B.Cu")
		(net "PSU2_REMOTE_R_P")
	)
	(segment
		(start 43.223688 -201.347578)
		(end 43.223688 -191.474344)
		(width 0.4572)
		(layer "B.Cu")
		(net "PSU2_REMOTE_R_P")
	)
	(segment
		(start 25.827482 -171.714668)
		(end 25.827482 -113.647982)
		(width 0.4572)
		(layer "B.Cu")
		(net "PSU2_REMOTE_R_P")
	)
	(segment
		(start 29.988764 -109.4867)
		(end 38.303454 -109.4867)
		(width 0.4572)
		(layer "B.Cu")
		(net "PSU2_REMOTE_R_P")
	)
	(segment
		(start 44.158916 -243.248434)
		(end 38.838124 -243.248434)
		(width 0.4572)
		(layer "B.Cu")
		(net "PSU2_REMOTE_R_P")
	)
	(segment
		(start 27.79141 -209.532474)
		(end 29.191966 -208.131918)
		(width 0.4572)
		(layer "B.Cu")
		(net "PSU2_REMOTE_R_P")
	)
	(segment
		(start 38.303454 -109.4867)
		(end 40.390826 -111.574072)
		(width 0.4572)
		(layer "B.Cu")
		(net "PSU2_REMOTE_R_P")
	)
	(segment
		(start 36.754816 -241.165126)
		(end 29.882592 -241.165126)
		(width 0.4572)
		(layer "B.Cu")
		(net "PSU2_REMOTE_R_P")
	)
	(segment
		(start 44.592494 -242.814856)
		(end 44.158916 -243.248434)
		(width 0.4572)
		(layer "B.Cu")
		(net "PSU2_REMOTE_R_P")
	)
	(segment
		(start 37.994082 -180.369972)
		(end 36.654994 -179.030884)
		(width 0.4572)
		(layer "B.Cu")
		(net "PSU2_REMOTE_R_P")
	)
	(segment
		(start 29.191966 -208.131918)
		(end 36.439348 -208.131918)
		(width 0.4572)
		(layer "B.Cu")
		(net "PSU2_REMOTE_R_P")
	)
	(segment
		(start 27.79141 -239.073944)
		(end 27.79141 -209.532474)
		(width 0.4572)
		(layer "B.Cu")
		(net "PSU2_REMOTE_R_P")
	)
	(segment
		(start 29.882592 -241.165126)
		(end 27.79141 -239.073944)
		(width 0.4572)
		(layer "B.Cu")
		(net "PSU2_REMOTE_R_P")
	)
	(segment
		(start 25.827482 -113.647982)
		(end 29.988764 -109.4867)
		(width 0.4572)
		(layer "B.Cu")
		(net "PSU2_REMOTE_R_P")
	)
	(segment
		(start 36.439348 -208.131918)
		(end 43.223688 -201.347578)
		(width 0.4572)
		(layer "B.Cu")
		(net "PSU2_REMOTE_R_P")
	)
	(segment
		(start 33.143698 -179.030884)
		(end 25.827482 -171.714668)
		(width 0.4572)
		(layer "B.Cu")
		(net "PSU2_REMOTE_R_P")
	)
	(segment
		(start 37.994082 -186.244738)
		(end 37.994082 -180.369972)
		(width 0.4572)
		(layer "B.Cu")
		(net "PSU2_REMOTE_R_P")
	)
	(segment
		(start 38.838124 -243.248434)
		(end 36.754816 -241.165126)
		(width 0.4572)
		(layer "B.Cu")
		(net "PSU2_REMOTE_R_P")
	)
	(segment
		(start 43.223688 -191.474344)
		(end 37.994082 -186.244738)
		(width 0.4572)
		(layer "B.Cu")
		(net "PSU2_REMOTE_R_P")
	)
	(segment
		(start 44.748196 -244.518434)
		(end 45.985684 -244.518434)
		(width 0.4572)
		(layer "F.Cu")
		(net "PSU2_REMOTE_R_N")
	)
	(segment
		(start 27.80665 -110.424722)
		(end 27.347672 -109.965744)
		(width 0.4572)
		(layer "F.Cu")
		(net "PSU2_REMOTE_R_N")
	)
	(segment
		(start 44.541186 -244.725444)
		(end 44.748196 -244.518434)
		(width 0.4572)
		(layer "F.Cu")
		(net "PSU2_REMOTE_R_N")
	)
	(segment
		(start 27.347672 -109.965744)
		(end 27.347672 -109.030516)
		(width 0.4572)
		(layer "F.Cu")
		(net "PSU2_REMOTE_R_N")
	)
	(via
		(at 27.80665 -110.424722)
		(size 0.508)
		(drill 0.254)
		(layers "F.Cu" "B.Cu")
		(net "PSU2_REMOTE_R_N")
	)
	(via
		(at 44.541186 -244.725444)
		(size 0.508)
		(drill 0.254)
		(layers "F.Cu" "B.Cu")
		(net "PSU2_REMOTE_R_N")
	)
	(segment
		(start 38.513258 -244.183916)
		(end 43.999658 -244.183916)
		(width 0.4572)
		(layer "B.Cu")
		(net "PSU2_REMOTE_R_N")
	)
	(segment
		(start 32.874204 -179.966366)
		(end 36.228782 -179.966366)
		(width 0.4572)
		(layer "B.Cu")
		(net "PSU2_REMOTE_R_N")
	)
	(segment
		(start 36.228782 -179.966366)
		(end 37.182044 -180.919628)
		(width 0.4572)
		(layer "B.Cu")
		(net "PSU2_REMOTE_R_N")
	)
	(segment
		(start 43.999658 -244.183916)
		(end 44.541186 -244.725444)
		(width 0.4572)
		(layer "B.Cu")
		(net "PSU2_REMOTE_R_N")
	)
	(segment
		(start 37.717222 -205.530958)
		(end 29.271722 -205.530958)
		(width 0.4572)
		(layer "B.Cu")
		(net "PSU2_REMOTE_R_N")
	)
	(segment
		(start 37.182044 -186.755786)
		(end 42.288206 -191.861948)
		(width 0.4572)
		(layer "B.Cu")
		(net "PSU2_REMOTE_R_N")
	)
	(segment
		(start 27.80665 -110.424722)
		(end 24.925528 -113.305844)
		(width 0.4572)
		(layer "B.Cu")
		(net "PSU2_REMOTE_R_N")
	)
	(segment
		(start 29.471874 -243.586)
		(end 37.915342 -243.586)
		(width 0.4572)
		(layer "B.Cu")
		(net "PSU2_REMOTE_R_N")
	)
	(segment
		(start 29.271722 -205.530958)
		(end 27.051254 -207.751426)
		(width 0.4572)
		(layer "B.Cu")
		(net "PSU2_REMOTE_R_N")
	)
	(segment
		(start 37.915342 -243.586)
		(end 38.513258 -244.183916)
		(width 0.4572)
		(layer "B.Cu")
		(net "PSU2_REMOTE_R_N")
	)
	(segment
		(start 37.182044 -180.919628)
		(end 37.182044 -186.755786)
		(width 0.4572)
		(layer "B.Cu")
		(net "PSU2_REMOTE_R_N")
	)
	(segment
		(start 42.288206 -191.861948)
		(end 42.288206 -200.959974)
		(width 0.4572)
		(layer "B.Cu")
		(net "PSU2_REMOTE_R_N")
	)
	(segment
		(start 27.051254 -241.16538)
		(end 29.471874 -243.586)
		(width 0.4572)
		(layer "B.Cu")
		(net "PSU2_REMOTE_R_N")
	)
	(segment
		(start 24.925528 -113.305844)
		(end 24.925528 -172.01769)
		(width 0.4572)
		(layer "B.Cu")
		(net "PSU2_REMOTE_R_N")
	)
	(segment
		(start 27.051254 -207.751426)
		(end 27.051254 -241.16538)
		(width 0.4572)
		(layer "B.Cu")
		(net "PSU2_REMOTE_R_N")
	)
	(segment
		(start 42.288206 -200.959974)
		(end 37.717222 -205.530958)
		(width 0.4572)
		(layer "B.Cu")
		(net "PSU2_REMOTE_R_N")
	)
	(segment
		(start 24.925528 -172.01769)
		(end 32.874204 -179.966366)
		(width 0.4572)
		(layer "B.Cu")
		(net "PSU2_REMOTE_R_N")
	)
	(segment
		(start 39.46398 -23.185374)
		(end 40.491918 -23.185374)
		(width 0.4572)
		(layer "F.Cu")
		(net "PSU1_REMOTE_R_P")
	)
	(segment
		(start 44.998894 -238.246666)
		(end 46.030642 -238.246666)
		(width 0.4572)
		(layer "F.Cu")
		(net "PSU1_REMOTE_R_P")
	)
	(segment
		(start 44.706794 -237.954566)
		(end 44.998894 -238.246666)
		(width 0.4572)
		(layer "F.Cu")
		(net "PSU1_REMOTE_R_P")
	)
	(via
		(at 40.491918 -23.185374)
		(size 0.508)
		(drill 0.254)
		(layers "F.Cu" "B.Cu")
		(net "PSU1_REMOTE_R_P")
	)
	(via
		(at 44.706794 -237.954566)
		(size 0.508)
		(drill 0.254)
		(layers "F.Cu" "B.Cu")
		(net "PSU1_REMOTE_R_P")
	)
	(segment
		(start 36.455604 -213.093808)
		(end 38.055804 -211.493608)
		(width 0.4572)
		(layer "B.Cu")
		(net "PSU1_REMOTE_R_P")
	)
	(segment
		(start 42.637456 -111.894112)
		(end 42.637456 -100.589588)
		(width 0.4572)
		(layer "B.Cu")
		(net "PSU1_REMOTE_R_P")
	)
	(segment
		(start 29.952188 -213.093808)
		(end 36.455604 -213.093808)
		(width 0.4572)
		(layer "B.Cu")
		(net "PSU1_REMOTE_R_P")
	)
	(segment
		(start 35.514788 -89.365328)
		(end 33.754314 -89.365328)
		(width 0.4572)
		(layer "B.Cu")
		(net "PSU1_REMOTE_R_P")
	)
	(segment
		(start 44.706794 -237.954566)
		(end 44.124118 -238.537242)
		(width 0.4572)
		(layer "B.Cu")
		(net "PSU1_REMOTE_R_P")
	)
	(segment
		(start 39.573708 -179.638452)
		(end 37.17544 -177.240184)
		(width 0.4572)
		(layer "B.Cu")
		(net "PSU1_REMOTE_R_P")
	)
	(segment
		(start 27.671776 -83.28279)
		(end 27.671776 -24.87041)
		(width 0.4572)
		(layer "B.Cu")
		(net "PSU1_REMOTE_R_P")
	)
	(segment
		(start 29.271976 -235.28274)
		(end 29.271976 -213.77402)
		(width 0.4572)
		(layer "B.Cu")
		(net "PSU1_REMOTE_R_P")
	)
	(segment
		(start 38.876224 -96.828356)
		(end 38.876224 -92.726764)
		(width 0.4572)
		(layer "B.Cu")
		(net "PSU1_REMOTE_R_P")
	)
	(segment
		(start 45.031406 -191.069214)
		(end 39.573708 -185.611516)
		(width 0.4572)
		(layer "B.Cu")
		(net "PSU1_REMOTE_R_P")
	)
	(segment
		(start 40.019986 -23.657306)
		(end 40.491918 -23.185374)
		(width 0.4572)
		(layer "B.Cu")
		(net "PSU1_REMOTE_R_P")
	)
	(segment
		(start 33.754314 -89.365328)
		(end 27.671776 -83.28279)
		(width 0.4572)
		(layer "B.Cu")
		(net "PSU1_REMOTE_R_P")
	)
	(segment
		(start 39.14902 -238.537242)
		(end 36.65474 -236.042962)
		(width 0.4572)
		(layer "B.Cu")
		(net "PSU1_REMOTE_R_P")
	)
	(segment
		(start 39.573708 -185.611516)
		(end 39.573708 -179.638452)
		(width 0.4572)
		(layer "B.Cu")
		(net "PSU1_REMOTE_R_P")
	)
	(segment
		(start 38.055804 -209.024474)
		(end 45.031406 -202.048872)
		(width 0.4572)
		(layer "B.Cu")
		(net "PSU1_REMOTE_R_P")
	)
	(segment
		(start 27.671776 -24.87041)
		(end 28.88488 -23.657306)
		(width 0.4572)
		(layer "B.Cu")
		(net "PSU1_REMOTE_R_P")
	)
	(segment
		(start 29.494988 -114.592354)
		(end 39.939214 -114.592354)
		(width 0.4572)
		(layer "B.Cu")
		(net "PSU1_REMOTE_R_P")
	)
	(segment
		(start 39.939214 -114.592354)
		(end 42.637456 -111.894112)
		(width 0.4572)
		(layer "B.Cu")
		(net "PSU1_REMOTE_R_P")
	)
	(segment
		(start 37.17544 -177.240184)
		(end 33.783524 -177.240184)
		(width 0.4572)
		(layer "B.Cu")
		(net "PSU1_REMOTE_R_P")
	)
	(segment
		(start 30.032198 -236.042962)
		(end 29.271976 -235.28274)
		(width 0.4572)
		(layer "B.Cu")
		(net "PSU1_REMOTE_R_P")
	)
	(segment
		(start 28.321254 -171.777914)
		(end 28.321254 -115.766088)
		(width 0.4572)
		(layer "B.Cu")
		(net "PSU1_REMOTE_R_P")
	)
	(segment
		(start 36.65474 -236.042962)
		(end 30.032198 -236.042962)
		(width 0.4572)
		(layer "B.Cu")
		(net "PSU1_REMOTE_R_P")
	)
	(segment
		(start 45.031406 -202.048872)
		(end 45.031406 -191.069214)
		(width 0.4572)
		(layer "B.Cu")
		(net "PSU1_REMOTE_R_P")
	)
	(segment
		(start 38.055804 -211.493608)
		(end 38.055804 -209.024474)
		(width 0.4572)
		(layer "B.Cu")
		(net "PSU1_REMOTE_R_P")
	)
	(segment
		(start 42.637456 -100.589588)
		(end 38.876224 -96.828356)
		(width 0.4572)
		(layer "B.Cu")
		(net "PSU1_REMOTE_R_P")
	)
	(segment
		(start 29.271976 -213.77402)
		(end 29.952188 -213.093808)
		(width 0.4572)
		(layer "B.Cu")
		(net "PSU1_REMOTE_R_P")
	)
	(segment
		(start 33.783524 -177.240184)
		(end 28.321254 -171.777914)
		(width 0.4572)
		(layer "B.Cu")
		(net "PSU1_REMOTE_R_P")
	)
	(segment
		(start 38.876224 -92.726764)
		(end 35.514788 -89.365328)
		(width 0.4572)
		(layer "B.Cu")
		(net "PSU1_REMOTE_R_P")
	)
	(segment
		(start 44.124118 -238.537242)
		(end 39.14902 -238.537242)
		(width 0.4572)
		(layer "B.Cu")
		(net "PSU1_REMOTE_R_P")
	)
	(segment
		(start 28.88488 -23.657306)
		(end 40.019986 -23.657306)
		(width 0.4572)
		(layer "B.Cu")
		(net "PSU1_REMOTE_R_P")
	)
	(segment
		(start 28.321254 -115.766088)
		(end 29.494988 -114.592354)
		(width 0.4572)
		(layer "B.Cu")
		(net "PSU1_REMOTE_R_P")
	)
	(segment
		(start 44.944538 -239.669066)
		(end 46.008036 -239.669066)
		(width 0.4572)
		(layer "F.Cu")
		(net "PSU1_REMOTE_R_N")
	)
	(segment
		(start 27.232102 -21.632926)
		(end 27.232102 -21.646896)
		(width 0.4572)
		(layer "F.Cu")
		(net "PSU1_REMOTE_R_N")
	)
	(segment
		(start 27.246072 -21.632926)
		(end 27.246072 -20.66417)
		(width 0.4572)
		(layer "F.Cu")
		(net "PSU1_REMOTE_R_N")
	)
	(segment
		(start 44.701206 -239.912398)
		(end 44.944538 -239.669066)
		(width 0.4572)
		(layer "F.Cu")
		(net "PSU1_REMOTE_R_N")
	)
	(segment
		(start 27.232102 -21.646896)
		(end 27.246072 -21.632926)
		(width 0.4572)
		(layer "F.Cu")
		(net "PSU1_REMOTE_R_N")
	)
	(via
		(at 44.701206 -239.912398)
		(size 0.508)
		(drill 0.254)
		(layers "F.Cu" "B.Cu")
		(net "PSU1_REMOTE_R_N")
	)
	(via
		(at 27.232102 -21.632926)
		(size 0.508)
		(drill 0.254)
		(layers "F.Cu" "B.Cu")
		(net "PSU1_REMOTE_R_N")
	)
	(segment
		(start 26.94432 -83.584288)
		(end 26.94432 -24.106632)
		(width 0.4572)
		(layer "B.Cu")
		(net "PSU1_REMOTE_R_N")
	)
	(segment
		(start 38.148768 -93.028262)
		(end 35.21329 -90.092784)
		(width 0.4572)
		(layer "B.Cu")
		(net "PSU1_REMOTE_R_N")
	)
	(segment
		(start 44.162726 -239.373918)
		(end 38.21557 -239.373918)
		(width 0.4572)
		(layer "B.Cu")
		(net "PSU1_REMOTE_R_N")
	)
	(segment
		(start 33.452816 -90.092784)
		(end 26.94432 -83.584288)
		(width 0.4572)
		(layer "B.Cu")
		(net "PSU1_REMOTE_R_N")
	)
	(segment
		(start 29.792422 -238.514128)
		(end 28.571952 -237.293658)
		(width 0.4572)
		(layer "B.Cu")
		(net "PSU1_REMOTE_R_N")
	)
	(segment
		(start 28.571952 -211.93379)
		(end 29.872432 -210.63331)
		(width 0.4572)
		(layer "B.Cu")
		(net "PSU1_REMOTE_R_N")
	)
	(segment
		(start 41.91 -111.390938)
		(end 41.91 -100.891086)
		(width 0.4572)
		(layer "B.Cu")
		(net "PSU1_REMOTE_R_N")
	)
	(segment
		(start 38.64864 -112.081056)
		(end 39.05885 -112.491266)
		(width 0.4572)
		(layer "B.Cu")
		(net "PSU1_REMOTE_R_N")
	)
	(segment
		(start 41.91 -100.891086)
		(end 38.148768 -97.129854)
		(width 0.4572)
		(layer "B.Cu")
		(net "PSU1_REMOTE_R_N")
	)
	(segment
		(start 28.571952 -237.293658)
		(end 28.571952 -211.93379)
		(width 0.4572)
		(layer "B.Cu")
		(net "PSU1_REMOTE_R_N")
	)
	(segment
		(start 29.555186 -112.081056)
		(end 38.64864 -112.081056)
		(width 0.4572)
		(layer "B.Cu")
		(net "PSU1_REMOTE_R_N")
	)
	(segment
		(start 39.05885 -112.491266)
		(end 40.809672 -112.491266)
		(width 0.4572)
		(layer "B.Cu")
		(net "PSU1_REMOTE_R_N")
	)
	(segment
		(start 35.21329 -90.092784)
		(end 33.452816 -90.092784)
		(width 0.4572)
		(layer "B.Cu")
		(net "PSU1_REMOTE_R_N")
	)
	(segment
		(start 38.832282 -186.053476)
		(end 38.832282 -180.077364)
		(width 0.4572)
		(layer "B.Cu")
		(net "PSU1_REMOTE_R_N")
	)
	(segment
		(start 27.232102 -23.81885)
		(end 27.232102 -21.632926)
		(width 0.4572)
		(layer "B.Cu")
		(net "PSU1_REMOTE_R_N")
	)
	(segment
		(start 33.58388 -178.24069)
		(end 27.47264 -172.12945)
		(width 0.4572)
		(layer "B.Cu")
		(net "PSU1_REMOTE_R_N")
	)
	(segment
		(start 40.809672 -112.491266)
		(end 41.91 -111.390938)
		(width 0.4572)
		(layer "B.Cu")
		(net "PSU1_REMOTE_R_N")
	)
	(segment
		(start 38.832282 -180.077364)
		(end 36.995608 -178.24069)
		(width 0.4572)
		(layer "B.Cu")
		(net "PSU1_REMOTE_R_N")
	)
	(segment
		(start 36.294822 -210.63331)
		(end 37.055298 -209.872834)
		(width 0.4572)
		(layer "B.Cu")
		(net "PSU1_REMOTE_R_N")
	)
	(segment
		(start 37.35578 -238.514128)
		(end 29.792422 -238.514128)
		(width 0.4572)
		(layer "B.Cu")
		(net "PSU1_REMOTE_R_N")
	)
	(segment
		(start 37.055298 -208.841594)
		(end 44.19473 -201.702162)
		(width 0.4572)
		(layer "B.Cu")
		(net "PSU1_REMOTE_R_N")
	)
	(segment
		(start 29.872432 -210.63331)
		(end 36.294822 -210.63331)
		(width 0.4572)
		(layer "B.Cu")
		(net "PSU1_REMOTE_R_N")
	)
	(segment
		(start 37.055298 -209.872834)
		(end 37.055298 -208.841594)
		(width 0.4572)
		(layer "B.Cu")
		(net "PSU1_REMOTE_R_N")
	)
	(segment
		(start 44.19473 -191.415924)
		(end 38.832282 -186.053476)
		(width 0.4572)
		(layer "B.Cu")
		(net "PSU1_REMOTE_R_N")
	)
	(segment
		(start 38.21557 -239.373918)
		(end 37.35578 -238.514128)
		(width 0.4572)
		(layer "B.Cu")
		(net "PSU1_REMOTE_R_N")
	)
	(segment
		(start 27.47264 -114.163602)
		(end 29.555186 -112.081056)
		(width 0.4572)
		(layer "B.Cu")
		(net "PSU1_REMOTE_R_N")
	)
	(segment
		(start 44.19473 -201.702162)
		(end 44.19473 -191.415924)
		(width 0.4572)
		(layer "B.Cu")
		(net "PSU1_REMOTE_R_N")
	)
	(segment
		(start 44.701206 -239.912398)
		(end 44.162726 -239.373918)
		(width 0.4572)
		(layer "B.Cu")
		(net "PSU1_REMOTE_R_N")
	)
	(segment
		(start 27.47264 -172.12945)
		(end 27.47264 -114.163602)
		(width 0.4572)
		(layer "B.Cu")
		(net "PSU1_REMOTE_R_N")
	)
	(segment
		(start 26.94432 -24.106632)
		(end 27.232102 -23.81885)
		(width 0.4572)
		(layer "B.Cu")
		(net "PSU1_REMOTE_R_N")
	)
	(segment
		(start 36.995608 -178.24069)
		(end 33.58388 -178.24069)
		(width 0.4572)
		(layer "B.Cu")
		(net "PSU1_REMOTE_R_N")
	)
	(segment
		(start 38.148768 -97.129854)
		(end 38.148768 -93.028262)
		(width 0.4572)
		(layer "B.Cu")
		(net "PSU1_REMOTE_R_N")
	)
	(segment
		(start 27.550872 -286.838644)
		(end 27.639264 -286.750252)
		(width 0.4572)
		(layer "F.Cu")
		(net "PSU4_REMOTE_R_N")
	)
	(segment
		(start 45.965872 -257.889502)
		(end 44.819824 -257.889502)
		(width 0.4572)
		(layer "F.Cu")
		(net "PSU4_REMOTE_R_N")
	)
	(segment
		(start 27.639264 -286.750252)
		(end 27.639264 -285.829502)
		(width 0.4572)
		(layer "F.Cu")
		(net "PSU4_REMOTE_R_N")
	)
	(segment
		(start 44.819824 -257.889502)
		(end 44.570142 -258.139184)
		(width 0.4572)
		(layer "F.Cu")
		(net "PSU4_REMOTE_R_N")
	)
	(via
		(at 44.570142 -258.139184)
		(size 0.508)
		(drill 0.254)
		(layers "F.Cu" "B.Cu")
		(net "PSU4_REMOTE_R_N")
	)
	(via
		(at 20.192746 -257.777234)
		(size 0.508)
		(drill 0.254)
		(layers "F.Cu" "B.Cu")
		(net "PSU4_REMOTE_R_N")
	)
	(via
		(at 27.550872 -286.838644)
		(size 0.508)
		(drill 0.254)
		(layers "F.Cu" "B.Cu")
		(net "PSU4_REMOTE_R_N")
	)
	(segment
		(start 26.802842 -286.838644)
		(end 23.717504 -283.753306)
		(width 0.4572)
		(layer "B.Cu")
		(net "PSU4_REMOTE_R_N")
	)
	(segment
		(start 23.717504 -283.753306)
		(end 23.717504 -279.13584)
		(width 0.4572)
		(layer "B.Cu")
		(net "PSU4_REMOTE_R_N")
	)
	(segment
		(start 23.717504 -279.13584)
		(end 20.192746 -275.611082)
		(width 0.4572)
		(layer "B.Cu")
		(net "PSU4_REMOTE_R_N")
	)
	(segment
		(start 20.192746 -275.611082)
		(end 20.192746 -257.777234)
		(width 0.4572)
		(layer "B.Cu")
		(net "PSU4_REMOTE_R_N")
	)
	(segment
		(start 27.550872 -286.838644)
		(end 26.802842 -286.838644)
		(width 0.4572)
		(layer "B.Cu")
		(net "PSU4_REMOTE_R_N")
	)
	(segment
		(start 43.645836 -257.824478)
		(end 43.960542 -258.139184)
		(width 0.4572)
		(layer "In5.Cu")
		(net "PSU4_REMOTE_R_N")
	)
	(segment
		(start 39.626286 -257.824478)
		(end 43.645836 -257.824478)
		(width 0.4572)
		(layer "In5.Cu")
		(net "PSU4_REMOTE_R_N")
	)
	(segment
		(start 21.491702 -256.08915)
		(end 27.05227 -256.08915)
		(width 0.4572)
		(layer "In5.Cu")
		(net "PSU4_REMOTE_R_N")
	)
	(segment
		(start 43.960542 -258.139184)
		(end 44.570142 -258.139184)
		(width 0.4572)
		(layer "In5.Cu")
		(net "PSU4_REMOTE_R_N")
	)
	(segment
		(start 27.05227 -256.08915)
		(end 29.838142 -258.875022)
		(width 0.4572)
		(layer "In5.Cu")
		(net "PSU4_REMOTE_R_N")
	)
	(segment
		(start 29.838142 -258.875022)
		(end 38.575742 -258.875022)
		(width 0.4572)
		(layer "In5.Cu")
		(net "PSU4_REMOTE_R_N")
	)
	(segment
		(start 20.192746 -257.388106)
		(end 21.491702 -256.08915)
		(width 0.4572)
		(layer "In5.Cu")
		(net "PSU4_REMOTE_R_N")
	)
	(segment
		(start 38.575742 -258.875022)
		(end 39.626286 -257.824478)
		(width 0.4572)
		(layer "In5.Cu")
		(net "PSU4_REMOTE_R_N")
	)
	(segment
		(start 20.192746 -257.777234)
		(end 20.192746 -257.388106)
		(width 0.4572)
		(layer "In5.Cu")
		(net "PSU4_REMOTE_R_N")
	)
	(segment
		(start 39.642034 -288.582354)
		(end 40.483028 -288.582354)
		(width 0.4572)
		(layer "F.Cu")
		(net "PSU4_REMOTE_R_P")
	)
	(segment
		(start 39.437056 -288.377376)
		(end 39.642034 -288.582354)
		(width 0.4572)
		(layer "F.Cu")
		(net "PSU4_REMOTE_R_P")
	)
	(segment
		(start 44.627292 -256.21742)
		(end 44.876974 -256.467102)
		(width 0.4572)
		(layer "F.Cu")
		(net "PSU4_REMOTE_R_P")
	)
	(segment
		(start 44.876974 -256.467102)
		(end 45.96511 -256.467102)
		(width 0.4572)
		(layer "F.Cu")
		(net "PSU4_REMOTE_R_P")
	)
	(via
		(at 19.417284 -257.777234)
		(size 0.508)
		(drill 0.254)
		(layers "F.Cu" "B.Cu")
		(net "PSU4_REMOTE_R_P")
	)
	(via
		(at 40.483028 -288.582354)
		(size 0.508)
		(drill 0.254)
		(layers "F.Cu" "B.Cu")
		(net "PSU4_REMOTE_R_P")
	)
	(via
		(at 44.627292 -256.21742)
		(size 0.508)
		(drill 0.254)
		(layers "F.Cu" "B.Cu")
		(net "PSU4_REMOTE_R_P")
	)
	(segment
		(start 19.417284 -275.932392)
		(end 23.045674 -279.560782)
		(width 0.4572)
		(layer "B.Cu")
		(net "PSU4_REMOTE_R_P")
	)
	(segment
		(start 27.80792 -288.827718)
		(end 40.237664 -288.827718)
		(width 0.4572)
		(layer "B.Cu")
		(net "PSU4_REMOTE_R_P")
	)
	(segment
		(start 19.417284 -257.777234)
		(end 19.417284 -275.932392)
		(width 0.4572)
		(layer "B.Cu")
		(net "PSU4_REMOTE_R_P")
	)
	(segment
		(start 23.045674 -279.560782)
		(end 23.045674 -284.065472)
		(width 0.4572)
		(layer "B.Cu")
		(net "PSU4_REMOTE_R_P")
	)
	(segment
		(start 40.237664 -288.827718)
		(end 40.483028 -288.582354)
		(width 0.4572)
		(layer "B.Cu")
		(net "PSU4_REMOTE_R_P")
	)
	(segment
		(start 23.045674 -284.065472)
		(end 27.80792 -288.827718)
		(width 0.4572)
		(layer "B.Cu")
		(net "PSU4_REMOTE_R_P")
	)
	(segment
		(start 28.217876 -255.372616)
		(end 29.233876 -256.388616)
		(width 0.4572)
		(layer "In5.Cu")
		(net "PSU4_REMOTE_R_P")
	)
	(segment
		(start 21.09216 -255.372616)
		(end 28.217876 -255.372616)
		(width 0.4572)
		(layer "In5.Cu")
		(net "PSU4_REMOTE_R_P")
	)
	(segment
		(start 44.196 -255.786128)
		(end 44.627292 -256.21742)
		(width 0.4572)
		(layer "In5.Cu")
		(net "PSU4_REMOTE_R_P")
	)
	(segment
		(start 19.417284 -257.777234)
		(end 19.417284 -257.047492)
		(width 0.4572)
		(layer "In5.Cu")
		(net "PSU4_REMOTE_R_P")
	)
	(segment
		(start 40.423592 -256.388616)
		(end 41.02608 -255.786128)
		(width 0.4572)
		(layer "In5.Cu")
		(net "PSU4_REMOTE_R_P")
	)
	(segment
		(start 19.417284 -257.047492)
		(end 21.09216 -255.372616)
		(width 0.4572)
		(layer "In5.Cu")
		(net "PSU4_REMOTE_R_P")
	)
	(segment
		(start 29.233876 -256.388616)
		(end 40.423592 -256.388616)
		(width 0.4572)
		(layer "In5.Cu")
		(net "PSU4_REMOTE_R_P")
	)
	(segment
		(start 41.02608 -255.786128)
		(end 44.196 -255.786128)
		(width 0.4572)
		(layer "In5.Cu")
		(net "PSU4_REMOTE_R_P")
	)
	(segment
		(start 27.577542 -377.095004)
		(end 28.833572 -378.351034)
		(width 0.4572)
		(layer "F.Cu")
		(net "PSU5_REMOTE_R_N")
	)
	(segment
		(start 45.511466 -260.355588)
		(end 44.938188 -260.355588)
		(width 0.4572)
		(layer "F.Cu")
		(net "PSU5_REMOTE_R_N")
	)
	(segment
		(start 27.577542 -374.232678)
		(end 27.577542 -377.095004)
		(width 0.4572)
		(layer "F.Cu")
		(net "PSU5_REMOTE_R_N")
	)
	(segment
		(start 44.938188 -260.355588)
		(end 44.677838 -260.095238)
		(width 0.4572)
		(layer "F.Cu")
		(net "PSU5_REMOTE_R_N")
	)
	(via
		(at 44.677838 -260.095238)
		(size 0.508)
		(drill 0.254)
		(layers "F.Cu" "B.Cu")
		(net "PSU5_REMOTE_R_N")
	)
	(via
		(at 28.833572 -378.351034)
		(size 0.508)
		(drill 0.254)
		(layers "F.Cu" "B.Cu")
		(net "PSU5_REMOTE_R_N")
	)
	(segment
		(start 38.279324 -276.396704)
		(end 43.001692 -281.119072)
		(width 0.4572)
		(layer "B.Cu")
		(net "PSU5_REMOTE_R_N")
	)
	(segment
		(start 40.520874 -260.7056)
		(end 38.279324 -262.94715)
		(width 0.4572)
		(layer "B.Cu")
		(net "PSU5_REMOTE_R_N")
	)
	(segment
		(start 38.279324 -262.94715)
		(end 38.279324 -276.396704)
		(width 0.4572)
		(layer "B.Cu")
		(net "PSU5_REMOTE_R_N")
	)
	(segment
		(start 28.090114 -293.186866)
		(end 28.090114 -351.007172)
		(width 0.4572)
		(layer "B.Cu")
		(net "PSU5_REMOTE_R_N")
	)
	(segment
		(start 43.001692 -287.130236)
		(end 38.747192 -291.384736)
		(width 0.4572)
		(layer "B.Cu")
		(net "PSU5_REMOTE_R_N")
	)
	(segment
		(start 38.747192 -291.384736)
		(end 29.892244 -291.384736)
		(width 0.4572)
		(layer "B.Cu")
		(net "PSU5_REMOTE_R_N")
	)
	(segment
		(start 37.435536 -354.970334)
		(end 38.719252 -356.25405)
		(width 0.4572)
		(layer "B.Cu")
		(net "PSU5_REMOTE_R_N")
	)
	(segment
		(start 31.622746 -354.539804)
		(end 31.623 -354.539804)
		(width 0.4572)
		(layer "B.Cu")
		(net "PSU5_REMOTE_R_N")
	)
	(segment
		(start 38.719252 -374.670828)
		(end 36.203382 -377.186698)
		(width 0.4572)
		(layer "B.Cu")
		(net "PSU5_REMOTE_R_N")
	)
	(segment
		(start 28.090114 -351.007172)
		(end 31.622746 -354.539804)
		(width 0.4572)
		(layer "B.Cu")
		(net "PSU5_REMOTE_R_N")
	)
	(segment
		(start 38.719252 -356.25405)
		(end 38.719252 -374.670828)
		(width 0.4572)
		(layer "B.Cu")
		(net "PSU5_REMOTE_R_N")
	)
	(segment
		(start 36.203382 -377.186698)
		(end 29.997908 -377.186698)
		(width 0.4572)
		(layer "B.Cu")
		(net "PSU5_REMOTE_R_N")
	)
	(segment
		(start 29.892244 -291.384736)
		(end 28.090114 -293.186866)
		(width 0.4572)
		(layer "B.Cu")
		(net "PSU5_REMOTE_R_N")
	)
	(segment
		(start 31.623 -354.539804)
		(end 32.05353 -354.970334)
		(width 0.4572)
		(layer "B.Cu")
		(net "PSU5_REMOTE_R_N")
	)
	(segment
		(start 32.05353 -354.970334)
		(end 37.435536 -354.970334)
		(width 0.4572)
		(layer "B.Cu")
		(net "PSU5_REMOTE_R_N")
	)
	(segment
		(start 44.677838 -260.095238)
		(end 44.067476 -260.7056)
		(width 0.4572)
		(layer "B.Cu")
		(net "PSU5_REMOTE_R_N")
	)
	(segment
		(start 29.997908 -377.186698)
		(end 28.833572 -378.351034)
		(width 0.4572)
		(layer "B.Cu")
		(net "PSU5_REMOTE_R_N")
	)
	(segment
		(start 43.001692 -281.119072)
		(end 43.001692 -287.130236)
		(width 0.4572)
		(layer "B.Cu")
		(net "PSU5_REMOTE_R_N")
	)
	(segment
		(start 44.067476 -260.7056)
		(end 40.520874 -260.7056)
		(width 0.4572)
		(layer "B.Cu")
		(net "PSU5_REMOTE_R_N")
	)
	(segment
		(start 44.862496 -261.76986)
		(end 44.563792 -262.068564)
		(width 0.4572)
		(layer "F.Cu")
		(net "PSU5_REMOTE_R_P")
	)
	(segment
		(start 44.868846 -261.777988)
		(end 44.862496 -261.771638)
		(width 0.4572)
		(layer "F.Cu")
		(net "PSU5_REMOTE_R_P")
	)
	(segment
		(start 44.862496 -261.771638)
		(end 44.862496 -261.76986)
		(width 0.4572)
		(layer "F.Cu")
		(net "PSU5_REMOTE_R_P")
	)
	(segment
		(start 39.581836 -376.789696)
		(end 40.519604 -376.792236)
		(width 0.4572)
		(layer "F.Cu")
		(net "PSU5_REMOTE_R_P")
	)
	(segment
		(start 45.510958 -261.777988)
		(end 44.868846 -261.777988)
		(width 0.4572)
		(layer "F.Cu")
		(net "PSU5_REMOTE_R_P")
	)
	(via
		(at 40.519604 -376.792236)
		(size 0.508)
		(drill 0.254)
		(layers "F.Cu" "B.Cu")
		(net "PSU5_REMOTE_R_P")
	)
	(via
		(at 44.563792 -262.068564)
		(size 0.508)
		(drill 0.254)
		(layers "F.Cu" "B.Cu")
		(net "PSU5_REMOTE_R_P")
	)
	(segment
		(start 39.49446 -375.767092)
		(end 40.519604 -376.792236)
		(width 0.4572)
		(layer "B.Cu")
		(net "PSU5_REMOTE_R_P")
	)
	(segment
		(start 32.133032 -354.029518)
		(end 37.895276 -354.029518)
		(width 0.4572)
		(layer "B.Cu")
		(net "PSU5_REMOTE_R_P")
	)
	(segment
		(start 29.88183 -293.885874)
		(end 28.811728 -294.955976)
		(width 0.4572)
		(layer "B.Cu")
		(net "PSU5_REMOTE_R_P")
	)
	(segment
		(start 28.811728 -350.708214)
		(end 32.133032 -354.029518)
		(width 0.4572)
		(layer "B.Cu")
		(net "PSU5_REMOTE_R_P")
	)
	(segment
		(start 28.811728 -294.955976)
		(end 28.811728 -350.708214)
		(width 0.4572)
		(layer "B.Cu")
		(net "PSU5_REMOTE_R_P")
	)
	(segment
		(start 40.842184 -261.480808)
		(end 39.054532 -263.26846)
		(width 0.4572)
		(layer "B.Cu")
		(net "PSU5_REMOTE_R_P")
	)
	(segment
		(start 44.563792 -262.068564)
		(end 43.976036 -261.480808)
		(width 0.4572)
		(layer "B.Cu")
		(net "PSU5_REMOTE_R_P")
	)
	(segment
		(start 39.054532 -263.26846)
		(end 39.054532 -276.075394)
		(width 0.4572)
		(layer "B.Cu")
		(net "PSU5_REMOTE_R_P")
	)
	(segment
		(start 39.49446 -355.628702)
		(end 39.49446 -375.767092)
		(width 0.4572)
		(layer "B.Cu")
		(net "PSU5_REMOTE_R_P")
	)
	(segment
		(start 43.7769 -280.797762)
		(end 43.7769 -287.451546)
		(width 0.4572)
		(layer "B.Cu")
		(net "PSU5_REMOTE_R_P")
	)
	(segment
		(start 43.7769 -287.451546)
		(end 37.342572 -293.885874)
		(width 0.4572)
		(layer "B.Cu")
		(net "PSU5_REMOTE_R_P")
	)
	(segment
		(start 37.895276 -354.029518)
		(end 39.49446 -355.628702)
		(width 0.4572)
		(layer "B.Cu")
		(net "PSU5_REMOTE_R_P")
	)
	(segment
		(start 39.054532 -276.075394)
		(end 43.7769 -280.797762)
		(width 0.4572)
		(layer "B.Cu")
		(net "PSU5_REMOTE_R_P")
	)
	(segment
		(start 43.976036 -261.480808)
		(end 40.842184 -261.480808)
		(width 0.4572)
		(layer "B.Cu")
		(net "PSU5_REMOTE_R_P")
	)
	(segment
		(start 37.342572 -293.885874)
		(end 29.88183 -293.885874)
		(width 0.4572)
		(layer "B.Cu")
		(net "PSU5_REMOTE_R_P")
	)
	(segment
		(start 29.245306 -451.669912)
		(end 30.45968 -451.669912)
		(width 0.1524)
		(layer "F.Cu")
		(net "PSU6_PS_KILL")
	)
	(segment
		(start 27.272234 -452.257668)
		(end 27.272742 -452.258176)
		(width 0.1524)
		(layer "F.Cu")
		(net "PSU6_PS_KILL")
	)
	(segment
		(start 26.626058 -450.980556)
		(end 26.626058 -452.257668)
		(width 0.1524)
		(layer "F.Cu")
		(net "PSU6_PS_KILL")
	)
	(segment
		(start 26.626058 -453.535034)
		(end 26.626058 -452.257668)
		(width 0.1524)
		(layer "F.Cu")
		(net "PSU6_PS_KILL")
	)
	(segment
		(start 26.626058 -452.257668)
		(end 27.272234 -452.257668)
		(width 0.1524)
		(layer "F.Cu")
		(net "PSU6_PS_KILL")
	)
	(segment
		(start 27.272742 -452.258176)
		(end 28.657042 -452.258176)
		(width 0.1524)
		(layer "F.Cu")
		(net "PSU6_PS_KILL")
	)
	(segment
		(start 28.657042 -452.258176)
		(end 29.245306 -451.669912)
		(width 0.1524)
		(layer "F.Cu")
		(net "PSU6_PS_KILL")
	)
	(via
		(at 27.272742 -452.258176)
		(size 0.508)
		(drill 0.254)
		(layers "F.Cu" "B.Cu")
		(net "PSU6_PS_KILL")
	)
	(segment
		(start 26.626058 -448.493388)
		(end 26.626058 -447.250058)
		(width 0.1524)
		(layer "F.Cu")
		(net "PSU6_RESET")
	)
	(segment
		(start 26.626058 -449.713858)
		(end 27.24531 -449.713858)
		(width 0.1524)
		(layer "F.Cu")
		(net "PSU6_RESET")
	)
	(segment
		(start 27.24531 -449.713858)
		(end 27.26817 -449.690998)
		(width 0.1524)
		(layer "F.Cu")
		(net "PSU6_RESET")
	)
	(segment
		(start 27.26817 -449.690998)
		(end 29.898594 -449.690998)
		(width 0.1524)
		(layer "F.Cu")
		(net "PSU6_RESET")
	)
	(segment
		(start 29.898594 -449.690998)
		(end 30.45968 -449.129912)
		(width 0.1524)
		(layer "F.Cu")
		(net "PSU6_RESET")
	)
	(segment
		(start 26.626058 -449.713858)
		(end 26.626058 -448.493388)
		(width 0.1524)
		(layer "F.Cu")
		(net "PSU6_RESET")
	)
	(via
		(at 27.26817 -449.690998)
		(size 0.508)
		(drill 0.254)
		(layers "F.Cu" "B.Cu")
		(net "PSU6_RESET")
	)
	(segment
		(start 30.045152 -360.550968)
		(end 30.224222 -360.730038)
		(width 0.1524)
		(layer "F.Cu")
		(net "PSU5_RESET")
	)
	(segment
		(start 27.157934 -360.550968)
		(end 30.045152 -360.550968)
		(width 0.1524)
		(layer "F.Cu")
		(net "PSU5_RESET")
	)
	(segment
		(start 30.224222 -360.730038)
		(end 30.45968 -360.730038)
		(width 0.1524)
		(layer "F.Cu")
		(net "PSU5_RESET")
	)
	(segment
		(start 26.257758 -363.01553)
		(end 26.257758 -361.78236)
		(width 0.1524)
		(layer "F.Cu")
		(net "PSU5_RESET")
	)
	(segment
		(start 26.257758 -361.78236)
		(end 26.257758 -360.550968)
		(width 0.1524)
		(layer "F.Cu")
		(net "PSU5_RESET")
	)
	(segment
		(start 26.257758 -360.550968)
		(end 27.157934 -360.550968)
		(width 0.1524)
		(layer "F.Cu")
		(net "PSU5_RESET")
	)
	(via
		(at 27.157934 -360.550968)
		(size 0.508)
		(drill 0.254)
		(layers "F.Cu" "B.Cu")
		(net "PSU5_RESET")
	)
	(segment
		(start 27.168348 -364.246414)
		(end 26.257758 -364.246414)
		(width 0.1524)
		(layer "F.Cu")
		(net "PSU5_PS_KILL")
	)
	(segment
		(start 29.483304 -364.246414)
		(end 27.168348 -364.246414)
		(width 0.1524)
		(layer "F.Cu")
		(net "PSU5_PS_KILL")
	)
	(segment
		(start 26.257758 -366.710722)
		(end 26.257758 -365.50092)
		(width 0.1524)
		(layer "F.Cu")
		(net "PSU5_PS_KILL")
	)
	(segment
		(start 26.257758 -365.50092)
		(end 26.257758 -364.246414)
		(width 0.1524)
		(layer "F.Cu")
		(net "PSU5_PS_KILL")
	)
	(segment
		(start 30.45968 -363.270038)
		(end 29.483304 -364.246414)
		(width 0.1524)
		(layer "F.Cu")
		(net "PSU5_PS_KILL")
	)
	(via
		(at 27.168348 -364.246414)
		(size 0.508)
		(drill 0.254)
		(layers "F.Cu" "B.Cu")
		(net "PSU5_PS_KILL")
	)
	(segment
		(start 27.32913 -272.32991)
		(end 30.45968 -272.32991)
		(width 0.1524)
		(layer "F.Cu")
		(net "PSU4_RESET")
	)
	(segment
		(start 27.318208 -272.340832)
		(end 26.502106 -272.345404)
		(width 0.1524)
		(layer "F.Cu")
		(net "PSU4_RESET")
	)
	(segment
		(start 26.502106 -273.532854)
		(end 26.502106 -272.345404)
		(width 0.1524)
		(layer "F.Cu")
		(net "PSU4_RESET")
	)
	(segment
		(start 26.502106 -272.345404)
		(end 26.502106 -271.14881)
		(width 0.1524)
		(layer "F.Cu")
		(net "PSU4_RESET")
	)
	(segment
		(start 27.23261 -272.340832)
		(end 27.318208 -272.340832)
		(width 0.1524)
		(layer "F.Cu")
		(net "PSU4_RESET")
	)
	(segment
		(start 27.318208 -272.340832)
		(end 27.32913 -272.32991)
		(width 0.1524)
		(layer "F.Cu")
		(net "PSU4_RESET")
	)
	(via
		(at 27.23261 -272.340832)
		(size 0.508)
		(drill 0.254)
		(layers "F.Cu" "B.Cu")
		(net "PSU4_RESET")
	)
	(segment
		(start 29.392118 -274.86991)
		(end 30.45968 -274.86991)
		(width 0.1524)
		(layer "F.Cu")
		(net "PSU4_PS_KILL")
	)
	(segment
		(start 26.502106 -274.774914)
		(end 27.23769 -274.770342)
		(width 0.1524)
		(layer "F.Cu")
		(net "PSU4_PS_KILL")
	)
	(segment
		(start 26.502106 -277.377144)
		(end 26.502106 -276.12213)
		(width 0.1524)
		(layer "F.Cu")
		(net "PSU4_PS_KILL")
	)
	(segment
		(start 27.23769 -274.774914)
		(end 27.244294 -274.76831)
		(width 0.1524)
		(layer "F.Cu")
		(net "PSU4_PS_KILL")
	)
	(segment
		(start 27.244294 -274.76831)
		(end 29.290518 -274.76831)
		(width 0.1524)
		(layer "F.Cu")
		(net "PSU4_PS_KILL")
	)
	(segment
		(start 29.290518 -274.76831)
		(end 29.392118 -274.86991)
		(width 0.1524)
		(layer "F.Cu")
		(net "PSU4_PS_KILL")
	)
	(segment
		(start 27.23769 -274.770342)
		(end 27.23769 -274.774914)
		(width 0.1524)
		(layer "F.Cu")
		(net "PSU4_PS_KILL")
	)
	(segment
		(start 26.502106 -276.12213)
		(end 26.502106 -274.774914)
		(width 0.1524)
		(layer "F.Cu")
		(net "PSU4_PS_KILL")
	)
	(via
		(at 27.23769 -274.774914)
		(size 0.508)
		(drill 0.254)
		(layers "F.Cu" "B.Cu")
		(net "PSU4_PS_KILL")
	)
	(segment
		(start 28.792424 -186.745626)
		(end 27.221942 -186.745626)
		(width 0.1524)
		(layer "F.Cu")
		(net "PSU3_PS_KILL")
	)
	(segment
		(start 29.068014 -186.470036)
		(end 28.792424 -186.745626)
		(width 0.1524)
		(layer "F.Cu")
		(net "PSU3_PS_KILL")
	)
	(segment
		(start 27.214576 -186.752992)
		(end 27.221942 -186.745626)
		(width 0.1524)
		(layer "F.Cu")
		(net "PSU3_PS_KILL")
	)
	(segment
		(start 26.468324 -186.752992)
		(end 27.214576 -186.752992)
		(width 0.1524)
		(layer "F.Cu")
		(net "PSU3_PS_KILL")
	)
	(segment
		(start 26.468324 -186.752992)
		(end 26.468324 -187.950348)
		(width 0.1524)
		(layer "F.Cu")
		(net "PSU3_PS_KILL")
	)
	(segment
		(start 30.45968 -186.470036)
		(end 29.068014 -186.470036)
		(width 0.1524)
		(layer "F.Cu")
		(net "PSU3_PS_KILL")
	)
	(segment
		(start 26.468324 -185.521092)
		(end 26.468324 -186.752992)
		(width 0.1524)
		(layer "F.Cu")
		(net "PSU3_PS_KILL")
	)
	(via
		(at 27.221942 -186.745626)
		(size 0.508)
		(drill 0.254)
		(layers "F.Cu" "B.Cu")
		(net "PSU3_PS_KILL")
	)
	(segment
		(start 29.092144 -183.930036)
		(end 28.778708 -184.243472)
		(width 0.1524)
		(layer "F.Cu")
		(net "PSU3_RESET")
	)
	(segment
		(start 28.778708 -184.243472)
		(end 27.18435 -184.243472)
		(width 0.1524)
		(layer "F.Cu")
		(net "PSU3_RESET")
	)
	(segment
		(start 26.468324 -183.06923)
		(end 26.468324 -181.847998)
		(width 0.1524)
		(layer "F.Cu")
		(net "PSU3_RESET")
	)
	(segment
		(start 30.45968 -183.930036)
		(end 29.092144 -183.930036)
		(width 0.1524)
		(layer "F.Cu")
		(net "PSU3_RESET")
	)
	(segment
		(start 26.468324 -184.266078)
		(end 27.161744 -184.266078)
		(width 0.1524)
		(layer "F.Cu")
		(net "PSU3_RESET")
	)
	(segment
		(start 26.468324 -184.266078)
		(end 26.468324 -183.06923)
		(width 0.1524)
		(layer "F.Cu")
		(net "PSU3_RESET")
	)
	(segment
		(start 27.161744 -184.266078)
		(end 27.18435 -184.243472)
		(width 0.1524)
		(layer "F.Cu")
		(net "PSU3_RESET")
	)
	(via
		(at 27.18435 -184.243472)
		(size 0.508)
		(drill 0.254)
		(layers "F.Cu" "B.Cu")
		(net "PSU3_RESET")
	)
	(segment
		(start 29.159962 -99.369626)
		(end 30.45968 -98.069908)
		(width 0.1524)
		(layer "F.Cu")
		(net "PSU2_PS_KILL")
	)
	(segment
		(start 27.104086 -99.369626)
		(end 29.159962 -99.369626)
		(width 0.1524)
		(layer "F.Cu")
		(net "PSU2_PS_KILL")
	)
	(segment
		(start 27.103832 -99.36988)
		(end 27.104086 -99.369626)
		(width 0.1524)
		(layer "F.Cu")
		(net "PSU2_PS_KILL")
	)
	(segment
		(start 26.331672 -99.36988)
		(end 26.331672 -98.10369)
		(width 0.1524)
		(layer "F.Cu")
		(net "PSU2_PS_KILL")
	)
	(segment
		(start 26.331672 -100.590096)
		(end 26.331672 -99.36988)
		(width 0.1524)
		(layer "F.Cu")
		(net "PSU2_PS_KILL")
	)
	(segment
		(start 26.331672 -99.36988)
		(end 27.103832 -99.36988)
		(width 0.1524)
		(layer "F.Cu")
		(net "PSU2_PS_KILL")
	)
	(via
		(at 27.104086 -99.369626)
		(size 0.508)
		(drill 0.254)
		(layers "F.Cu" "B.Cu")
		(net "PSU2_PS_KILL")
	)
	(segment
		(start 27.136344 -95.621094)
		(end 27.106118 -95.65132)
		(width 0.1524)
		(layer "F.Cu")
		(net "PSU2_RESET")
	)
	(segment
		(start 27.136344 -95.621094)
		(end 27.22753 -95.529908)
		(width 0.1524)
		(layer "F.Cu")
		(net "PSU2_RESET")
	)
	(segment
		(start 26.331672 -95.65132)
		(end 26.331672 -94.464886)
		(width 0.1524)
		(layer "F.Cu")
		(net "PSU2_RESET")
	)
	(segment
		(start 27.22753 -95.529908)
		(end 30.45968 -95.529908)
		(width 0.1524)
		(layer "F.Cu")
		(net "PSU2_RESET")
	)
	(segment
		(start 27.106118 -95.65132)
		(end 26.331672 -95.65132)
		(width 0.1524)
		(layer "F.Cu")
		(net "PSU2_RESET")
	)
	(segment
		(start 26.331672 -96.872044)
		(end 26.331672 -95.65132)
		(width 0.1524)
		(layer "F.Cu")
		(net "PSU2_RESET")
	)
	(via
		(at 27.136344 -95.621094)
		(size 0.508)
		(drill 0.254)
		(layers "F.Cu" "B.Cu")
		(net "PSU2_RESET")
	)
	(segment
		(start 27.620976 -7.130034)
		(end 27.167332 -6.67639)
		(width 0.1524)
		(layer "F.Cu")
		(net "PSU1_RESET")
	)
	(segment
		(start 26.638504 -6.147562)
		(end 27.167332 -6.67639)
		(width 0.1524)
		(layer "F.Cu")
		(net "PSU1_RESET")
	)
	(segment
		(start 27.68473 -5.10032)
		(end 27.68473 -6.158992)
		(width 0.1524)
		(layer "F.Cu")
		(net "PSU1_RESET")
	)
	(segment
		(start 26.376122 -6.147562)
		(end 26.638504 -6.147562)
		(width 0.1524)
		(layer "F.Cu")
		(net "PSU1_RESET")
	)
	(segment
		(start 30.45968 -7.130034)
		(end 27.620976 -7.130034)
		(width 0.1524)
		(layer "F.Cu")
		(net "PSU1_RESET")
	)
	(segment
		(start 27.68473 -6.158992)
		(end 27.167332 -6.67639)
		(width 0.1524)
		(layer "F.Cu")
		(net "PSU1_RESET")
	)
	(segment
		(start 27.68473 -4.025138)
		(end 27.68473 -5.10032)
		(width 0.1524)
		(layer "F.Cu")
		(net "PSU1_RESET")
	)
	(via
		(at 27.167332 -6.67639)
		(size 0.508)
		(drill 0.254)
		(layers "F.Cu" "B.Cu")
		(net "PSU1_RESET")
	)
	(segment
		(start 30.45968 -9.670034)
		(end 28.046934 -9.670034)
		(width 0.1524)
		(layer "F.Cu")
		(net "PSU1_PS_KILL")
	)
	(segment
		(start 26.721562 -8.344662)
		(end 27.187398 -8.810498)
		(width 0.1524)
		(layer "F.Cu")
		(net "PSU1_PS_KILL")
	)
	(segment
		(start 26.397712 -7.19328)
		(end 26.397712 -8.344662)
		(width 0.1524)
		(layer "F.Cu")
		(net "PSU1_PS_KILL")
	)
	(segment
		(start 28.046934 -9.670034)
		(end 27.187398 -8.810498)
		(width 0.1524)
		(layer "F.Cu")
		(net "PSU1_PS_KILL")
	)
	(segment
		(start 26.397712 -8.344662)
		(end 26.721562 -8.344662)
		(width 0.1524)
		(layer "F.Cu")
		(net "PSU1_PS_KILL")
	)
	(segment
		(start 26.397712 -9.509252)
		(end 26.397712 -8.344662)
		(width 0.1524)
		(layer "F.Cu")
		(net "PSU1_PS_KILL")
	)
	(via
		(at 27.187398 -8.810498)
		(size 0.508)
		(drill 0.254)
		(layers "F.Cu" "B.Cu")
		(net "PSU1_PS_KILL")
	)
	(segment
		(start 33.06953 -267.37564)
		(end 33.06953 -281.850846)
		(width 0.1524)
		(layer "F.Cu")
		(net "MATE_A1")
	)
	(segment
		(start 9.83234 -345.72321)
		(end 11.067034 -344.488516)
		(width 0.1524)
		(layer "F.Cu")
		(net "MATE_A1")
	)
	(segment
		(start 29.219906 -282.92044)
		(end 27.856942 -282.92044)
		(width 0.1524)
		(layer "F.Cu")
		(net "MATE_A1")
	)
	(segment
		(start 28.317444 -309.64378)
		(end 28.317444 -288.791142)
		(width 0.1524)
		(layer "F.Cu")
		(net "MATE_A1")
	)
	(segment
		(start 22.179026 -197.9676)
		(end 26.97099 -202.759564)
		(width 0.1524)
		(layer "F.Cu")
		(net "MATE_A1")
	)
	(segment
		(start 26.854404 -339.649308)
		(end 26.854404 -311.10682)
		(width 0.1524)
		(layer "F.Cu")
		(net "MATE_A1")
	)
	(segment
		(start 21.085302 -344.488516)
		(end 24.246332 -341.327486)
		(width 0.1524)
		(layer "F.Cu")
		(net "MATE_A1")
	)
	(segment
		(start 25.45461 -237.918498)
		(end 25.45461 -247.784874)
		(width 0.1524)
		(layer "F.Cu")
		(net "MATE_A1")
	)
	(segment
		(start 7.629398 -179.584096)
		(end 17.53489 -179.584096)
		(width 0.1524)
		(layer "F.Cu")
		(net "MATE_A1")
	)
	(segment
		(start 9.83234 -351.780348)
		(end 9.83234 -345.72321)
		(width 0.1524)
		(layer "F.Cu")
		(net "MATE_A1")
	)
	(segment
		(start 11.067034 -344.488516)
		(end 21.085302 -344.488516)
		(width 0.1524)
		(layer "F.Cu")
		(net "MATE_A1")
	)
	(segment
		(start 25.176226 -341.327486)
		(end 26.854404 -339.649308)
		(width 0.1524)
		(layer "F.Cu")
		(net "MATE_A1")
	)
	(segment
		(start 31.296864 -283.623512)
		(end 29.922978 -283.623512)
		(width 0.1524)
		(layer "F.Cu")
		(net "MATE_A1")
	)
	(segment
		(start 27.856942 -282.92044)
		(end 26.708608 -284.068774)
		(width 0.1524)
		(layer "F.Cu")
		(net "MATE_A1")
	)
	(segment
		(start 22.179026 -184.228232)
		(end 22.179026 -197.9676)
		(width 0.1524)
		(layer "F.Cu")
		(net "MATE_A1")
	)
	(segment
		(start 26.854404 -311.10682)
		(end 28.317444 -309.64378)
		(width 0.1524)
		(layer "F.Cu")
		(net "MATE_A1")
	)
	(segment
		(start 26.97099 -236.402118)
		(end 25.45461 -237.918498)
		(width 0.1524)
		(layer "F.Cu")
		(net "MATE_A1")
	)
	(segment
		(start 33.06953 -281.850846)
		(end 31.296864 -283.623512)
		(width 0.1524)
		(layer "F.Cu")
		(net "MATE_A1")
	)
	(segment
		(start 6.449822 -352.669856)
		(end 8.942832 -352.669856)
		(width 0.1524)
		(layer "F.Cu")
		(net "MATE_A1")
	)
	(segment
		(start 27.418284 -261.724394)
		(end 33.06953 -267.37564)
		(width 0.1524)
		(layer "F.Cu")
		(net "MATE_A1")
	)
	(segment
		(start 25.45461 -247.784874)
		(end 27.418284 -249.748548)
		(width 0.1524)
		(layer "F.Cu")
		(net "MATE_A1")
	)
	(segment
		(start 29.922978 -283.623512)
		(end 29.219906 -282.92044)
		(width 0.1524)
		(layer "F.Cu")
		(net "MATE_A1")
	)
	(segment
		(start 28.317444 -288.791142)
		(end 26.142696 -286.616394)
		(width 0.1524)
		(layer "F.Cu")
		(net "MATE_A1")
	)
	(segment
		(start 6.799326 -180.414168)
		(end 7.629398 -179.584096)
		(width 0.1524)
		(layer "F.Cu")
		(net "MATE_A1")
	)
	(segment
		(start 26.142696 -284.634686)
		(end 26.708608 -284.068774)
		(width 0.1524)
		(layer "F.Cu")
		(net "MATE_A1")
	)
	(segment
		(start 3.948938 -179.670456)
		(end 4.69265 -180.414168)
		(width 0.1524)
		(layer "F.Cu")
		(net "MATE_A1")
	)
	(segment
		(start 27.418284 -249.748548)
		(end 27.418284 -261.724394)
		(width 0.1524)
		(layer "F.Cu")
		(net "MATE_A1")
	)
	(segment
		(start 8.942832 -352.669856)
		(end 9.83234 -351.780348)
		(width 0.1524)
		(layer "F.Cu")
		(net "MATE_A1")
	)
	(segment
		(start 17.53489 -179.584096)
		(end 22.179026 -184.228232)
		(width 0.1524)
		(layer "F.Cu")
		(net "MATE_A1")
	)
	(segment
		(start 26.97099 -202.759564)
		(end 26.97099 -236.402118)
		(width 0.1524)
		(layer "F.Cu")
		(net "MATE_A1")
	)
	(segment
		(start 4.69265 -180.414168)
		(end 6.799326 -180.414168)
		(width 0.1524)
		(layer "F.Cu")
		(net "MATE_A1")
	)
	(segment
		(start 24.246332 -341.327486)
		(end 25.176226 -341.327486)
		(width 0.1524)
		(layer "F.Cu")
		(net "MATE_A1")
	)
	(segment
		(start 26.142696 -286.616394)
		(end 26.142696 -284.634686)
		(width 0.1524)
		(layer "F.Cu")
		(net "MATE_A1")
	)
	(via
		(at 26.708608 -284.068774)
		(size 0.508)
		(drill 0.254)
		(layers "F.Cu" "B.Cu")
		(net "MATE_A1")
	)
	(via
		(at 23.964138 -107.076748)
		(size 0.508)
		(drill 0.254)
		(layers "F.Cu" "B.Cu")
		(net "PSU2_DC_OK")
	)
	(segment
		(start 8.448802 -214.67064)
		(end 7.670546 -213.892384)
		(width 0.127)
		(layer "In2.Cu")
		(net "PSU2_DC_OK")
	)
	(segment
		(start 15.099792 -197.296024)
		(end 15.099792 -177.805588)
		(width 0.127)
		(layer "In2.Cu")
		(net "PSU2_DC_OK")
	)
	(segment
		(start 23.865078 -169.040302)
		(end 23.865078 -107.175808)
		(width 0.127)
		(layer "In2.Cu")
		(net "PSU2_DC_OK")
	)
	(segment
		(start 7.670546 -213.892384)
		(end 7.670546 -202.399392)
		(width 0.127)
		(layer "In2.Cu")
		(net "PSU2_DC_OK")
	)
	(segment
		(start 15.099792 -177.805588)
		(end 23.865078 -169.040302)
		(width 0.127)
		(layer "In2.Cu")
		(net "PSU2_DC_OK")
	)
	(segment
		(start 7.670546 -202.399392)
		(end 8.215122 -201.854816)
		(width 0.127)
		(layer "In2.Cu")
		(net "PSU2_DC_OK")
	)
	(segment
		(start 23.865078 -107.175808)
		(end 23.964138 -107.076748)
		(width 0.127)
		(layer "In2.Cu")
		(net "PSU2_DC_OK")
	)
	(segment
		(start 8.215122 -201.854816)
		(end 10.541 -201.854816)
		(width 0.127)
		(layer "In2.Cu")
		(net "PSU2_DC_OK")
	)
	(segment
		(start 10.541 -201.854816)
		(end 15.099792 -197.296024)
		(width 0.127)
		(layer "In2.Cu")
		(net "PSU2_DC_OK")
	)
	(segment
		(start 32.52597 -103.149908)
		(end 35.53968 -103.149908)
		(width 0.127)
		(layer "In5.Cu")
		(net "PSU2_DC_OK")
	)
	(segment
		(start 26.779982 -104.260904)
		(end 31.414974 -104.260904)
		(width 0.127)
		(layer "In5.Cu")
		(net "PSU2_DC_OK")
	)
	(segment
		(start 31.414974 -104.260904)
		(end 32.52597 -103.149908)
		(width 0.127)
		(layer "In5.Cu")
		(net "PSU2_DC_OK")
	)
	(segment
		(start 23.964138 -107.076748)
		(end 26.779982 -104.260904)
		(width 0.127)
		(layer "In5.Cu")
		(net "PSU2_DC_OK")
	)
	(segment
		(start 31.191708 -281.03322)
		(end 32.322262 -279.902666)
		(width 0.1524)
		(layer "F.Cu")
		(net "PSU6_DC_OK")
	)
	(segment
		(start 27.479244 -308.47665)
		(end 27.479244 -289.372294)
		(width 0.1524)
		(layer "F.Cu")
		(net "PSU6_DC_OK")
	)
	(segment
		(start 21.123148 -216.986612)
		(end 17.99971 -216.986612)
		(width 0.1524)
		(layer "F.Cu")
		(net "PSU6_DC_OK")
	)
	(segment
		(start 28.217368 -281.03322)
		(end 31.191708 -281.03322)
		(width 0.1524)
		(layer "F.Cu")
		(net "PSU6_DC_OK")
	)
	(segment
		(start 25.388316 -283.862272)
		(end 28.217368 -281.03322)
		(width 0.1524)
		(layer "F.Cu")
		(net "PSU6_DC_OK")
	)
	(segment
		(start 32.322262 -279.902666)
		(end 32.322262 -268.113764)
		(width 0.1524)
		(layer "F.Cu")
		(net "PSU6_DC_OK")
	)
	(segment
		(start 25.388316 -287.281366)
		(end 25.388316 -283.862272)
		(width 0.1524)
		(layer "F.Cu")
		(net "PSU6_DC_OK")
	)
	(segment
		(start 26.504646 -250.00839)
		(end 24.404828 -247.908572)
		(width 0.1524)
		(layer "F.Cu")
		(net "PSU6_DC_OK")
	)
	(segment
		(start 24.404828 -247.908572)
		(end 24.404828 -237.295436)
		(width 0.1524)
		(layer "F.Cu")
		(net "PSU6_DC_OK")
	)
	(segment
		(start 26.504646 -262.296148)
		(end 26.504646 -250.00839)
		(width 0.1524)
		(layer "F.Cu")
		(net "PSU6_DC_OK")
	)
	(segment
		(start 24.404828 -237.295436)
		(end 25.927304 -235.77296)
		(width 0.1524)
		(layer "F.Cu")
		(net "PSU6_DC_OK")
	)
	(segment
		(start 32.322262 -268.113764)
		(end 26.504646 -262.296148)
		(width 0.1524)
		(layer "F.Cu")
		(net "PSU6_DC_OK")
	)
	(segment
		(start 25.927304 -235.77296)
		(end 25.927304 -221.790768)
		(width 0.1524)
		(layer "F.Cu")
		(net "PSU6_DC_OK")
	)
	(segment
		(start 25.927304 -221.790768)
		(end 21.123148 -216.986612)
		(width 0.1524)
		(layer "F.Cu")
		(net "PSU6_DC_OK")
	)
	(segment
		(start 25.582626 -310.373268)
		(end 27.479244 -308.47665)
		(width 0.1524)
		(layer "F.Cu")
		(net "PSU6_DC_OK")
	)
	(segment
		(start 25.582626 -331.92974)
		(end 25.582626 -310.373268)
		(width 0.1524)
		(layer "F.Cu")
		(net "PSU6_DC_OK")
	)
	(segment
		(start 27.479244 -289.372294)
		(end 25.388316 -287.281366)
		(width 0.1524)
		(layer "F.Cu")
		(net "PSU6_DC_OK")
	)
	(via
		(at 17.99971 -216.986612)
		(size 0.508)
		(drill 0.254)
		(layers "F.Cu" "B.Cu")
		(net "PSU6_DC_OK")
	)
	(via
		(at 25.582626 -331.92974)
		(size 0.508)
		(drill 0.254)
		(layers "F.Cu" "B.Cu")
		(net "PSU6_DC_OK")
	)
	(segment
		(start 37.250116 -456.039728)
		(end 36.539932 -456.749912)
		(width 0.1524)
		(layer "B.Cu")
		(net "PSU6_DC_OK")
	)
	(segment
		(start 8.448802 -210.670648)
		(end 14.764766 -216.986612)
		(width 0.1524)
		(layer "B.Cu")
		(net "PSU6_DC_OK")
	)
	(segment
		(start 14.764766 -216.986612)
		(end 17.99971 -216.986612)
		(width 0.1524)
		(layer "B.Cu")
		(net "PSU6_DC_OK")
	)
	(segment
		(start 35.86099 -374.951498)
		(end 29.525214 -374.951498)
		(width 0.1524)
		(layer "B.Cu")
		(net "PSU6_DC_OK")
	)
	(segment
		(start 28.011374 -436.533036)
		(end 37.250116 -445.771778)
		(width 0.1524)
		(layer "B.Cu")
		(net "PSU6_DC_OK")
	)
	(segment
		(start 37.250116 -445.771778)
		(end 37.250116 -456.039728)
		(width 0.1524)
		(layer "B.Cu")
		(net "PSU6_DC_OK")
	)
	(segment
		(start 27.436318 -333.783432)
		(end 27.436318 -351.538032)
		(width 0.1524)
		(layer "B.Cu")
		(net "PSU6_DC_OK")
	)
	(segment
		(start 37.845492 -357.173784)
		(end 37.845492 -372.966996)
		(width 0.1524)
		(layer "B.Cu")
		(net "PSU6_DC_OK")
	)
	(segment
		(start 32.297878 -356.399592)
		(end 37.0713 -356.399592)
		(width 0.1524)
		(layer "B.Cu")
		(net "PSU6_DC_OK")
	)
	(segment
		(start 37.845492 -372.966996)
		(end 35.86099 -374.951498)
		(width 0.1524)
		(layer "B.Cu")
		(net "PSU6_DC_OK")
	)
	(segment
		(start 25.582626 -331.92974)
		(end 27.436318 -333.783432)
		(width 0.1524)
		(layer "B.Cu")
		(net "PSU6_DC_OK")
	)
	(segment
		(start 37.0713 -356.399592)
		(end 37.845492 -357.173784)
		(width 0.1524)
		(layer "B.Cu")
		(net "PSU6_DC_OK")
	)
	(segment
		(start 28.011374 -376.465338)
		(end 28.011374 -436.533036)
		(width 0.1524)
		(layer "B.Cu")
		(net "PSU6_DC_OK")
	)
	(segment
		(start 27.436318 -351.538032)
		(end 32.297878 -356.399592)
		(width 0.1524)
		(layer "B.Cu")
		(net "PSU6_DC_OK")
	)
	(segment
		(start 29.525214 -374.951498)
		(end 28.011374 -376.465338)
		(width 0.1524)
		(layer "B.Cu")
		(net "PSU6_DC_OK")
	)
	(segment
		(start 36.539932 -456.749912)
		(end 35.53968 -456.749912)
		(width 0.1524)
		(layer "B.Cu")
		(net "PSU6_DC_OK")
	)
	(segment
		(start 26.132282 -192.678558)
		(end 24.32685 -190.873126)
		(width 0.1524)
		(layer "F.Cu")
		(net "PSU3_DC_OK")
	)
	(segment
		(start 32.829754 -191.550036)
		(end 31.701232 -192.678558)
		(width 0.1524)
		(layer "F.Cu")
		(net "PSU3_DC_OK")
	)
	(segment
		(start 31.701232 -192.678558)
		(end 26.132282 -192.678558)
		(width 0.1524)
		(layer "F.Cu")
		(net "PSU3_DC_OK")
	)
	(segment
		(start 35.53968 -191.550036)
		(end 32.829754 -191.550036)
		(width 0.1524)
		(layer "F.Cu")
		(net "PSU3_DC_OK")
	)
	(via
		(at 24.32685 -190.873126)
		(size 0.508)
		(drill 0.254)
		(layers "F.Cu" "B.Cu")
		(net "PSU3_DC_OK")
	)
	(segment
		(start 7.99338 -209.793586)
		(end 9.345676 -209.793586)
		(width 0.1524)
		(layer "B.Cu")
		(net "PSU3_DC_OK")
	)
	(segment
		(start 22.184106 -193.01587)
		(end 24.32685 -190.873126)
		(width 0.1524)
		(layer "B.Cu")
		(net "PSU3_DC_OK")
	)
	(segment
		(start 22.184106 -210.561682)
		(end 22.184106 -193.01587)
		(width 0.1524)
		(layer "B.Cu")
		(net "PSU3_DC_OK")
	)
	(segment
		(start 7.269988 -212.84946)
		(end 7.269988 -210.516978)
		(width 0.1524)
		(layer "B.Cu")
		(net "PSU3_DC_OK")
	)
	(segment
		(start 6.448806 -213.670642)
		(end 7.269988 -212.84946)
		(width 0.1524)
		(layer "B.Cu")
		(net "PSU3_DC_OK")
	)
	(segment
		(start 12.340082 -212.787992)
		(end 19.957796 -212.787992)
		(width 0.1524)
		(layer "B.Cu")
		(net "PSU3_DC_OK")
	)
	(segment
		(start 19.957796 -212.787992)
		(end 22.184106 -210.561682)
		(width 0.1524)
		(layer "B.Cu")
		(net "PSU3_DC_OK")
	)
	(segment
		(start 9.345676 -209.793586)
		(end 12.340082 -212.787992)
		(width 0.1524)
		(layer "B.Cu")
		(net "PSU3_DC_OK")
	)
	(segment
		(start 7.269988 -210.516978)
		(end 7.99338 -209.793586)
		(width 0.1524)
		(layer "B.Cu")
		(net "PSU3_DC_OK")
	)
	(segment
		(start 15.070836 -220.61424)
		(end 9.941052 -215.484456)
		(width 0.1524)
		(layer "F.Cu")
		(net "PSU5_DC_OK")
	)
	(segment
		(start 18.35404 -220.61424)
		(end 15.070836 -220.61424)
		(width 0.1524)
		(layer "F.Cu")
		(net "PSU5_DC_OK")
	)
	(segment
		(start 24.586692 -288.103818)
		(end 24.586692 -281.144472)
		(width 0.1524)
		(layer "F.Cu")
		(net "PSU5_DC_OK")
	)
	(segment
		(start 20.006818 -222.267018)
		(end 18.35404 -220.61424)
		(width 0.1524)
		(layer "F.Cu")
		(net "PSU5_DC_OK")
	)
	(segment
		(start 26.527252 -279.203912)
		(end 29.053282 -279.203912)
		(width 0.1524)
		(layer "F.Cu")
		(net "PSU5_DC_OK")
	)
	(segment
		(start 24.520144 -333.915258)
		(end 24.520144 -309.992522)
		(width 0.1524)
		(layer "F.Cu")
		(net "PSU5_DC_OK")
	)
	(segment
		(start 29.604716 -278.652478)
		(end 31.241492 -278.652478)
		(width 0.1524)
		(layer "F.Cu")
		(net "PSU5_DC_OK")
	)
	(segment
		(start 25.364948 -224.166938)
		(end 23.465028 -222.267018)
		(width 0.1524)
		(layer "F.Cu")
		(net "PSU5_DC_OK")
	)
	(segment
		(start 26.077672 -262.64235)
		(end 26.077672 -250.489974)
		(width 0.1524)
		(layer "F.Cu")
		(net "PSU5_DC_OK")
	)
	(segment
		(start 26.768044 -307.744622)
		(end 26.768044 -290.28517)
		(width 0.1524)
		(layer "F.Cu")
		(net "PSU5_DC_OK")
	)
	(segment
		(start 31.241492 -278.652478)
		(end 31.935166 -277.958804)
		(width 0.1524)
		(layer "F.Cu")
		(net "PSU5_DC_OK")
	)
	(segment
		(start 25.582626 -334.97774)
		(end 24.520144 -333.915258)
		(width 0.1524)
		(layer "F.Cu")
		(net "PSU5_DC_OK")
	)
	(segment
		(start 23.465028 -222.267018)
		(end 20.006818 -222.267018)
		(width 0.1524)
		(layer "F.Cu")
		(net "PSU5_DC_OK")
	)
	(segment
		(start 29.053282 -279.203912)
		(end 29.604716 -278.652478)
		(width 0.1524)
		(layer "F.Cu")
		(net "PSU5_DC_OK")
	)
	(segment
		(start 8.184896 -215.484456)
		(end 7.177786 -214.477346)
		(width 0.1524)
		(layer "F.Cu")
		(net "PSU5_DC_OK")
	)
	(segment
		(start 23.622 -236.868462)
		(end 25.364948 -235.125514)
		(width 0.1524)
		(layer "F.Cu")
		(net "PSU5_DC_OK")
	)
	(segment
		(start 26.768044 -290.28517)
		(end 24.586692 -288.103818)
		(width 0.1524)
		(layer "F.Cu")
		(net "PSU5_DC_OK")
	)
	(segment
		(start 31.935166 -268.499844)
		(end 26.077672 -262.64235)
		(width 0.1524)
		(layer "F.Cu")
		(net "PSU5_DC_OK")
	)
	(segment
		(start 25.364948 -235.125514)
		(end 25.364948 -224.166938)
		(width 0.1524)
		(layer "F.Cu")
		(net "PSU5_DC_OK")
	)
	(segment
		(start 24.520144 -309.992522)
		(end 26.768044 -307.744622)
		(width 0.1524)
		(layer "F.Cu")
		(net "PSU5_DC_OK")
	)
	(segment
		(start 7.177786 -212.399626)
		(end 6.448806 -211.670646)
		(width 0.1524)
		(layer "F.Cu")
		(net "PSU5_DC_OK")
	)
	(segment
		(start 31.935166 -277.958804)
		(end 31.935166 -268.499844)
		(width 0.1524)
		(layer "F.Cu")
		(net "PSU5_DC_OK")
	)
	(segment
		(start 26.077672 -250.489974)
		(end 23.622 -248.034302)
		(width 0.1524)
		(layer "F.Cu")
		(net "PSU5_DC_OK")
	)
	(segment
		(start 24.586692 -281.144472)
		(end 26.527252 -279.203912)
		(width 0.1524)
		(layer "F.Cu")
		(net "PSU5_DC_OK")
	)
	(segment
		(start 23.622 -248.034302)
		(end 23.622 -236.868462)
		(width 0.1524)
		(layer "F.Cu")
		(net "PSU5_DC_OK")
	)
	(segment
		(start 9.941052 -215.484456)
		(end 8.184896 -215.484456)
		(width 0.1524)
		(layer "F.Cu")
		(net "PSU5_DC_OK")
	)
	(segment
		(start 7.177786 -214.477346)
		(end 7.177786 -212.399626)
		(width 0.1524)
		(layer "F.Cu")
		(net "PSU5_DC_OK")
	)
	(via
		(at 25.582626 -334.97774)
		(size 0.508)
		(drill 0.254)
		(layers "F.Cu" "B.Cu")
		(net "PSU5_DC_OK")
	)
	(segment
		(start 36.71951 -356.770178)
		(end 37.488114 -357.538782)
		(width 0.1524)
		(layer "B.Cu")
		(net "PSU5_DC_OK")
	)
	(segment
		(start 37.488114 -357.538782)
		(end 37.488114 -366.401604)
		(width 0.1524)
		(layer "B.Cu")
		(net "PSU5_DC_OK")
	)
	(segment
		(start 27.011122 -336.406236)
		(end 27.011122 -351.729802)
		(width 0.1524)
		(layer "B.Cu")
		(net "PSU5_DC_OK")
	)
	(segment
		(start 25.582626 -334.97774)
		(end 27.011122 -336.406236)
		(width 0.1524)
		(layer "B.Cu")
		(net "PSU5_DC_OK")
	)
	(segment
		(start 37.488114 -366.401604)
		(end 35.53968 -368.350038)
		(width 0.1524)
		(layer "B.Cu")
		(net "PSU5_DC_OK")
	)
	(segment
		(start 27.011122 -351.729802)
		(end 32.051498 -356.770178)
		(width 0.1524)
		(layer "B.Cu")
		(net "PSU5_DC_OK")
	)
	(segment
		(start 32.051498 -356.770178)
		(end 36.71951 -356.770178)
		(width 0.1524)
		(layer "B.Cu")
		(net "PSU5_DC_OK")
	)
	(segment
		(start 14.674342 -177.72888)
		(end 23.51151 -168.891712)
		(width 0.127)
		(layer "In2.Cu")
		(net "PSU1_DC_OK")
	)
	(segment
		(start 22.204934 -103.693722)
		(end 22.204934 -91.288362)
		(width 0.127)
		(layer "In2.Cu")
		(net "PSU1_DC_OK")
	)
	(segment
		(start 6.448806 -215.670638)
		(end 7.259066 -214.860378)
		(width 0.127)
		(layer "In2.Cu")
		(net "PSU1_DC_OK")
	)
	(segment
		(start 32.33547 -20.920456)
		(end 33.038288 -20.217638)
		(width 0.127)
		(layer "In2.Cu")
		(net "PSU1_DC_OK")
	)
	(segment
		(start 22.204934 -91.288362)
		(end 24.42591 -89.067386)
		(width 0.127)
		(layer "In2.Cu")
		(net "PSU1_DC_OK")
	)
	(segment
		(start 23.51151 -106.900726)
		(end 24.123142 -106.289094)
		(width 0.127)
		(layer "In2.Cu")
		(net "PSU1_DC_OK")
	)
	(segment
		(start 24.123142 -106.289094)
		(end 24.123142 -105.61193)
		(width 0.127)
		(layer "In2.Cu")
		(net "PSU1_DC_OK")
	)
	(segment
		(start 24.42591 -26.154634)
		(end 29.660088 -20.920456)
		(width 0.127)
		(layer "In2.Cu")
		(net "PSU1_DC_OK")
	)
	(segment
		(start 33.038288 -17.248378)
		(end 35.536632 -14.750034)
		(width 0.127)
		(layer "In2.Cu")
		(net "PSU1_DC_OK")
	)
	(segment
		(start 23.51151 -168.891712)
		(end 23.51151 -106.900726)
		(width 0.127)
		(layer "In2.Cu")
		(net "PSU1_DC_OK")
	)
	(segment
		(start 7.99465 -201.443336)
		(end 10.48512 -201.443336)
		(width 0.127)
		(layer "In2.Cu")
		(net "PSU1_DC_OK")
	)
	(segment
		(start 7.259066 -202.17892)
		(end 7.99465 -201.443336)
		(width 0.127)
		(layer "In2.Cu")
		(net "PSU1_DC_OK")
	)
	(segment
		(start 10.48512 -201.443336)
		(end 14.674342 -197.254114)
		(width 0.127)
		(layer "In2.Cu")
		(net "PSU1_DC_OK")
	)
	(segment
		(start 24.42591 -89.067386)
		(end 24.42591 -26.154634)
		(width 0.127)
		(layer "In2.Cu")
		(net "PSU1_DC_OK")
	)
	(segment
		(start 7.259066 -214.860378)
		(end 7.259066 -202.17892)
		(width 0.127)
		(layer "In2.Cu")
		(net "PSU1_DC_OK")
	)
	(segment
		(start 29.660088 -20.920456)
		(end 32.33547 -20.920456)
		(width 0.127)
		(layer "In2.Cu")
		(net "PSU1_DC_OK")
	)
	(segment
		(start 35.536632 -14.750034)
		(end 35.53968 -14.750034)
		(width 0.127)
		(layer "In2.Cu")
		(net "PSU1_DC_OK")
	)
	(segment
		(start 33.038288 -20.217638)
		(end 33.038288 -17.248378)
		(width 0.127)
		(layer "In2.Cu")
		(net "PSU1_DC_OK")
	)
	(segment
		(start 24.123142 -105.61193)
		(end 22.204934 -103.693722)
		(width 0.127)
		(layer "In2.Cu")
		(net "PSU1_DC_OK")
	)
	(segment
		(start 14.674342 -197.254114)
		(end 14.674342 -177.72888)
		(width 0.127)
		(layer "In2.Cu")
		(net "PSU1_DC_OK")
	)
	(segment
		(start 14.28877 -218.510612)
		(end 8.448802 -212.670644)
		(width 0.1524)
		(layer "F.Cu")
		(net "PSU4_DC_OK")
	)
	(segment
		(start 17.99971 -218.510612)
		(end 14.28877 -218.510612)
		(width 0.1524)
		(layer "F.Cu")
		(net "PSU4_DC_OK")
	)
	(via
		(at 17.99971 -218.510612)
		(size 0.508)
		(drill 0.254)
		(layers "F.Cu" "B.Cu")
		(net "PSU4_DC_OK")
	)
	(segment
		(start 35.53968 -279.94991)
		(end 34.496248 -280.993342)
		(width 0.1524)
		(layer "B.Cu")
		(net "PSU4_DC_OK")
	)
	(segment
		(start 21.33727 -265.312144)
		(end 21.33727 -238.287306)
		(width 0.1524)
		(layer "B.Cu")
		(net "PSU4_DC_OK")
	)
	(segment
		(start 28.79471 -281.57297)
		(end 27.440128 -281.57297)
		(width 0.1524)
		(layer "B.Cu")
		(net "PSU4_DC_OK")
	)
	(segment
		(start 18.78076 -219.291662)
		(end 17.99971 -218.510612)
		(width 0.1524)
		(layer "B.Cu")
		(net "PSU4_DC_OK")
	)
	(segment
		(start 18.78076 -235.730796)
		(end 18.78076 -219.291662)
		(width 0.1524)
		(layer "B.Cu")
		(net "PSU4_DC_OK")
	)
	(segment
		(start 34.496248 -280.993342)
		(end 29.374338 -280.993342)
		(width 0.1524)
		(layer "B.Cu")
		(net "PSU4_DC_OK")
	)
	(segment
		(start 29.374338 -280.993342)
		(end 28.79471 -281.57297)
		(width 0.1524)
		(layer "B.Cu")
		(net "PSU4_DC_OK")
	)
	(segment
		(start 26.47315 -270.448024)
		(end 21.33727 -265.312144)
		(width 0.1524)
		(layer "B.Cu")
		(net "PSU4_DC_OK")
	)
	(segment
		(start 27.440128 -281.57297)
		(end 26.47315 -280.605992)
		(width 0.1524)
		(layer "B.Cu")
		(net "PSU4_DC_OK")
	)
	(segment
		(start 21.33727 -238.287306)
		(end 18.78076 -235.730796)
		(width 0.1524)
		(layer "B.Cu")
		(net "PSU4_DC_OK")
	)
	(segment
		(start 26.47315 -280.605992)
		(end 26.47315 -270.448024)
		(width 0.1524)
		(layer "B.Cu")
		(net "PSU4_DC_OK")
	)
	(segment
		(start 7.693152 -211.318094)
		(end 7.045706 -210.670648)
		(width 0.1524)
		(layer "F.Cu")
		(net "PSU6_AC_OK")
	)
	(segment
		(start 17.97431 -220.060012)
		(end 15.089124 -220.060012)
		(width 0.1524)
		(layer "F.Cu")
		(net "PSU6_AC_OK")
	)
	(segment
		(start 17.99971 -220.034612)
		(end 17.97431 -220.060012)
		(width 0.1524)
		(layer "F.Cu")
		(net "PSU6_AC_OK")
	)
	(segment
		(start 15.089124 -220.060012)
		(end 8.952738 -213.923626)
		(width 0.1524)
		(layer "F.Cu")
		(net "PSU6_AC_OK")
	)
	(segment
		(start 8.566404 -213.923626)
		(end 7.693152 -213.050374)
		(width 0.1524)
		(layer "F.Cu")
		(net "PSU6_AC_OK")
	)
	(segment
		(start 7.045706 -210.670648)
		(end 1.948942 -210.670648)
		(width 0.1524)
		(layer "F.Cu")
		(net "PSU6_AC_OK")
	)
	(segment
		(start 8.952738 -213.923626)
		(end 8.566404 -213.923626)
		(width 0.1524)
		(layer "F.Cu")
		(net "PSU6_AC_OK")
	)
	(segment
		(start 7.693152 -213.050374)
		(end 7.693152 -211.318094)
		(width 0.1524)
		(layer "F.Cu")
		(net "PSU6_AC_OK")
	)
	(via
		(at 17.99971 -220.034612)
		(size 0.508)
		(drill 0.254)
		(layers "F.Cu" "B.Cu")
		(net "PSU6_AC_OK")
	)
	(segment
		(start 23.461726 -378.762768)
		(end 25.573482 -380.874524)
		(width 0.1524)
		(layer "B.Cu")
		(net "PSU6_AC_OK")
	)
	(segment
		(start 17.99971 -220.034612)
		(end 15.889986 -222.144336)
		(width 0.1524)
		(layer "B.Cu")
		(net "PSU6_AC_OK")
	)
	(segment
		(start 26.338022 -442.966602)
		(end 26.338022 -455.877168)
		(width 0.1524)
		(layer "B.Cu")
		(net "PSU6_AC_OK")
	)
	(segment
		(start 17.32534 -277.147782)
		(end 20.793202 -280.615644)
		(width 0.1524)
		(layer "B.Cu")
		(net "PSU6_AC_OK")
	)
	(segment
		(start 25.802844 -289.856672)
		(end 25.802844 -318.802766)
		(width 0.1524)
		(layer "B.Cu")
		(net "PSU6_AC_OK")
	)
	(segment
		(start 17.32534 -254.187706)
		(end 17.32534 -277.147782)
		(width 0.1524)
		(layer "B.Cu")
		(net "PSU6_AC_OK")
	)
	(segment
		(start 25.573482 -442.202062)
		(end 26.338022 -442.966602)
		(width 0.1524)
		(layer "B.Cu")
		(net "PSU6_AC_OK")
	)
	(segment
		(start 27.46375 -457.002896)
		(end 28.172664 -457.002896)
		(width 0.1524)
		(layer "B.Cu")
		(net "PSU6_AC_OK")
	)
	(segment
		(start 23.461726 -359.81259)
		(end 23.461726 -378.762768)
		(width 0.1524)
		(layer "B.Cu")
		(net "PSU6_AC_OK")
	)
	(segment
		(start 26.338022 -455.877168)
		(end 27.46375 -457.002896)
		(width 0.1524)
		(layer "B.Cu")
		(net "PSU6_AC_OK")
	)
	(segment
		(start 21.459444 -357.810308)
		(end 23.461726 -359.81259)
		(width 0.1524)
		(layer "B.Cu")
		(net "PSU6_AC_OK")
	)
	(segment
		(start 20.793202 -280.615644)
		(end 20.793202 -284.84703)
		(width 0.1524)
		(layer "B.Cu")
		(net "PSU6_AC_OK")
	)
	(segment
		(start 15.889986 -252.752352)
		(end 17.32534 -254.187706)
		(width 0.1524)
		(layer "B.Cu")
		(net "PSU6_AC_OK")
	)
	(segment
		(start 20.793202 -284.84703)
		(end 25.802844 -289.856672)
		(width 0.1524)
		(layer "B.Cu")
		(net "PSU6_AC_OK")
	)
	(segment
		(start 25.573482 -380.874524)
		(end 25.573482 -442.202062)
		(width 0.1524)
		(layer "B.Cu")
		(net "PSU6_AC_OK")
	)
	(segment
		(start 21.459444 -323.146166)
		(end 21.459444 -357.810308)
		(width 0.1524)
		(layer "B.Cu")
		(net "PSU6_AC_OK")
	)
	(segment
		(start 25.802844 -318.802766)
		(end 21.459444 -323.146166)
		(width 0.1524)
		(layer "B.Cu")
		(net "PSU6_AC_OK")
	)
	(segment
		(start 28.172664 -457.002896)
		(end 30.45968 -459.289912)
		(width 0.1524)
		(layer "B.Cu")
		(net "PSU6_AC_OK")
	)
	(segment
		(start 15.889986 -222.144336)
		(end 15.889986 -252.752352)
		(width 0.1524)
		(layer "B.Cu")
		(net "PSU6_AC_OK")
	)
	(segment
		(start 10.475722 -217.441272)
		(end 14.450314 -221.415864)
		(width 0.1524)
		(layer "F.Cu")
		(net "PSU3_AC_OK")
	)
	(segment
		(start 7.60349 -217.441272)
		(end 10.475722 -217.441272)
		(width 0.1524)
		(layer "F.Cu")
		(net "PSU3_AC_OK")
	)
	(segment
		(start 5.04952 -214.771224)
		(end 5.04952 -215.880188)
		(width 0.1524)
		(layer "F.Cu")
		(net "PSU3_AC_OK")
	)
	(segment
		(start 16.139668 -221.415864)
		(end 17.892014 -223.16821)
		(width 0.1524)
		(layer "F.Cu")
		(net "PSU3_AC_OK")
	)
	(segment
		(start 14.450314 -221.415864)
		(end 16.139668 -221.415864)
		(width 0.1524)
		(layer "F.Cu")
		(net "PSU3_AC_OK")
	)
	(segment
		(start 5.04952 -215.880188)
		(end 5.956046 -216.786714)
		(width 0.1524)
		(layer "F.Cu")
		(net "PSU3_AC_OK")
	)
	(segment
		(start 6.948932 -216.786714)
		(end 7.60349 -217.441272)
		(width 0.1524)
		(layer "F.Cu")
		(net "PSU3_AC_OK")
	)
	(segment
		(start 3.948938 -213.670642)
		(end 5.04952 -214.771224)
		(width 0.1524)
		(layer "F.Cu")
		(net "PSU3_AC_OK")
	)
	(segment
		(start 5.956046 -216.786714)
		(end 6.948932 -216.786714)
		(width 0.1524)
		(layer "F.Cu")
		(net "PSU3_AC_OK")
	)
	(segment
		(start 17.892014 -223.16821)
		(end 23.039832 -223.16821)
		(width 0.1524)
		(layer "F.Cu")
		(net "PSU3_AC_OK")
	)
	(via
		(at 23.039832 -223.16821)
		(size 0.508)
		(drill 0.254)
		(layers "F.Cu" "B.Cu")
		(net "PSU3_AC_OK")
	)
	(segment
		(start 23.250906 -222.957136)
		(end 23.250906 -200.553574)
		(width 0.1524)
		(layer "B.Cu")
		(net "PSU3_AC_OK")
	)
	(segment
		(start 26.552652 -196.58203)
		(end 29.044646 -194.090036)
		(width 0.1524)
		(layer "B.Cu")
		(net "PSU3_AC_OK")
	)
	(segment
		(start 29.044646 -194.090036)
		(end 30.45968 -194.090036)
		(width 0.1524)
		(layer "B.Cu")
		(net "PSU3_AC_OK")
	)
	(segment
		(start 23.250906 -200.553574)
		(end 26.552652 -197.251828)
		(width 0.1524)
		(layer "B.Cu")
		(net "PSU3_AC_OK")
	)
	(segment
		(start 26.552652 -197.251828)
		(end 26.552652 -196.58203)
		(width 0.1524)
		(layer "B.Cu")
		(net "PSU3_AC_OK")
	)
	(segment
		(start 23.039832 -223.16821)
		(end 23.250906 -222.957136)
		(width 0.1524)
		(layer "B.Cu")
		(net "PSU3_AC_OK")
	)
	(segment
		(start 6.250432 -218.767152)
		(end 4.33197 -216.84869)
		(width 0.1524)
		(layer "F.Cu")
		(net "PSU4_AC_OK")
	)
	(segment
		(start 17.99971 -226.089464)
		(end 14.431518 -226.089464)
		(width 0.1524)
		(layer "F.Cu")
		(net "PSU4_AC_OK")
	)
	(segment
		(start 7.853934 -219.721684)
		(end 6.899402 -218.767152)
		(width 0.1524)
		(layer "F.Cu")
		(net "PSU4_AC_OK")
	)
	(segment
		(start 2.73812 -215.770206)
		(end 2.73812 -213.459822)
		(width 0.1524)
		(layer "F.Cu")
		(net "PSU4_AC_OK")
	)
	(segment
		(start 11.728704 -222.71863)
		(end 8.731758 -219.721684)
		(width 0.1524)
		(layer "F.Cu")
		(net "PSU4_AC_OK")
	)
	(segment
		(start 2.73812 -213.459822)
		(end 1.948942 -212.670644)
		(width 0.1524)
		(layer "F.Cu")
		(net "PSU4_AC_OK")
	)
	(segment
		(start 14.431518 -226.089464)
		(end 11.728704 -223.38665)
		(width 0.1524)
		(layer "F.Cu")
		(net "PSU4_AC_OK")
	)
	(segment
		(start 4.33197 -216.84869)
		(end 3.816604 -216.84869)
		(width 0.1524)
		(layer "F.Cu")
		(net "PSU4_AC_OK")
	)
	(segment
		(start 3.816604 -216.84869)
		(end 2.73812 -215.770206)
		(width 0.1524)
		(layer "F.Cu")
		(net "PSU4_AC_OK")
	)
	(segment
		(start 11.728704 -223.38665)
		(end 11.728704 -222.71863)
		(width 0.1524)
		(layer "F.Cu")
		(net "PSU4_AC_OK")
	)
	(segment
		(start 8.731758 -219.721684)
		(end 7.853934 -219.721684)
		(width 0.1524)
		(layer "F.Cu")
		(net "PSU4_AC_OK")
	)
	(segment
		(start 6.899402 -218.767152)
		(end 6.250432 -218.767152)
		(width 0.1524)
		(layer "F.Cu")
		(net "PSU4_AC_OK")
	)
	(via
		(at 17.99971 -226.089464)
		(size 0.508)
		(drill 0.254)
		(layers "F.Cu" "B.Cu")
		(net "PSU4_AC_OK")
	)
	(segment
		(start 16.9545 -227.134674)
		(end 17.99971 -226.089464)
		(width 0.1524)
		(layer "B.Cu")
		(net "PSU4_AC_OK")
	)
	(segment
		(start 20.897342 -265.62431)
		(end 20.897342 -240.123218)
		(width 0.1524)
		(layer "B.Cu")
		(net "PSU4_AC_OK")
	)
	(segment
		(start 25.646634 -281.361642)
		(end 25.646634 -270.373602)
		(width 0.1524)
		(layer "B.Cu")
		(net "PSU4_AC_OK")
	)
	(segment
		(start 30.45968 -282.48991)
		(end 29.22778 -282.48991)
		(width 0.1524)
		(layer "B.Cu")
		(net "PSU4_AC_OK")
	)
	(segment
		(start 28.887674 -282.830016)
		(end 27.115008 -282.830016)
		(width 0.1524)
		(layer "B.Cu")
		(net "PSU4_AC_OK")
	)
	(segment
		(start 16.9545 -236.180376)
		(end 16.9545 -227.134674)
		(width 0.1524)
		(layer "B.Cu")
		(net "PSU4_AC_OK")
	)
	(segment
		(start 25.646634 -270.373602)
		(end 20.897342 -265.62431)
		(width 0.1524)
		(layer "B.Cu")
		(net "PSU4_AC_OK")
	)
	(segment
		(start 29.22778 -282.48991)
		(end 28.887674 -282.830016)
		(width 0.1524)
		(layer "B.Cu")
		(net "PSU4_AC_OK")
	)
	(segment
		(start 27.115008 -282.830016)
		(end 25.646634 -281.361642)
		(width 0.1524)
		(layer "B.Cu")
		(net "PSU4_AC_OK")
	)
	(segment
		(start 20.897342 -240.123218)
		(end 16.9545 -236.180376)
		(width 0.1524)
		(layer "B.Cu")
		(net "PSU4_AC_OK")
	)
	(segment
		(start 24.093678 -105.689908)
		(end 23.678642 -106.104944)
		(width 0.1524)
		(layer "F.Cu")
		(net "PSU2_AC_OK")
	)
	(segment
		(start 30.45968 -105.689908)
		(end 24.093678 -105.689908)
		(width 0.1524)
		(layer "F.Cu")
		(net "PSU2_AC_OK")
	)
	(via
		(at 23.678642 -106.104944)
		(size 0.508)
		(drill 0.254)
		(layers "F.Cu" "B.Cu")
		(net "PSU2_AC_OK")
	)
	(segment
		(start 6.132322 -200.862946)
		(end 5.678678 -201.31659)
		(width 0.127)
		(layer "In2.Cu")
		(net "PSU2_AC_OK")
	)
	(segment
		(start 3.655314 -216.377012)
		(end 1.948942 -214.67064)
		(width 0.127)
		(layer "In2.Cu")
		(net "PSU2_AC_OK")
	)
	(segment
		(start 23.678642 -106.104944)
		(end 23.157942 -106.625644)
		(width 0.127)
		(layer "In2.Cu")
		(net "PSU2_AC_OK")
	)
	(segment
		(start 14.316202 -177.550064)
		(end 14.316202 -197.145148)
		(width 0.127)
		(layer "In2.Cu")
		(net "PSU2_AC_OK")
	)
	(segment
		(start 14.316202 -197.145148)
		(end 11.522456 -199.938894)
		(width 0.127)
		(layer "In2.Cu")
		(net "PSU2_AC_OK")
	)
	(segment
		(start 7.171436 -200.862946)
		(end 6.132322 -200.862946)
		(width 0.127)
		(layer "In2.Cu")
		(net "PSU2_AC_OK")
	)
	(segment
		(start 5.678678 -201.31659)
		(end 5.678678 -214.945976)
		(width 0.127)
		(layer "In2.Cu")
		(net "PSU2_AC_OK")
	)
	(segment
		(start 5.678678 -214.945976)
		(end 4.247642 -216.377012)
		(width 0.127)
		(layer "In2.Cu")
		(net "PSU2_AC_OK")
	)
	(segment
		(start 11.522456 -199.938894)
		(end 8.095488 -199.938894)
		(width 0.127)
		(layer "In2.Cu")
		(net "PSU2_AC_OK")
	)
	(segment
		(start 4.247642 -216.377012)
		(end 3.655314 -216.377012)
		(width 0.127)
		(layer "In2.Cu")
		(net "PSU2_AC_OK")
	)
	(segment
		(start 23.157942 -168.708324)
		(end 14.316202 -177.550064)
		(width 0.127)
		(layer "In2.Cu")
		(net "PSU2_AC_OK")
	)
	(segment
		(start 8.095488 -199.938894)
		(end 7.171436 -200.862946)
		(width 0.127)
		(layer "In2.Cu")
		(net "PSU2_AC_OK")
	)
	(segment
		(start 23.157942 -106.625644)
		(end 23.157942 -168.708324)
		(width 0.127)
		(layer "In2.Cu")
		(net "PSU2_AC_OK")
	)
	(segment
		(start 14.758924 -220.996002)
		(end 9.676384 -215.913462)
		(width 0.1524)
		(layer "F.Cu")
		(net "PSU5_AC_OK")
	)
	(segment
		(start 17.99971 -221.558612)
		(end 17.4371 -220.996002)
		(width 0.1524)
		(layer "F.Cu")
		(net "PSU5_AC_OK")
	)
	(segment
		(start 9.676384 -215.913462)
		(end 7.76478 -215.913462)
		(width 0.1524)
		(layer "F.Cu")
		(net "PSU5_AC_OK")
	)
	(segment
		(start 4.952238 -212.673946)
		(end 3.948938 -211.670646)
		(width 0.1524)
		(layer "F.Cu")
		(net "PSU5_AC_OK")
	)
	(segment
		(start 4.952238 -213.632542)
		(end 4.952238 -212.673946)
		(width 0.1524)
		(layer "F.Cu")
		(net "PSU5_AC_OK")
	)
	(segment
		(start 6.719824 -214.868506)
		(end 6.188202 -214.868506)
		(width 0.1524)
		(layer "F.Cu")
		(net "PSU5_AC_OK")
	)
	(segment
		(start 17.4371 -220.996002)
		(end 14.758924 -220.996002)
		(width 0.1524)
		(layer "F.Cu")
		(net "PSU5_AC_OK")
	)
	(segment
		(start 7.76478 -215.913462)
		(end 6.719824 -214.868506)
		(width 0.1524)
		(layer "F.Cu")
		(net "PSU5_AC_OK")
	)
	(segment
		(start 6.188202 -214.868506)
		(end 4.952238 -213.632542)
		(width 0.1524)
		(layer "F.Cu")
		(net "PSU5_AC_OK")
	)
	(via
		(at 17.99971 -221.558612)
		(size 0.508)
		(drill 0.254)
		(layers "F.Cu" "B.Cu")
		(net "PSU5_AC_OK")
	)
	(segment
		(start 29.253688 -367.9825)
		(end 26.200608 -364.92942)
		(width 0.1524)
		(layer "B.Cu")
		(net "PSU5_AC_OK")
	)
	(segment
		(start 26.200608 -364.92942)
		(end 26.200608 -360.139234)
		(width 0.1524)
		(layer "B.Cu")
		(net "PSU5_AC_OK")
	)
	(segment
		(start 22.310344 -323.607938)
		(end 26.23058 -319.687702)
		(width 0.1524)
		(layer "B.Cu")
		(net "PSU5_AC_OK")
	)
	(segment
		(start 17.86001 -276.038564)
		(end 17.86001 -253.81204)
		(width 0.1524)
		(layer "B.Cu")
		(net "PSU5_AC_OK")
	)
	(segment
		(start 16.358616 -223.199706)
		(end 17.99971 -221.558612)
		(width 0.1524)
		(layer "B.Cu")
		(net "PSU5_AC_OK")
	)
	(segment
		(start 21.701506 -284.454854)
		(end 21.701506 -279.88006)
		(width 0.1524)
		(layer "B.Cu")
		(net "PSU5_AC_OK")
	)
	(segment
		(start 26.23058 -319.687702)
		(end 26.23058 -288.983928)
		(width 0.1524)
		(layer "B.Cu")
		(net "PSU5_AC_OK")
	)
	(segment
		(start 30.45968 -370.890038)
		(end 29.253688 -369.684046)
		(width 0.1524)
		(layer "B.Cu")
		(net "PSU5_AC_OK")
	)
	(segment
		(start 29.253688 -369.684046)
		(end 29.253688 -367.9825)
		(width 0.1524)
		(layer "B.Cu")
		(net "PSU5_AC_OK")
	)
	(segment
		(start 26.23058 -288.983928)
		(end 21.701506 -284.454854)
		(width 0.1524)
		(layer "B.Cu")
		(net "PSU5_AC_OK")
	)
	(segment
		(start 21.701506 -279.88006)
		(end 17.86001 -276.038564)
		(width 0.1524)
		(layer "B.Cu")
		(net "PSU5_AC_OK")
	)
	(segment
		(start 16.358616 -252.310646)
		(end 16.358616 -223.199706)
		(width 0.1524)
		(layer "B.Cu")
		(net "PSU5_AC_OK")
	)
	(segment
		(start 22.310344 -356.24897)
		(end 22.310344 -323.607938)
		(width 0.1524)
		(layer "B.Cu")
		(net "PSU5_AC_OK")
	)
	(segment
		(start 17.86001 -253.81204)
		(end 16.358616 -252.310646)
		(width 0.1524)
		(layer "B.Cu")
		(net "PSU5_AC_OK")
	)
	(segment
		(start 26.200608 -360.139234)
		(end 22.310344 -356.24897)
		(width 0.1524)
		(layer "B.Cu")
		(net "PSU5_AC_OK")
	)
	(segment
		(start 24.091392 -88.934798)
		(end 21.84781 -91.17838)
		(width 0.127)
		(layer "In2.Cu")
		(net "PSU1_AC_OK")
	)
	(segment
		(start 6.008116 -200.414636)
		(end 5.109972 -201.31278)
		(width 0.127)
		(layer "In2.Cu")
		(net "PSU1_AC_OK")
	)
	(segment
		(start 24.091392 -25.816052)
		(end 24.091392 -88.934798)
		(width 0.127)
		(layer "In2.Cu")
		(net "PSU1_AC_OK")
	)
	(segment
		(start 5.109972 -214.509604)
		(end 3.948938 -215.670638)
		(width 0.127)
		(layer "In2.Cu")
		(net "PSU1_AC_OK")
	)
	(segment
		(start 29.083762 -18.665952)
		(end 29.083762 -20.823682)
		(width 0.127)
		(layer "In2.Cu")
		(net "PSU1_AC_OK")
	)
	(segment
		(start 21.84781 -91.17838)
		(end 21.84781 -105.588816)
		(width 0.127)
		(layer "In2.Cu")
		(net "PSU1_AC_OK")
	)
	(segment
		(start 11.209274 -199.430132)
		(end 7.78891 -199.430132)
		(width 0.127)
		(layer "In2.Cu")
		(net "PSU1_AC_OK")
	)
	(segment
		(start 29.083762 -20.823682)
		(end 24.091392 -25.816052)
		(width 0.127)
		(layer "In2.Cu")
		(net "PSU1_AC_OK")
	)
	(segment
		(start 13.98016 -196.659246)
		(end 11.209274 -199.430132)
		(width 0.127)
		(layer "In2.Cu")
		(net "PSU1_AC_OK")
	)
	(segment
		(start 5.109972 -201.31278)
		(end 5.109972 -214.509604)
		(width 0.127)
		(layer "In2.Cu")
		(net "PSU1_AC_OK")
	)
	(segment
		(start 22.816058 -168.53535)
		(end 13.98016 -177.371248)
		(width 0.127)
		(layer "In2.Cu")
		(net "PSU1_AC_OK")
	)
	(segment
		(start 13.98016 -177.371248)
		(end 13.98016 -196.659246)
		(width 0.127)
		(layer "In2.Cu")
		(net "PSU1_AC_OK")
	)
	(segment
		(start 22.816058 -106.557064)
		(end 22.816058 -168.53535)
		(width 0.127)
		(layer "In2.Cu")
		(net "PSU1_AC_OK")
	)
	(segment
		(start 6.804406 -200.414636)
		(end 6.008116 -200.414636)
		(width 0.127)
		(layer "In2.Cu")
		(net "PSU1_AC_OK")
	)
	(segment
		(start 7.78891 -199.430132)
		(end 6.804406 -200.414636)
		(width 0.127)
		(layer "In2.Cu")
		(net "PSU1_AC_OK")
	)
	(segment
		(start 21.84781 -105.588816)
		(end 22.816058 -106.557064)
		(width 0.127)
		(layer "In2.Cu")
		(net "PSU1_AC_OK")
	)
	(segment
		(start 30.45968 -17.290034)
		(end 29.083762 -18.665952)
		(width 0.127)
		(layer "In2.Cu")
		(net "PSU1_AC_OK")
	)
	(segment
		(start 13.020802 -318.358012)
		(end 13.020802 -319.404238)
		(width 0.1524)
		(layer "F.Cu")
		(net "FAN_PWM")
	)
	(segment
		(start 13.020802 -319.404238)
		(end 12.986258 -319.438782)
		(width 0.1524)
		(layer "F.Cu")
		(net "FAN_PWM")
	)
	(segment
		(start 8.449818 -321.669918)
		(end 9.474708 -321.669918)
		(width 0.1524)
		(layer "F.Cu")
		(net "FAN_PWM")
	)
	(segment
		(start 9.474708 -321.669918)
		(end 11.705844 -319.438782)
		(width 0.1524)
		(layer "F.Cu")
		(net "FAN_PWM")
	)
	(segment
		(start 11.705844 -319.438782)
		(end 12.986258 -319.438782)
		(width 0.1524)
		(layer "F.Cu")
		(net "FAN_PWM")
	)
	(segment
		(start 22.236684 -382.497076)
		(end 12.226798 -372.48719)
		(width 0.1524)
		(layer "B.Cu")
		(net "FAN_PWM")
	)
	(segment
		(start 5.308092 -324.691502)
		(end 6.32206 -323.677534)
		(width 0.1524)
		(layer "B.Cu")
		(net "FAN_PWM")
	)
	(segment
		(start 7.07136 -327.568052)
		(end 6.2484 -327.568052)
		(width 0.1524)
		(layer "B.Cu")
		(net "FAN_PWM")
	)
	(segment
		(start 7.691374 -322.428362)
		(end 8.449818 -321.669918)
		(width 0.1524)
		(layer "B.Cu")
		(net "FAN_PWM")
	)
	(segment
		(start 6.698488 -323.677534)
		(end 7.691374 -322.684648)
		(width 0.1524)
		(layer "B.Cu")
		(net "FAN_PWM")
	)
	(segment
		(start 5.944108 -436.49392)
		(end 7.450074 -434.987954)
		(width 0.1524)
		(layer "B.Cu")
		(net "FAN_PWM")
	)
	(segment
		(start 5.308092 -326.627744)
		(end 5.308092 -324.691502)
		(width 0.1524)
		(layer "B.Cu")
		(net "FAN_PWM")
	)
	(segment
		(start 7.450074 -434.987954)
		(end 7.450074 -425.399962)
		(width 0.1524)
		(layer "B.Cu")
		(net "FAN_PWM")
	)
	(segment
		(start 9.976358 -329.887072)
		(end 8.877046 -328.78776)
		(width 0.1524)
		(layer "B.Cu")
		(net "FAN_PWM")
	)
	(segment
		(start 22.236684 -406.096724)
		(end 22.236684 -382.497076)
		(width 0.1524)
		(layer "B.Cu")
		(net "FAN_PWM")
	)
	(segment
		(start 6.2484 -327.568052)
		(end 5.308092 -326.627744)
		(width 0.1524)
		(layer "B.Cu")
		(net "FAN_PWM")
	)
	(segment
		(start 6.32206 -323.677534)
		(end 6.698488 -323.677534)
		(width 0.1524)
		(layer "B.Cu")
		(net "FAN_PWM")
	)
	(segment
		(start 5.944108 -423.893996)
		(end 5.944108 -422.3893)
		(width 0.1524)
		(layer "B.Cu")
		(net "FAN_PWM")
	)
	(segment
		(start 12.226798 -372.48719)
		(end 12.226798 -345.977464)
		(width 0.1524)
		(layer "B.Cu")
		(net "FAN_PWM")
	)
	(segment
		(start 12.226798 -345.977464)
		(end 9.976358 -343.727024)
		(width 0.1524)
		(layer "B.Cu")
		(net "FAN_PWM")
	)
	(segment
		(start 5.944108 -422.3893)
		(end 22.236684 -406.096724)
		(width 0.1524)
		(layer "B.Cu")
		(net "FAN_PWM")
	)
	(segment
		(start 7.450074 -425.399962)
		(end 5.944108 -423.893996)
		(width 0.1524)
		(layer "B.Cu")
		(net "FAN_PWM")
	)
	(segment
		(start 8.877046 -328.78776)
		(end 8.291068 -328.78776)
		(width 0.1524)
		(layer "B.Cu")
		(net "FAN_PWM")
	)
	(segment
		(start 9.976358 -343.727024)
		(end 9.976358 -329.887072)
		(width 0.1524)
		(layer "B.Cu")
		(net "FAN_PWM")
	)
	(segment
		(start 8.291068 -328.78776)
		(end 7.07136 -327.568052)
		(width 0.1524)
		(layer "B.Cu")
		(net "FAN_PWM")
	)
	(segment
		(start 7.691374 -322.684648)
		(end 7.691374 -322.428362)
		(width 0.1524)
		(layer "B.Cu")
		(net "FAN_PWM")
	)
	(segment
		(start 18.264886 -330.05522)
		(end 18.264886 -329.228196)
		(width 0.508)
		(layer "F.Cu")
		(net "P3V3")
	)
	(segment
		(start 10.198354 -338.712556)
		(end 8.1915 -338.712556)
		(width 0.508)
		(layer "F.Cu")
		(net "P3V3")
	)
	(segment
		(start 13.241274 -328.585576)
		(end 12.784074 -329.042776)
		(width 0.508)
		(layer "F.Cu")
		(net "P3V3")
	)
	(segment
		(start 14.443964 -339.370162)
		(end 14.443964 -337.975702)
		(width 0.508)
		(layer "F.Cu")
		(net "P3V3")
	)
	(segment
		(start 3.297936 -337.691222)
		(end 1.949958 -339.0392)
		(width 0.508)
		(layer "F.Cu")
		(net "P3V3")
	)
	(segment
		(start 14.443964 -339.370162)
		(end 13.45692 -339.370162)
		(width 0.508)
		(layer "F.Cu")
		(net "P3V3")
	)
	(segment
		(start 11.676888 -331.970888)
		(end 11.676888 -330.503784)
		(width 0.508)
		(layer "F.Cu")
		(net "P3V3")
	)
	(segment
		(start 11.676888 -330.503784)
		(end 12.100052 -330.08062)
		(width 0.508)
		(layer "F.Cu")
		(net "P3V3")
	)
	(segment
		(start 7.170166 -337.691222)
		(end 3.297936 -337.691222)
		(width 0.508)
		(layer "F.Cu")
		(net "P3V3")
	)
	(segment
		(start 12.500102 -339.304122)
		(end 11.93292 -339.304122)
		(width 0.508)
		(layer "F.Cu")
		(net "P3V3")
	)
	(segment
		(start 14.923008 -329.150726)
		(end 14.357858 -328.585576)
		(width 0.508)
		(layer "F.Cu")
		(net "P3V3")
	)
	(segment
		(start 14.443964 -337.975702)
		(end 12.683744 -336.215482)
		(width 0.508)
		(layer "F.Cu")
		(net "P3V3")
	)
	(segment
		(start 8.1915 -338.712556)
		(end 7.170166 -337.691222)
		(width 0.508)
		(layer "F.Cu")
		(net "P3V3")
	)
	(segment
		(start 14.923008 -329.123802)
		(end 14.923008 -329.150726)
		(width 0.508)
		(layer "F.Cu")
		(net "P3V3")
	)
	(segment
		(start 15.461742 -328.585068)
		(end 14.923008 -329.123802)
		(width 0.508)
		(layer "F.Cu")
		(net "P3V3")
	)
	(segment
		(start 12.560554 -339.364574)
		(end 12.500102 -339.304122)
		(width 0.508)
		(layer "F.Cu")
		(net "P3V3")
	)
	(segment
		(start 1.949958 -339.0392)
		(end 1.949958 -339.669882)
		(width 0.508)
		(layer "F.Cu")
		(net "P3V3")
	)
	(segment
		(start 13.451332 -339.364574)
		(end 12.560554 -339.364574)
		(width 0.508)
		(layer "F.Cu")
		(net "P3V3")
	)
	(segment
		(start 12.683744 -332.977744)
		(end 11.676888 -331.970888)
		(width 0.508)
		(layer "F.Cu")
		(net "P3V3")
	)
	(segment
		(start 13.45692 -339.370162)
		(end 13.451332 -339.364574)
		(width 0.508)
		(layer "F.Cu")
		(net "P3V3")
	)
	(segment
		(start 18.264886 -329.228196)
		(end 17.621758 -328.585068)
		(width 0.508)
		(layer "F.Cu")
		(net "P3V3")
	)
	(segment
		(start 12.100052 -330.08062)
		(end 12.784074 -330.08062)
		(width 0.508)
		(layer "F.Cu")
		(net "P3V3")
	)
	(segment
		(start 14.357858 -328.585576)
		(end 13.241274 -328.585576)
		(width 0.508)
		(layer "F.Cu")
		(net "P3V3")
	)
	(segment
		(start 17.621758 -328.585068)
		(end 15.461742 -328.585068)
		(width 0.508)
		(layer "F.Cu")
		(net "P3V3")
	)
	(segment
		(start 11.93292 -339.304122)
		(end 10.78992 -339.304122)
		(width 0.508)
		(layer "F.Cu")
		(net "P3V3")
	)
	(segment
		(start 10.78992 -339.304122)
		(end 10.198354 -338.712556)
		(width 0.508)
		(layer "F.Cu")
		(net "P3V3")
	)
	(segment
		(start 14.923008 -330.097384)
		(end 14.923008 -329.150726)
		(width 0.508)
		(layer "F.Cu")
		(net "P3V3")
	)
	(segment
		(start 12.683744 -336.215482)
		(end 12.683744 -332.977744)
		(width 0.508)
		(layer "F.Cu")
		(net "P3V3")
	)
	(segment
		(start 12.784074 -329.042776)
		(end 12.784074 -330.08062)
		(width 0.508)
		(layer "F.Cu")
		(net "P3V3")
	)
	(via
		(at 11.93292 -339.304122)
		(size 0.508)
		(drill 0.254)
		(layers "F.Cu" "B.Cu")
		(net "P3V3")
	)
	(segment
		(start 16.919702 -342.301322)
		(end 18.253964 -340.96706)
		(width 0.1524)
		(layer "F.Cu")
		(net "I2C_PDB_SDA")
	)
	(segment
		(start 11.93292 -340.574122)
		(end 11.47572 -341.031322)
		(width 0.1524)
		(layer "F.Cu")
		(net "I2C_PDB_SDA")
	)
	(segment
		(start 11.47572 -341.031322)
		(end 11.47572 -342.04021)
		(width 0.1524)
		(layer "F.Cu")
		(net "I2C_PDB_SDA")
	)
	(segment
		(start 18.253964 -340.96706)
		(end 18.253964 -339.370162)
		(width 0.1524)
		(layer "F.Cu")
		(net "I2C_PDB_SDA")
	)
	(segment
		(start 11.736832 -342.301322)
		(end 16.919702 -342.301322)
		(width 0.1524)
		(layer "F.Cu")
		(net "I2C_PDB_SDA")
	)
	(segment
		(start 11.47572 -342.04021)
		(end 11.736832 -342.301322)
		(width 0.1524)
		(layer "F.Cu")
		(net "I2C_PDB_SDA")
	)
	(via
		(at 11.93292 -340.574122)
		(size 0.508)
		(drill 0.254)
		(layers "F.Cu" "B.Cu")
		(net "I2C_PDB_SDA")
	)
	(segment
		(start 10.802874 -341.704168)
		(end 11.93292 -340.574122)
		(width 0.127)
		(layer "In2.Cu")
		(net "I2C_PDB_SDA")
	)
	(segment
		(start 8.843772 -341.704168)
		(end 10.802874 -341.704168)
		(width 0.127)
		(layer "In2.Cu")
		(net "I2C_PDB_SDA")
	)
	(segment
		(start 4.723638 -343.44356)
		(end 7.10438 -343.44356)
		(width 0.127)
		(layer "In2.Cu")
		(net "I2C_PDB_SDA")
	)
	(segment
		(start 3.949954 -342.669876)
		(end 4.723638 -343.44356)
		(width 0.127)
		(layer "In2.Cu")
		(net "I2C_PDB_SDA")
	)
	(segment
		(start 7.10438 -343.44356)
		(end 8.843772 -341.704168)
		(width 0.127)
		(layer "In2.Cu")
		(net "I2C_PDB_SDA")
	)
	(segment
		(start 11.93292 -341.844122)
		(end 16.474186 -341.844122)
		(width 0.1524)
		(layer "F.Cu")
		(net "I2C_PDB_SCL")
	)
	(segment
		(start 16.983964 -341.334344)
		(end 16.983964 -339.370162)
		(width 0.1524)
		(layer "F.Cu")
		(net "I2C_PDB_SCL")
	)
	(segment
		(start 16.474186 -341.844122)
		(end 16.983964 -341.334344)
		(width 0.1524)
		(layer "F.Cu")
		(net "I2C_PDB_SCL")
	)
	(via
		(at 11.93292 -341.844122)
		(size 0.508)
		(drill 0.254)
		(layers "F.Cu" "B.Cu")
		(net "I2C_PDB_SCL")
	)
	(segment
		(start 7.210552 -343.834212)
		(end 8.71474 -342.330024)
		(width 0.127)
		(layer "In2.Cu")
		(net "I2C_PDB_SCL")
	)
	(segment
		(start 1.949958 -343.669874)
		(end 3.437382 -343.669874)
		(width 0.127)
		(layer "In2.Cu")
		(net "I2C_PDB_SCL")
	)
	(segment
		(start 3.60172 -343.834212)
		(end 7.210552 -343.834212)
		(width 0.127)
		(layer "In2.Cu")
		(net "I2C_PDB_SCL")
	)
	(segment
		(start 11.447018 -342.330024)
		(end 11.93292 -341.844122)
		(width 0.127)
		(layer "In2.Cu")
		(net "I2C_PDB_SCL")
	)
	(segment
		(start 3.437382 -343.669874)
		(end 3.60172 -343.834212)
		(width 0.127)
		(layer "In2.Cu")
		(net "I2C_PDB_SCL")
	)
	(segment
		(start 8.71474 -342.330024)
		(end 11.447018 -342.330024)
		(width 0.127)
		(layer "In2.Cu")
		(net "I2C_PDB_SCL")
	)
	(segment
		(start 40.019732 -13.519404)
		(end 40.019732 -13.062204)
		(width 0.1524)
		(layer "F.Cu")
		(net "PSU1_RETURN")
	)
	(segment
		(start 39.757604 -13.781532)
		(end 40.019732 -13.519404)
		(width 0.1524)
		(layer "F.Cu")
		(net "PSU1_RETURN")
	)
	(segment
		(start 39.757604 -14.412976)
		(end 39.757604 -13.781532)
		(width 0.1524)
		(layer "F.Cu")
		(net "PSU1_RETURN")
	)
	(segment
		(start 39.167308 -12.20978)
		(end 40.019732 -13.062204)
		(width 0.1524)
		(layer "F.Cu")
		(net "PSU1_RETURN")
	)
	(segment
		(start 35.539934 -12.20978)
		(end 39.167308 -12.20978)
		(width 0.1524)
		(layer "F.Cu")
		(net "PSU1_RETURN")
	)
	(segment
		(start 35.53968 -12.210034)
		(end 35.539934 -12.20978)
		(width 0.1524)
		(layer "F.Cu")
		(net "PSU1_RETURN")
	)
	(via
		(at 40.019732 -13.062204)
		(size 0.508)
		(drill 0.254)
		(layers "F.Cu" "B.Cu")
		(net "PSU1_RETURN")
	)
	(segment
		(start 35.53968 -17.290034)
		(end 36.539932 -17.290034)
		(width 0.1524)
		(layer "F.Cu")
		(net "PSU1_AD0")
	)
	(segment
		(start 36.539932 -17.290034)
		(end 37.555932 -17.28978)
		(width 0.1524)
		(layer "F.Cu")
		(net "PSU1_AD0")
	)
	(segment
		(start 37.555932 -17.28978)
		(end 37.571172 -17.30502)
		(width 0.1524)
		(layer "F.Cu")
		(net "PSU1_AD0")
	)
	(segment
		(start 37.571172 -17.30502)
		(end 39.449502 -17.30502)
		(width 0.1524)
		(layer "F.Cu")
		(net "PSU1_AD0")
	)
	(via
		(at 94.366842 -306.00015)
		(size 0.508)
		(drill 0.254)
		(layers "F.Cu" "B.Cu")
		(net "T8_BLAD2_TXD")
	)
	(segment
		(start 10.798556 -276.82571)
		(end 18.91538 -268.708886)
		(width 0.127)
		(layer "In5.Cu")
		(net "T8_BLAD2_TXD")
	)
	(segment
		(start 8.05053 -278.835866)
		(end 9.547606 -278.835866)
		(width 0.127)
		(layer "In5.Cu")
		(net "T8_BLAD2_TXD")
	)
	(segment
		(start 18.91538 -268.708886)
		(end 70.947026 -268.708886)
		(width 0.127)
		(layer "In5.Cu")
		(net "T8_BLAD2_TXD")
	)
	(segment
		(start 5.154168 -280.828242)
		(end 6.021832 -279.960578)
		(width 0.127)
		(layer "In5.Cu")
		(net "T8_BLAD2_TXD")
	)
	(segment
		(start 94.366842 -306.791614)
		(end 94.366842 -306.00015)
		(width 0.127)
		(layer "In5.Cu")
		(net "T8_BLAD2_TXD")
	)
	(segment
		(start 5.154168 -281.465528)
		(end 5.154168 -280.828242)
		(width 0.127)
		(layer "In5.Cu")
		(net "T8_BLAD2_TXD")
	)
	(segment
		(start 6.021832 -279.960578)
		(end 6.925818 -279.960578)
		(width 0.127)
		(layer "In5.Cu")
		(net "T8_BLAD2_TXD")
	)
	(segment
		(start 94.485968 -269.874746)
		(end 98.799904 -274.188682)
		(width 0.127)
		(layer "In5.Cu")
		(net "T8_BLAD2_TXD")
	)
	(segment
		(start 85.47608 -321.39382)
		(end 84.524088 -320.441828)
		(width 0.127)
		(layer "In5.Cu")
		(net "T8_BLAD2_TXD")
	)
	(segment
		(start 98.799904 -274.188682)
		(end 98.799904 -288.47796)
		(width 0.127)
		(layer "In5.Cu")
		(net "T8_BLAD2_TXD")
	)
	(segment
		(start 89.29116 -321.39382)
		(end 85.47608 -321.39382)
		(width 0.127)
		(layer "In5.Cu")
		(net "T8_BLAD2_TXD")
	)
	(segment
		(start 6.925818 -279.960578)
		(end 8.05053 -278.835866)
		(width 0.127)
		(layer "In5.Cu")
		(net "T8_BLAD2_TXD")
	)
	(segment
		(start 84.524088 -320.441828)
		(end 84.524088 -316.634368)
		(width 0.127)
		(layer "In5.Cu")
		(net "T8_BLAD2_TXD")
	)
	(segment
		(start 9.547606 -278.835866)
		(end 10.798556 -277.584916)
		(width 0.127)
		(layer "In5.Cu")
		(net "T8_BLAD2_TXD")
	)
	(segment
		(start 94.366842 -292.911022)
		(end 94.366842 -306.00015)
		(width 0.127)
		(layer "In5.Cu")
		(net "T8_BLAD2_TXD")
	)
	(segment
		(start 84.524088 -316.634368)
		(end 94.366842 -306.791614)
		(width 0.127)
		(layer "In5.Cu")
		(net "T8_BLAD2_TXD")
	)
	(segment
		(start 90.71991 -319.96507)
		(end 89.29116 -321.39382)
		(width 0.127)
		(layer "In5.Cu")
		(net "T8_BLAD2_TXD")
	)
	(segment
		(start 3.949954 -282.669742)
		(end 5.154168 -281.465528)
		(width 0.127)
		(layer "In5.Cu")
		(net "T8_BLAD2_TXD")
	)
	(segment
		(start 10.798556 -277.584916)
		(end 10.798556 -276.82571)
		(width 0.127)
		(layer "In5.Cu")
		(net "T8_BLAD2_TXD")
	)
	(segment
		(start 98.799904 -288.47796)
		(end 94.366842 -292.911022)
		(width 0.127)
		(layer "In5.Cu")
		(net "T8_BLAD2_TXD")
	)
	(segment
		(start 70.947026 -268.708886)
		(end 72.112886 -269.874746)
		(width 0.127)
		(layer "In5.Cu")
		(net "T8_BLAD2_TXD")
	)
	(segment
		(start 72.112886 -269.874746)
		(end 94.485968 -269.874746)
		(width 0.127)
		(layer "In5.Cu")
		(net "T8_BLAD2_TXD")
	)
	(segment
		(start 35.53968 -22.370034)
		(end 39.43858 -22.370034)
		(width 0.508)
		(layer "F.Cu")
		(net "PSU1_REMOTE_P")
	)
	(segment
		(start 39.43858 -22.370034)
		(end 39.462964 -22.394418)
		(width 0.508)
		(layer "F.Cu")
		(net "PSU1_REMOTE_P")
	)
	(via
		(at 83.723226 -326.140064)
		(size 0.508)
		(drill 0.254)
		(layers "F.Cu" "B.Cu")
		(net "T8_BLAD1_EN")
	)
	(segment
		(start 27.577796 -293.02202)
		(end 21.608542 -287.052766)
		(width 0.127)
		(layer "In2.Cu")
		(net "T8_BLAD1_EN")
	)
	(segment
		(start 2.576068 -288.709862)
		(end 1.755902 -288.709862)
		(width 0.127)
		(layer "In2.Cu")
		(net "T8_BLAD1_EN")
	)
	(segment
		(start 1.234948 -290.279836)
		(end 1.625092 -290.66998)
		(width 0.127)
		(layer "In2.Cu")
		(net "T8_BLAD1_EN")
	)
	(segment
		(start 1.234948 -289.230816)
		(end 1.234948 -290.279836)
		(width 0.127)
		(layer "In2.Cu")
		(net "T8_BLAD1_EN")
	)
	(segment
		(start 88.17991 -321.68338)
		(end 83.723226 -326.140064)
		(width 0.127)
		(layer "In2.Cu")
		(net "T8_BLAD1_EN")
	)
	(segment
		(start 7.090664 -285.89478)
		(end 6.217158 -285.89478)
		(width 0.127)
		(layer "In2.Cu")
		(net "T8_BLAD1_EN")
	)
	(segment
		(start 88.17991 -319.96507)
		(end 88.17991 -321.68338)
		(width 0.127)
		(layer "In2.Cu")
		(net "T8_BLAD1_EN")
	)
	(segment
		(start 6.217158 -285.89478)
		(end 4.142486 -287.969452)
		(width 0.127)
		(layer "In2.Cu")
		(net "T8_BLAD1_EN")
	)
	(segment
		(start 27.577796 -349.153226)
		(end 27.577796 -293.02202)
		(width 0.127)
		(layer "In2.Cu")
		(net "T8_BLAD1_EN")
	)
	(segment
		(start 4.142486 -287.969452)
		(end 3.316478 -287.969452)
		(width 0.127)
		(layer "In2.Cu")
		(net "T8_BLAD1_EN")
	)
	(segment
		(start 1.625092 -290.66998)
		(end 3.949954 -290.66998)
		(width 0.127)
		(layer "In2.Cu")
		(net "T8_BLAD1_EN")
	)
	(segment
		(start 8.711184 -286.821626)
		(end 8.01751 -286.821626)
		(width 0.127)
		(layer "In2.Cu")
		(net "T8_BLAD1_EN")
	)
	(segment
		(start 8.01751 -286.821626)
		(end 7.090664 -285.89478)
		(width 0.127)
		(layer "In2.Cu")
		(net "T8_BLAD1_EN")
	)
	(segment
		(start 44.397676 -351.223326)
		(end 29.647896 -351.223326)
		(width 0.127)
		(layer "In2.Cu")
		(net "T8_BLAD1_EN")
	)
	(segment
		(start 21.608542 -287.052766)
		(end 8.942324 -287.052766)
		(width 0.127)
		(layer "In2.Cu")
		(net "T8_BLAD1_EN")
	)
	(segment
		(start 1.755902 -288.709862)
		(end 1.234948 -289.230816)
		(width 0.127)
		(layer "In2.Cu")
		(net "T8_BLAD1_EN")
	)
	(segment
		(start 29.647896 -351.223326)
		(end 27.577796 -349.153226)
		(width 0.127)
		(layer "In2.Cu")
		(net "T8_BLAD1_EN")
	)
	(segment
		(start 60.49391 -349.36938)
		(end 46.251622 -349.36938)
		(width 0.127)
		(layer "In2.Cu")
		(net "T8_BLAD1_EN")
	)
	(segment
		(start 46.251622 -349.36938)
		(end 44.397676 -351.223326)
		(width 0.127)
		(layer "In2.Cu")
		(net "T8_BLAD1_EN")
	)
	(segment
		(start 83.723226 -326.140064)
		(end 60.49391 -349.36938)
		(width 0.127)
		(layer "In2.Cu")
		(net "T8_BLAD1_EN")
	)
	(segment
		(start 8.942324 -287.052766)
		(end 8.711184 -286.821626)
		(width 0.127)
		(layer "In2.Cu")
		(net "T8_BLAD1_EN")
	)
	(segment
		(start 3.316478 -287.969452)
		(end 2.576068 -288.709862)
		(width 0.127)
		(layer "In2.Cu")
		(net "T8_BLAD1_EN")
	)
	(via
		(at 98.251264 -299.679614)
		(size 0.508)
		(drill 0.254)
		(layers "F.Cu" "B.Cu")
		(net "T8_BLAD4_TXD")
	)
	(segment
		(start 80.826102 -266.879324)
		(end 81.096866 -266.60856)
		(width 0.127)
		(layer "In5.Cu")
		(net "T8_BLAD4_TXD")
	)
	(segment
		(start 18.062194 -266.879324)
		(end 80.826102 -266.879324)
		(width 0.127)
		(layer "In5.Cu")
		(net "T8_BLAD4_TXD")
	)
	(segment
		(start 4.89331 -276.864826)
		(end 4.89331 -276.602952)
		(width 0.127)
		(layer "In5.Cu")
		(net "T8_BLAD4_TXD")
	)
	(segment
		(start 100.729034 -289.345116)
		(end 98.251264 -291.822886)
		(width 0.127)
		(layer "In5.Cu")
		(net "T8_BLAD4_TXD")
	)
	(segment
		(start 8.00608 -274.380452)
		(end 10.561066 -274.380452)
		(width 0.127)
		(layer "In5.Cu")
		(net "T8_BLAD4_TXD")
	)
	(segment
		(start 100.729034 -273.5707)
		(end 100.729034 -289.345116)
		(width 0.127)
		(layer "In5.Cu")
		(net "T8_BLAD4_TXD")
	)
	(segment
		(start 98.251264 -311.38114)
		(end 98.251264 -299.679614)
		(width 0.127)
		(layer "In5.Cu")
		(net "T8_BLAD4_TXD")
	)
	(segment
		(start 90.71991 -317.42507)
		(end 92.207334 -317.42507)
		(width 0.127)
		(layer "In5.Cu")
		(net "T8_BLAD4_TXD")
	)
	(segment
		(start 4.89331 -276.602952)
		(end 6.004306 -275.491956)
		(width 0.127)
		(layer "In5.Cu")
		(net "T8_BLAD4_TXD")
	)
	(segment
		(start 94.037658 -266.879324)
		(end 100.729034 -273.5707)
		(width 0.127)
		(layer "In5.Cu")
		(net "T8_BLAD4_TXD")
	)
	(segment
		(start 83.093306 -266.60856)
		(end 83.36407 -266.879324)
		(width 0.127)
		(layer "In5.Cu")
		(net "T8_BLAD4_TXD")
	)
	(segment
		(start 6.894576 -275.491956)
		(end 8.00608 -274.380452)
		(width 0.127)
		(layer "In5.Cu")
		(net "T8_BLAD4_TXD")
	)
	(segment
		(start 4.088384 -277.669752)
		(end 4.89331 -276.864826)
		(width 0.127)
		(layer "In5.Cu")
		(net "T8_BLAD4_TXD")
	)
	(segment
		(start 1.949958 -277.669752)
		(end 4.088384 -277.669752)
		(width 0.127)
		(layer "In5.Cu")
		(net "T8_BLAD4_TXD")
	)
	(segment
		(start 81.096866 -266.60856)
		(end 83.093306 -266.60856)
		(width 0.127)
		(layer "In5.Cu")
		(net "T8_BLAD4_TXD")
	)
	(segment
		(start 10.561066 -274.380452)
		(end 18.062194 -266.879324)
		(width 0.127)
		(layer "In5.Cu")
		(net "T8_BLAD4_TXD")
	)
	(segment
		(start 83.36407 -266.879324)
		(end 94.037658 -266.879324)
		(width 0.127)
		(layer "In5.Cu")
		(net "T8_BLAD4_TXD")
	)
	(segment
		(start 6.004306 -275.491956)
		(end 6.894576 -275.491956)
		(width 0.127)
		(layer "In5.Cu")
		(net "T8_BLAD4_TXD")
	)
	(segment
		(start 98.251264 -291.822886)
		(end 98.251264 -299.679614)
		(width 0.127)
		(layer "In5.Cu")
		(net "T8_BLAD4_TXD")
	)
	(segment
		(start 92.207334 -317.42507)
		(end 98.251264 -311.38114)
		(width 0.127)
		(layer "In5.Cu")
		(net "T8_BLAD4_TXD")
	)
	(via
		(at 83.294728 -327.462134)
		(size 0.508)
		(drill 0.254)
		(layers "F.Cu" "B.Cu")
		(net "T8_BLAD3_EN")
	)
	(segment
		(start 21.623782 -287.535112)
		(end 27.247596 -293.158926)
		(width 0.127)
		(layer "In2.Cu")
		(net "T8_BLAD3_EN")
	)
	(segment
		(start 44.846748 -351.553526)
		(end 46.638718 -349.761556)
		(width 0.127)
		(layer "In2.Cu")
		(net "T8_BLAD3_EN")
	)
	(segment
		(start 88.17991 -317.42507)
		(end 88.17991 -318.81826)
		(width 0.127)
		(layer "In2.Cu")
		(net "T8_BLAD3_EN")
	)
	(segment
		(start 10.470388 -287.535112)
		(end 21.623782 -287.535112)
		(width 0.127)
		(layer "In2.Cu")
		(net "T8_BLAD3_EN")
	)
	(segment
		(start 6.045454 -287.588706)
		(end 7.248398 -287.588706)
		(width 0.127)
		(layer "In2.Cu")
		(net "T8_BLAD3_EN")
	)
	(segment
		(start 88.17991 -318.81826)
		(end 89.013538 -319.651888)
		(width 0.127)
		(layer "In2.Cu")
		(net "T8_BLAD3_EN")
	)
	(segment
		(start 27.247596 -349.290132)
		(end 29.51099 -351.553526)
		(width 0.127)
		(layer "In2.Cu")
		(net "T8_BLAD3_EN")
	)
	(segment
		(start 89.013538 -321.743324)
		(end 83.294728 -327.462134)
		(width 0.127)
		(layer "In2.Cu")
		(net "T8_BLAD3_EN")
	)
	(segment
		(start 89.013538 -319.651888)
		(end 89.013538 -321.743324)
		(width 0.127)
		(layer "In2.Cu")
		(net "T8_BLAD3_EN")
	)
	(segment
		(start 60.995306 -349.761556)
		(end 83.294728 -327.462134)
		(width 0.127)
		(layer "In2.Cu")
		(net "T8_BLAD3_EN")
	)
	(segment
		(start 46.638718 -349.761556)
		(end 60.995306 -349.761556)
		(width 0.127)
		(layer "In2.Cu")
		(net "T8_BLAD3_EN")
	)
	(segment
		(start 7.248398 -287.588706)
		(end 8.093964 -288.434272)
		(width 0.127)
		(layer "In2.Cu")
		(net "T8_BLAD3_EN")
	)
	(segment
		(start 4.964176 -288.669984)
		(end 6.045454 -287.588706)
		(width 0.127)
		(layer "In2.Cu")
		(net "T8_BLAD3_EN")
	)
	(segment
		(start 27.247596 -293.158926)
		(end 27.247596 -349.290132)
		(width 0.127)
		(layer "In2.Cu")
		(net "T8_BLAD3_EN")
	)
	(segment
		(start 8.093964 -288.434272)
		(end 9.571228 -288.434272)
		(width 0.127)
		(layer "In2.Cu")
		(net "T8_BLAD3_EN")
	)
	(segment
		(start 3.949954 -288.669984)
		(end 4.964176 -288.669984)
		(width 0.127)
		(layer "In2.Cu")
		(net "T8_BLAD3_EN")
	)
	(segment
		(start 9.571228 -288.434272)
		(end 10.470388 -287.535112)
		(width 0.127)
		(layer "In2.Cu")
		(net "T8_BLAD3_EN")
	)
	(segment
		(start 29.51099 -351.553526)
		(end 44.846748 -351.553526)
		(width 0.127)
		(layer "In2.Cu")
		(net "T8_BLAD3_EN")
	)
	(via
		(at 84.643468 -324.309486)
		(size 0.508)
		(drill 0.254)
		(layers "F.Cu" "B.Cu")
		(net "T8_BLAD4_EN")
	)
	(segment
		(start 87.217504 -321.73545)
		(end 87.217504 -319.672208)
		(width 0.127)
		(layer "In2.Cu")
		(net "T8_BLAD4_EN")
	)
	(segment
		(start 21.749766 -286.712152)
		(end 27.91841 -292.880796)
		(width 0.127)
		(layer "In2.Cu")
		(net "T8_BLAD4_EN")
	)
	(segment
		(start 29.817314 -350.814386)
		(end 43.996356 -350.814386)
		(width 0.127)
		(layer "In2.Cu")
		(net "T8_BLAD4_EN")
	)
	(segment
		(start 4.161028 -287.469072)
		(end 6.075934 -285.554166)
		(width 0.127)
		(layer "In2.Cu")
		(net "T8_BLAD4_EN")
	)
	(segment
		(start 2.831338 -287.669732)
		(end 3.031998 -287.469072)
		(width 0.127)
		(layer "In2.Cu")
		(net "T8_BLAD4_EN")
	)
	(segment
		(start 1.949958 -287.669732)
		(end 2.831338 -287.669732)
		(width 0.127)
		(layer "In2.Cu")
		(net "T8_BLAD4_EN")
	)
	(segment
		(start 8.852408 -286.481012)
		(end 9.083548 -286.712152)
		(width 0.127)
		(layer "In2.Cu")
		(net "T8_BLAD4_EN")
	)
	(segment
		(start 87.732616 -319.157096)
		(end 87.732616 -318.231266)
		(width 0.127)
		(layer "In2.Cu")
		(net "T8_BLAD4_EN")
	)
	(segment
		(start 87.352632 -317.050928)
		(end 88.24849 -316.15507)
		(width 0.127)
		(layer "In2.Cu")
		(net "T8_BLAD4_EN")
	)
	(segment
		(start 9.083548 -286.712152)
		(end 21.749766 -286.712152)
		(width 0.127)
		(layer "In2.Cu")
		(net "T8_BLAD4_EN")
	)
	(segment
		(start 27.91841 -292.880796)
		(end 27.91841 -348.915482)
		(width 0.127)
		(layer "In2.Cu")
		(net "T8_BLAD4_EN")
	)
	(segment
		(start 6.075934 -285.554166)
		(end 7.231888 -285.554166)
		(width 0.127)
		(layer "In2.Cu")
		(net "T8_BLAD4_EN")
	)
	(segment
		(start 7.231888 -285.554166)
		(end 8.158734 -286.481012)
		(width 0.127)
		(layer "In2.Cu")
		(net "T8_BLAD4_EN")
	)
	(segment
		(start 45.863002 -348.94774)
		(end 60.005214 -348.94774)
		(width 0.127)
		(layer "In2.Cu")
		(net "T8_BLAD4_EN")
	)
	(segment
		(start 27.91841 -348.915482)
		(end 29.817314 -350.814386)
		(width 0.127)
		(layer "In2.Cu")
		(net "T8_BLAD4_EN")
	)
	(segment
		(start 88.24849 -316.15507)
		(end 89.44991 -316.15507)
		(width 0.127)
		(layer "In2.Cu")
		(net "T8_BLAD4_EN")
	)
	(segment
		(start 43.996356 -350.814386)
		(end 45.863002 -348.94774)
		(width 0.127)
		(layer "In2.Cu")
		(net "T8_BLAD4_EN")
	)
	(segment
		(start 87.352632 -317.851282)
		(end 87.352632 -317.050928)
		(width 0.127)
		(layer "In2.Cu")
		(net "T8_BLAD4_EN")
	)
	(segment
		(start 84.643468 -324.309486)
		(end 87.217504 -321.73545)
		(width 0.127)
		(layer "In2.Cu")
		(net "T8_BLAD4_EN")
	)
	(segment
		(start 87.217504 -319.672208)
		(end 87.732616 -319.157096)
		(width 0.127)
		(layer "In2.Cu")
		(net "T8_BLAD4_EN")
	)
	(segment
		(start 87.732616 -318.231266)
		(end 87.352632 -317.851282)
		(width 0.127)
		(layer "In2.Cu")
		(net "T8_BLAD4_EN")
	)
	(segment
		(start 8.158734 -286.481012)
		(end 8.852408 -286.481012)
		(width 0.127)
		(layer "In2.Cu")
		(net "T8_BLAD4_EN")
	)
	(segment
		(start 3.031998 -287.469072)
		(end 4.161028 -287.469072)
		(width 0.127)
		(layer "In2.Cu")
		(net "T8_BLAD4_EN")
	)
	(segment
		(start 60.005214 -348.94774)
		(end 84.643468 -324.309486)
		(width 0.127)
		(layer "In2.Cu")
		(net "T8_BLAD4_EN")
	)
	(via
		(at 85.863938 -325.780146)
		(size 0.508)
		(drill 0.254)
		(layers "F.Cu" "B.Cu")
		(net "T8_BLAD2_EN")
	)
	(segment
		(start 7.72668 -288.863786)
		(end 9.80821 -288.863786)
		(width 0.127)
		(layer "In2.Cu")
		(net "T8_BLAD2_EN")
	)
	(segment
		(start 89.44991 -322.194174)
		(end 85.863938 -325.780146)
		(width 0.127)
		(layer "In2.Cu")
		(net "T8_BLAD2_EN")
	)
	(segment
		(start 4.445254 -289.669728)
		(end 6.186424 -287.928558)
		(width 0.127)
		(layer "In2.Cu")
		(net "T8_BLAD2_EN")
	)
	(segment
		(start 6.186424 -287.928558)
		(end 6.791452 -287.928558)
		(width 0.127)
		(layer "In2.Cu")
		(net "T8_BLAD2_EN")
	)
	(segment
		(start 21.573236 -288.020252)
		(end 26.868882 -293.315898)
		(width 0.127)
		(layer "In2.Cu")
		(net "T8_BLAD2_EN")
	)
	(segment
		(start 26.868882 -349.447104)
		(end 29.354018 -351.93224)
		(width 0.127)
		(layer "In2.Cu")
		(net "T8_BLAD2_EN")
	)
	(segment
		(start 6.791452 -287.928558)
		(end 7.72668 -288.863786)
		(width 0.127)
		(layer "In2.Cu")
		(net "T8_BLAD2_EN")
	)
	(segment
		(start 9.80821 -288.863786)
		(end 10.651744 -288.020252)
		(width 0.127)
		(layer "In2.Cu")
		(net "T8_BLAD2_EN")
	)
	(segment
		(start 89.44991 -318.69507)
		(end 89.44991 -322.194174)
		(width 0.127)
		(layer "In2.Cu")
		(net "T8_BLAD2_EN")
	)
	(segment
		(start 29.354018 -351.93224)
		(end 59.711844 -351.93224)
		(width 0.127)
		(layer "In2.Cu")
		(net "T8_BLAD2_EN")
	)
	(segment
		(start 59.711844 -351.93224)
		(end 85.863938 -325.780146)
		(width 0.127)
		(layer "In2.Cu")
		(net "T8_BLAD2_EN")
	)
	(segment
		(start 10.651744 -288.020252)
		(end 21.573236 -288.020252)
		(width 0.127)
		(layer "In2.Cu")
		(net "T8_BLAD2_EN")
	)
	(segment
		(start 1.949958 -289.669728)
		(end 4.445254 -289.669728)
		(width 0.127)
		(layer "In2.Cu")
		(net "T8_BLAD2_EN")
	)
	(segment
		(start 26.868882 -293.315898)
		(end 26.868882 -349.447104)
		(width 0.127)
		(layer "In2.Cu")
		(net "T8_BLAD2_EN")
	)
	(via
		(at 81.782412 -325.649844)
		(size 0.508)
		(drill 0.254)
		(layers "F.Cu" "B.Cu")
		(net "T8_BLAD1_TXD")
	)
	(segment
		(start 85.63991 -321.792346)
		(end 81.782412 -325.649844)
		(width 0.127)
		(layer "In2.Cu")
		(net "T8_BLAD1_TXD")
	)
	(segment
		(start 5.09778 -283.522166)
		(end 7.270242 -283.522166)
		(width 0.127)
		(layer "In2.Cu")
		(net "T8_BLAD1_TXD")
	)
	(segment
		(start 20.998942 -285.005272)
		(end 28.594304 -292.600634)
		(width 0.127)
		(layer "In2.Cu")
		(net "T8_BLAD1_TXD")
	)
	(segment
		(start 7.270242 -283.522166)
		(end 8.251952 -284.503876)
		(width 0.127)
		(layer "In2.Cu")
		(net "T8_BLAD1_TXD")
	)
	(segment
		(start 9.393428 -284.503876)
		(end 9.894824 -285.005272)
		(width 0.127)
		(layer "In2.Cu")
		(net "T8_BLAD1_TXD")
	)
	(segment
		(start 30.211522 -349.98279)
		(end 43.294046 -349.98279)
		(width 0.127)
		(layer "In2.Cu")
		(net "T8_BLAD1_TXD")
	)
	(segment
		(start 3.949954 -284.669992)
		(end 5.09778 -283.522166)
		(width 0.127)
		(layer "In2.Cu")
		(net "T8_BLAD1_TXD")
	)
	(segment
		(start 28.594304 -348.365572)
		(end 30.211522 -349.98279)
		(width 0.127)
		(layer "In2.Cu")
		(net "T8_BLAD1_TXD")
	)
	(segment
		(start 43.294046 -349.98279)
		(end 45.357034 -347.919802)
		(width 0.127)
		(layer "In2.Cu")
		(net "T8_BLAD1_TXD")
	)
	(segment
		(start 45.357034 -347.919802)
		(end 59.512454 -347.919802)
		(width 0.127)
		(layer "In2.Cu")
		(net "T8_BLAD1_TXD")
	)
	(segment
		(start 8.251952 -284.503876)
		(end 9.393428 -284.503876)
		(width 0.127)
		(layer "In2.Cu")
		(net "T8_BLAD1_TXD")
	)
	(segment
		(start 28.594304 -292.600634)
		(end 28.594304 -348.365572)
		(width 0.127)
		(layer "In2.Cu")
		(net "T8_BLAD1_TXD")
	)
	(segment
		(start 59.512454 -347.919802)
		(end 81.782412 -325.649844)
		(width 0.127)
		(layer "In2.Cu")
		(net "T8_BLAD1_TXD")
	)
	(segment
		(start 85.63991 -319.96507)
		(end 85.63991 -321.792346)
		(width 0.127)
		(layer "In2.Cu")
		(net "T8_BLAD1_TXD")
	)
	(segment
		(start 9.894824 -285.005272)
		(end 20.998942 -285.005272)
		(width 0.127)
		(layer "In2.Cu")
		(net "T8_BLAD1_TXD")
	)
	(via
		(at 83.172808 -324.979538)
		(size 0.508)
		(drill 0.254)
		(layers "F.Cu" "B.Cu")
		(net "T8_BLAD1_RXD")
	)
	(segment
		(start 5.7658 -283.958792)
		(end 6.978904 -283.958792)
		(width 0.127)
		(layer "In2.Cu")
		(net "T8_BLAD1_RXD")
	)
	(segment
		(start 9.708642 -285.347918)
		(end 20.856956 -285.347918)
		(width 0.127)
		(layer "In2.Cu")
		(net "T8_BLAD1_RXD")
	)
	(segment
		(start 86.90991 -319.506854)
		(end 86.532212 -319.884552)
		(width 0.127)
		(layer "In2.Cu")
		(net "T8_BLAD1_RXD")
	)
	(segment
		(start 6.978904 -283.958792)
		(end 7.871714 -284.851602)
		(width 0.127)
		(layer "In2.Cu")
		(net "T8_BLAD1_RXD")
	)
	(segment
		(start 59.654948 -348.497398)
		(end 83.172808 -324.979538)
		(width 0.127)
		(layer "In2.Cu")
		(net "T8_BLAD1_RXD")
	)
	(segment
		(start 28.251658 -348.636336)
		(end 30.03169 -350.416368)
		(width 0.127)
		(layer "In2.Cu")
		(net "T8_BLAD1_RXD")
	)
	(segment
		(start 28.251658 -292.74262)
		(end 28.251658 -348.636336)
		(width 0.127)
		(layer "In2.Cu")
		(net "T8_BLAD1_RXD")
	)
	(segment
		(start 9.212326 -284.851602)
		(end 9.708642 -285.347918)
		(width 0.127)
		(layer "In2.Cu")
		(net "T8_BLAD1_RXD")
	)
	(segment
		(start 86.532212 -321.620134)
		(end 83.172808 -324.979538)
		(width 0.127)
		(layer "In2.Cu")
		(net "T8_BLAD1_RXD")
	)
	(segment
		(start 86.90991 -318.69507)
		(end 86.90991 -319.506854)
		(width 0.127)
		(layer "In2.Cu")
		(net "T8_BLAD1_RXD")
	)
	(segment
		(start 1.949958 -285.669736)
		(end 4.054856 -285.669736)
		(width 0.127)
		(layer "In2.Cu")
		(net "T8_BLAD1_RXD")
	)
	(segment
		(start 7.871714 -284.851602)
		(end 9.212326 -284.851602)
		(width 0.127)
		(layer "In2.Cu")
		(net "T8_BLAD1_RXD")
	)
	(segment
		(start 43.561508 -350.416368)
		(end 45.480478 -348.497398)
		(width 0.127)
		(layer "In2.Cu")
		(net "T8_BLAD1_RXD")
	)
	(segment
		(start 4.054856 -285.669736)
		(end 5.7658 -283.958792)
		(width 0.127)
		(layer "In2.Cu")
		(net "T8_BLAD1_RXD")
	)
	(segment
		(start 86.532212 -319.884552)
		(end 86.532212 -321.620134)
		(width 0.127)
		(layer "In2.Cu")
		(net "T8_BLAD1_RXD")
	)
	(segment
		(start 30.03169 -350.416368)
		(end 43.561508 -350.416368)
		(width 0.127)
		(layer "In2.Cu")
		(net "T8_BLAD1_RXD")
	)
	(segment
		(start 45.480478 -348.497398)
		(end 59.654948 -348.497398)
		(width 0.127)
		(layer "In2.Cu")
		(net "T8_BLAD1_RXD")
	)
	(segment
		(start 20.856956 -285.347918)
		(end 28.251658 -292.74262)
		(width 0.127)
		(layer "In2.Cu")
		(net "T8_BLAD1_RXD")
	)
	(via
		(at 97.352104 -300.770544)
		(size 0.508)
		(drill 0.254)
		(layers "F.Cu" "B.Cu")
		(net "T8_BLAD4_RXD")
	)
	(segment
		(start 5.22351 -277.396194)
		(end 3.949954 -278.66975)
		(width 0.127)
		(layer "In5.Cu")
		(net "T8_BLAD4_RXD")
	)
	(segment
		(start 8.057134 -274.796504)
		(end 7.031482 -275.822156)
		(width 0.127)
		(layer "In5.Cu")
		(net "T8_BLAD4_RXD")
	)
	(segment
		(start 100.341176 -273.731482)
		(end 94.629986 -268.020292)
		(width 0.127)
		(layer "In5.Cu")
		(net "T8_BLAD4_RXD")
	)
	(segment
		(start 97.352104 -300.770544)
		(end 97.352104 -292.173406)
		(width 0.127)
		(layer "In5.Cu")
		(net "T8_BLAD4_RXD")
	)
	(segment
		(start 7.031482 -275.822156)
		(end 6.141212 -275.822156)
		(width 0.127)
		(layer "In5.Cu")
		(net "T8_BLAD4_RXD")
	)
	(segment
		(start 10.704322 -274.796504)
		(end 8.057134 -274.796504)
		(width 0.127)
		(layer "In5.Cu")
		(net "T8_BLAD4_RXD")
	)
	(segment
		(start 76.105004 -267.21054)
		(end 18.29308 -267.21054)
		(width 0.127)
		(layer "In5.Cu")
		(net "T8_BLAD4_RXD")
	)
	(segment
		(start 6.141212 -275.822156)
		(end 5.22351 -276.739858)
		(width 0.127)
		(layer "In5.Cu")
		(net "T8_BLAD4_RXD")
	)
	(segment
		(start 94.629986 -268.020292)
		(end 76.914756 -268.020292)
		(width 0.127)
		(layer "In5.Cu")
		(net "T8_BLAD4_RXD")
	)
	(segment
		(start 91.98991 -316.15507)
		(end 97.352104 -310.792876)
		(width 0.127)
		(layer "In5.Cu")
		(net "T8_BLAD4_RXD")
	)
	(segment
		(start 11.679936 -273.823684)
		(end 10.704322 -274.796504)
		(width 0.127)
		(layer "In5.Cu")
		(net "T8_BLAD4_RXD")
	)
	(segment
		(start 5.22351 -276.739858)
		(end 5.22351 -277.396194)
		(width 0.127)
		(layer "In5.Cu")
		(net "T8_BLAD4_RXD")
	)
	(segment
		(start 18.29308 -267.21054)
		(end 11.679936 -273.823684)
		(width 0.127)
		(layer "In5.Cu")
		(net "T8_BLAD4_RXD")
	)
	(segment
		(start 97.352104 -310.792876)
		(end 97.352104 -300.770544)
		(width 0.127)
		(layer "In5.Cu")
		(net "T8_BLAD4_RXD")
	)
	(segment
		(start 76.914756 -268.020292)
		(end 76.105004 -267.21054)
		(width 0.127)
		(layer "In5.Cu")
		(net "T8_BLAD4_RXD")
	)
	(segment
		(start 97.352104 -292.173406)
		(end 100.341176 -289.184334)
		(width 0.127)
		(layer "In5.Cu")
		(net "T8_BLAD4_RXD")
	)
	(segment
		(start 100.341176 -289.184334)
		(end 100.341176 -273.731482)
		(width 0.127)
		(layer "In5.Cu")
		(net "T8_BLAD4_RXD")
	)
	(via
		(at 94.913196 -304.791618)
		(size 0.508)
		(drill 0.254)
		(layers "F.Cu" "B.Cu")
		(net "T8_BLAD2_RXD")
	)
	(segment
		(start 84.854288 -317.014352)
		(end 84.854288 -320.276728)
		(width 0.127)
		(layer "In5.Cu")
		(net "T8_BLAD2_RXD")
	)
	(segment
		(start 9.32815 -278.50465)
		(end 10.342372 -277.490428)
		(width 0.127)
		(layer "In5.Cu")
		(net "T8_BLAD2_RXD")
	)
	(segment
		(start 18.75409 -268.319504)
		(end 71.417688 -268.319504)
		(width 0.127)
		(layer "In5.Cu")
		(net "T8_BLAD2_RXD")
	)
	(segment
		(start 10.342372 -277.490428)
		(end 10.342372 -276.731222)
		(width 0.127)
		(layer "In5.Cu")
		(net "T8_BLAD2_RXD")
	)
	(segment
		(start 4.747768 -280.65984)
		(end 5.85343 -279.554178)
		(width 0.127)
		(layer "In5.Cu")
		(net "T8_BLAD2_RXD")
	)
	(segment
		(start 6.864604 -279.554178)
		(end 6.95452 -279.464262)
		(width 0.127)
		(layer "In5.Cu")
		(net "T8_BLAD2_RXD")
	)
	(segment
		(start 94.467426 -269.389098)
		(end 99.186746 -274.108418)
		(width 0.127)
		(layer "In5.Cu")
		(net "T8_BLAD2_RXD")
	)
	(segment
		(start 94.913196 -292.979348)
		(end 94.913196 -304.791618)
		(width 0.127)
		(layer "In5.Cu")
		(net "T8_BLAD2_RXD")
	)
	(segment
		(start 3.960368 -281.65933)
		(end 4.252722 -281.65933)
		(width 0.127)
		(layer "In5.Cu")
		(net "T8_BLAD2_RXD")
	)
	(segment
		(start 85.64118 -321.06362)
		(end 88.366092 -321.06362)
		(width 0.127)
		(layer "In5.Cu")
		(net "T8_BLAD2_RXD")
	)
	(segment
		(start 71.417688 -268.319504)
		(end 72.487282 -269.389098)
		(width 0.127)
		(layer "In5.Cu")
		(net "T8_BLAD2_RXD")
	)
	(segment
		(start 1.949958 -283.66974)
		(end 3.960368 -281.65933)
		(width 0.127)
		(layer "In5.Cu")
		(net "T8_BLAD2_RXD")
	)
	(segment
		(start 88.366092 -321.06362)
		(end 90.734642 -318.69507)
		(width 0.127)
		(layer "In5.Cu")
		(net "T8_BLAD2_RXD")
	)
	(segment
		(start 94.913196 -306.955444)
		(end 84.854288 -317.014352)
		(width 0.127)
		(layer "In5.Cu")
		(net "T8_BLAD2_RXD")
	)
	(segment
		(start 4.252722 -281.65933)
		(end 4.747768 -281.164284)
		(width 0.127)
		(layer "In5.Cu")
		(net "T8_BLAD2_RXD")
	)
	(segment
		(start 4.747768 -281.164284)
		(end 4.747768 -280.65984)
		(width 0.127)
		(layer "In5.Cu")
		(net "T8_BLAD2_RXD")
	)
	(segment
		(start 90.734642 -318.69507)
		(end 91.98991 -318.69507)
		(width 0.127)
		(layer "In5.Cu")
		(net "T8_BLAD2_RXD")
	)
	(segment
		(start 5.85343 -279.554178)
		(end 6.864604 -279.554178)
		(width 0.127)
		(layer "In5.Cu")
		(net "T8_BLAD2_RXD")
	)
	(segment
		(start 10.342372 -276.731222)
		(end 18.75409 -268.319504)
		(width 0.127)
		(layer "In5.Cu")
		(net "T8_BLAD2_RXD")
	)
	(segment
		(start 99.186746 -274.108418)
		(end 99.186746 -288.705798)
		(width 0.127)
		(layer "In5.Cu")
		(net "T8_BLAD2_RXD")
	)
	(segment
		(start 6.95452 -279.463246)
		(end 7.913116 -278.50465)
		(width 0.127)
		(layer "In5.Cu")
		(net "T8_BLAD2_RXD")
	)
	(segment
		(start 72.487282 -269.389098)
		(end 94.467426 -269.389098)
		(width 0.127)
		(layer "In5.Cu")
		(net "T8_BLAD2_RXD")
	)
	(segment
		(start 84.854288 -320.276728)
		(end 85.64118 -321.06362)
		(width 0.127)
		(layer "In5.Cu")
		(net "T8_BLAD2_RXD")
	)
	(segment
		(start 7.913116 -278.50465)
		(end 9.32815 -278.50465)
		(width 0.127)
		(layer "In5.Cu")
		(net "T8_BLAD2_RXD")
	)
	(segment
		(start 6.95452 -279.464262)
		(end 6.95452 -279.463246)
		(width 0.127)
		(layer "In5.Cu")
		(net "T8_BLAD2_RXD")
	)
	(segment
		(start 94.913196 -304.791618)
		(end 94.913196 -306.955444)
		(width 0.127)
		(layer "In5.Cu")
		(net "T8_BLAD2_RXD")
	)
	(segment
		(start 99.186746 -288.705798)
		(end 94.913196 -292.979348)
		(width 0.127)
		(layer "In5.Cu")
		(net "T8_BLAD2_RXD")
	)
	(segment
		(start 27.45486 -12.146788)
		(end 27.28087 -12.320778)
		(width 0.1524)
		(layer "F.Cu")
		(net "PSU1_PS_ON_N")
	)
	(segment
		(start 27.45486 -11.75639)
		(end 27.45486 -12.146788)
		(width 0.1524)
		(layer "F.Cu")
		(net "PSU1_PS_ON_N")
	)
	(segment
		(start 28.840684 -12.632182)
		(end 29.262832 -12.210034)
		(width 0.1524)
		(layer "F.Cu")
		(net "PSU1_PS_ON_N")
	)
	(segment
		(start 29.262832 -12.210034)
		(end 30.45968 -12.210034)
		(width 0.1524)
		(layer "F.Cu")
		(net "PSU1_PS_ON_N")
	)
	(segment
		(start 27.28087 -12.674092)
		(end 27.32278 -12.632182)
		(width 0.1524)
		(layer "F.Cu")
		(net "PSU1_PS_ON_N")
	)
	(segment
		(start 27.28087 -12.320778)
		(end 27.28087 -12.674092)
		(width 0.1524)
		(layer "F.Cu")
		(net "PSU1_PS_ON_N")
	)
	(segment
		(start 27.32278 -12.632182)
		(end 28.840684 -12.632182)
		(width 0.1524)
		(layer "F.Cu")
		(net "PSU1_PS_ON_N")
	)
	(via
		(at 27.28087 -12.674092)
		(size 0.508)
		(drill 0.254)
		(layers "F.Cu" "B.Cu")
		(net "PSU1_PS_ON_N")
	)
	(via
		(at 95.623888 -303.529746)
		(size 0.508)
		(drill 0.254)
		(layers "F.Cu" "B.Cu")
		(net "T8_BLAD3_RXD")
	)
	(segment
		(start 71.781416 -267.972032)
		(end 72.666606 -268.857222)
		(width 0.127)
		(layer "In5.Cu")
		(net "T8_BLAD3_RXD")
	)
	(segment
		(start 99.592892 -288.8742)
		(end 95.623888 -292.843204)
		(width 0.127)
		(layer "In5.Cu")
		(net "T8_BLAD3_RXD")
	)
	(segment
		(start 95.623888 -307.44414)
		(end 87.724488 -315.340492)
		(width 0.127)
		(layer "In5.Cu")
		(net "T8_BLAD3_RXD")
	)
	(segment
		(start 18.610072 -267.972032)
		(end 71.781416 -267.972032)
		(width 0.127)
		(layer "In5.Cu")
		(net "T8_BLAD3_RXD")
	)
	(segment
		(start 5.36829 -278.577802)
		(end 6.194552 -277.75154)
		(width 0.127)
		(layer "In5.Cu")
		(net "T8_BLAD3_RXD")
	)
	(segment
		(start 95.623888 -303.529746)
		(end 95.623888 -307.44414)
		(width 0.127)
		(layer "In5.Cu")
		(net "T8_BLAD3_RXD")
	)
	(segment
		(start 87.724488 -315.340492)
		(end 86.90991 -316.15507)
		(width 0.127)
		(layer "In5.Cu")
		(net "T8_BLAD3_RXD")
	)
	(segment
		(start 8.020304 -276.816312)
		(end 9.765792 -276.816312)
		(width 0.127)
		(layer "In5.Cu")
		(net "T8_BLAD3_RXD")
	)
	(segment
		(start 9.765792 -276.816312)
		(end 18.610072 -267.972032)
		(width 0.127)
		(layer "In5.Cu")
		(net "T8_BLAD3_RXD")
	)
	(segment
		(start 5.36829 -279.25141)
		(end 5.36829 -278.577802)
		(width 0.127)
		(layer "In5.Cu")
		(net "T8_BLAD3_RXD")
	)
	(segment
		(start 95.623888 -292.843204)
		(end 95.623888 -303.529746)
		(width 0.127)
		(layer "In5.Cu")
		(net "T8_BLAD3_RXD")
	)
	(segment
		(start 6.194552 -277.75154)
		(end 7.085076 -277.75154)
		(width 0.127)
		(layer "In5.Cu")
		(net "T8_BLAD3_RXD")
	)
	(segment
		(start 7.085076 -277.75154)
		(end 8.020304 -276.816312)
		(width 0.127)
		(layer "In5.Cu")
		(net "T8_BLAD3_RXD")
	)
	(segment
		(start 99.592892 -274.041616)
		(end 99.592892 -288.8742)
		(width 0.127)
		(layer "In5.Cu")
		(net "T8_BLAD3_RXD")
	)
	(segment
		(start 72.666606 -268.857222)
		(end 94.408498 -268.857222)
		(width 0.127)
		(layer "In5.Cu")
		(net "T8_BLAD3_RXD")
	)
	(segment
		(start 3.949954 -280.669746)
		(end 5.36829 -279.25141)
		(width 0.127)
		(layer "In5.Cu")
		(net "T8_BLAD3_RXD")
	)
	(segment
		(start 94.408498 -268.857222)
		(end 99.592892 -274.041616)
		(width 0.127)
		(layer "In5.Cu")
		(net "T8_BLAD3_RXD")
	)
	(via
		(at 96.35109 -302.203612)
		(size 0.508)
		(drill 0.254)
		(layers "F.Cu" "B.Cu")
		(net "T8_BLAD3_TXD")
	)
	(segment
		(start 18.438368 -267.558012)
		(end 73.115932 -267.558012)
		(width 0.127)
		(layer "In5.Cu")
		(net "T8_BLAD3_TXD")
	)
	(segment
		(start 94.487746 -268.469364)
		(end 99.923092 -273.90471)
		(width 0.127)
		(layer "In5.Cu")
		(net "T8_BLAD3_TXD")
	)
	(segment
		(start 7.879588 -276.476968)
		(end 9.519412 -276.476968)
		(width 0.127)
		(layer "In5.Cu")
		(net "T8_BLAD3_TXD")
	)
	(segment
		(start 4.136136 -279.669748)
		(end 5.028946 -278.776938)
		(width 0.127)
		(layer "In5.Cu")
		(net "T8_BLAD3_TXD")
	)
	(segment
		(start 85.63991 -317.42507)
		(end 86.871302 -317.42507)
		(width 0.127)
		(layer "In5.Cu")
		(net "T8_BLAD3_TXD")
	)
	(segment
		(start 99.923092 -273.90471)
		(end 99.923092 -289.011106)
		(width 0.127)
		(layer "In5.Cu")
		(net "T8_BLAD3_TXD")
	)
	(segment
		(start 73.115932 -267.558012)
		(end 74.027284 -268.469364)
		(width 0.127)
		(layer "In5.Cu")
		(net "T8_BLAD3_TXD")
	)
	(segment
		(start 5.028946 -278.437086)
		(end 6.053836 -277.412196)
		(width 0.127)
		(layer "In5.Cu")
		(net "T8_BLAD3_TXD")
	)
	(segment
		(start 96.35109 -307.945282)
		(end 96.35109 -302.203612)
		(width 0.127)
		(layer "In5.Cu")
		(net "T8_BLAD3_TXD")
	)
	(segment
		(start 9.519412 -276.476968)
		(end 18.438368 -267.558012)
		(width 0.127)
		(layer "In5.Cu")
		(net "T8_BLAD3_TXD")
	)
	(segment
		(start 6.94436 -277.412196)
		(end 7.879588 -276.476968)
		(width 0.127)
		(layer "In5.Cu")
		(net "T8_BLAD3_TXD")
	)
	(segment
		(start 96.35109 -292.583108)
		(end 96.35109 -302.203612)
		(width 0.127)
		(layer "In5.Cu")
		(net "T8_BLAD3_TXD")
	)
	(segment
		(start 74.027284 -268.469364)
		(end 94.487746 -268.469364)
		(width 0.127)
		(layer "In5.Cu")
		(net "T8_BLAD3_TXD")
	)
	(segment
		(start 86.871302 -317.42507)
		(end 96.35109 -307.945282)
		(width 0.127)
		(layer "In5.Cu")
		(net "T8_BLAD3_TXD")
	)
	(segment
		(start 1.949958 -279.669748)
		(end 4.136136 -279.669748)
		(width 0.127)
		(layer "In5.Cu")
		(net "T8_BLAD3_TXD")
	)
	(segment
		(start 99.923092 -289.011106)
		(end 96.35109 -292.583108)
		(width 0.127)
		(layer "In5.Cu")
		(net "T8_BLAD3_TXD")
	)
	(segment
		(start 6.053836 -277.412196)
		(end 6.94436 -277.412196)
		(width 0.127)
		(layer "In5.Cu")
		(net "T8_BLAD3_TXD")
	)
	(segment
		(start 5.028946 -278.776938)
		(end 5.028946 -278.437086)
		(width 0.127)
		(layer "In5.Cu")
		(net "T8_BLAD3_TXD")
	)
	(segment
		(start 35.53968 -459.289912)
		(end 36.674806 -459.289912)
		(width 0.1524)
		(layer "F.Cu")
		(net "PSU6_AD0")
	)
	(segment
		(start 40.273986 -461.994758)
		(end 39.474902 -461.195674)
		(width 0.1524)
		(layer "F.Cu")
		(net "PSU6_AD0")
	)
	(segment
		(start 39.474902 -460.713074)
		(end 39.474902 -461.170274)
		(width 0.1524)
		(layer "F.Cu")
		(net "PSU6_AD0")
	)
	(segment
		(start 39.474902 -461.195674)
		(end 39.474902 -461.170274)
		(width 0.1524)
		(layer "F.Cu")
		(net "PSU6_AD0")
	)
	(segment
		(start 37.555932 -459.289658)
		(end 38.051486 -459.289658)
		(width 0.1524)
		(layer "F.Cu")
		(net "PSU6_AD0")
	)
	(segment
		(start 40.273986 -462.37144)
		(end 40.273986 -461.994758)
		(width 0.1524)
		(layer "F.Cu")
		(net "PSU6_AD0")
	)
	(segment
		(start 38.051486 -459.289658)
		(end 39.474902 -460.713074)
		(width 0.1524)
		(layer "F.Cu")
		(net "PSU6_AD0")
	)
	(segment
		(start 36.674806 -459.289912)
		(end 37.555932 -459.289658)
		(width 0.1524)
		(layer "F.Cu")
		(net "PSU6_AD0")
	)
	(segment
		(start 37.555932 -282.489656)
		(end 37.762434 -282.696158)
		(width 0.1524)
		(layer "F.Cu")
		(net "PSU4_AD0")
	)
	(segment
		(start 36.997894 -282.48991)
		(end 37.555932 -282.489656)
		(width 0.1524)
		(layer "F.Cu")
		(net "PSU4_AD0")
	)
	(segment
		(start 35.53968 -282.48991)
		(end 36.997894 -282.48991)
		(width 0.1524)
		(layer "F.Cu")
		(net "PSU4_AD0")
	)
	(segment
		(start 40.401748 -282.696158)
		(end 40.40378 -282.69819)
		(width 0.1524)
		(layer "F.Cu")
		(net "PSU4_AD0")
	)
	(segment
		(start 40.40378 -282.69819)
		(end 40.86098 -282.69819)
		(width 0.1524)
		(layer "F.Cu")
		(net "PSU4_AD0")
	)
	(segment
		(start 37.762434 -282.696158)
		(end 39.653718 -282.696158)
		(width 0.1524)
		(layer "F.Cu")
		(net "PSU4_AD0")
	)
	(segment
		(start 39.653718 -282.696158)
		(end 40.401748 -282.696158)
		(width 0.1524)
		(layer "F.Cu")
		(net "PSU4_AD0")
	)
	(segment
		(start 28.038806 -19.83994)
		(end 28.019502 -19.859244)
		(width 0.508)
		(layer "F.Cu")
		(net "PSU1_REMOTE_N")
	)
	(segment
		(start 30.442662 -19.847052)
		(end 28.045918 -19.847052)
		(width 0.508)
		(layer "F.Cu")
		(net "PSU1_REMOTE_N")
	)
	(segment
		(start 28.045918 -19.847052)
		(end 28.038806 -19.83994)
		(width 0.508)
		(layer "F.Cu")
		(net "PSU1_REMOTE_N")
	)
	(segment
		(start 30.45968 -19.830034)
		(end 30.442662 -19.847052)
		(width 0.508)
		(layer "F.Cu")
		(net "PSU1_REMOTE_N")
	)
	(segment
		(start 28.019502 -19.859244)
		(end 27.250898 -19.859244)
		(width 0.508)
		(layer "F.Cu")
		(net "PSU1_REMOTE_N")
	)
	(via
		(at 80.668368 -267.4747)
		(size 0.508)
		(drill 0.254)
		(layers "F.Cu" "B.Cu")
		(net "T7_BLAD3_TXD")
	)
	(segment
		(start 85.63991 -272.446242)
		(end 80.668368 -267.4747)
		(width 0.127)
		(layer "In2.Cu")
		(net "T7_BLAD3_TXD")
	)
	(segment
		(start 80.134968 -266.9413)
		(end 80.668368 -267.4747)
		(width 0.127)
		(layer "In2.Cu")
		(net "T7_BLAD3_TXD")
	)
	(segment
		(start 12.605512 -275.669756)
		(end 21.333968 -266.9413)
		(width 0.127)
		(layer "In2.Cu")
		(net "T7_BLAD3_TXD")
	)
	(segment
		(start 85.63991 -272.97507)
		(end 85.63991 -272.446242)
		(width 0.127)
		(layer "In2.Cu")
		(net "T7_BLAD3_TXD")
	)
	(segment
		(start 8.449818 -275.669756)
		(end 12.605512 -275.669756)
		(width 0.127)
		(layer "In2.Cu")
		(net "T7_BLAD3_TXD")
	)
	(segment
		(start 21.333968 -266.9413)
		(end 80.134968 -266.9413)
		(width 0.127)
		(layer "In2.Cu")
		(net "T7_BLAD3_TXD")
	)
	(via
		(at 88.86317 -280.492708)
		(size 0.508)
		(drill 0.254)
		(layers "F.Cu" "B.Cu")
		(net "T7_BLAD2_EN")
	)
	(segment
		(start 81.275682 -323.795136)
		(end 84.183982 -320.886836)
		(width 0.127)
		(layer "In5.Cu")
		(net "T7_BLAD2_EN")
	)
	(segment
		(start 22.323806 -285.669736)
		(end 23.600918 -286.946848)
		(width 0.127)
		(layer "In5.Cu")
		(net "T7_BLAD2_EN")
	)
	(segment
		(start 85.607906 -283.747972)
		(end 88.86317 -280.492708)
		(width 0.127)
		(layer "In5.Cu")
		(net "T7_BLAD2_EN")
	)
	(segment
		(start 29.825696 -351.954846)
		(end 59.349132 -351.954846)
		(width 0.127)
		(layer "In5.Cu")
		(net "T7_BLAD2_EN")
	)
	(segment
		(start 81.275682 -330.028296)
		(end 81.275682 -323.795136)
		(width 0.127)
		(layer "In5.Cu")
		(net "T7_BLAD2_EN")
	)
	(segment
		(start 89.44991 -279.905968)
		(end 88.86317 -280.492708)
		(width 0.127)
		(layer "In5.Cu")
		(net "T7_BLAD2_EN")
	)
	(segment
		(start 27.61107 -349.74022)
		(end 29.825696 -351.954846)
		(width 0.127)
		(layer "In5.Cu")
		(net "T7_BLAD2_EN")
	)
	(segment
		(start 92.397834 -297.883326)
		(end 85.607906 -291.093398)
		(width 0.127)
		(layer "In5.Cu")
		(net "T7_BLAD2_EN")
	)
	(segment
		(start 92.397834 -307.609748)
		(end 92.397834 -297.883326)
		(width 0.127)
		(layer "In5.Cu")
		(net "T7_BLAD2_EN")
	)
	(segment
		(start 85.607906 -291.093398)
		(end 85.607906 -283.747972)
		(width 0.127)
		(layer "In5.Cu")
		(net "T7_BLAD2_EN")
	)
	(segment
		(start 59.349132 -351.954846)
		(end 81.275682 -330.028296)
		(width 0.127)
		(layer "In5.Cu")
		(net "T7_BLAD2_EN")
	)
	(segment
		(start 89.44991 -274.24507)
		(end 89.44991 -279.905968)
		(width 0.127)
		(layer "In5.Cu")
		(net "T7_BLAD2_EN")
	)
	(segment
		(start 23.600918 -286.946848)
		(end 27.61107 -290.956746)
		(width 0.127)
		(layer "In5.Cu")
		(net "T7_BLAD2_EN")
	)
	(segment
		(start 84.183982 -315.8236)
		(end 92.397834 -307.609748)
		(width 0.127)
		(layer "In5.Cu")
		(net "T7_BLAD2_EN")
	)
	(segment
		(start 27.61107 -290.956746)
		(end 27.61107 -349.74022)
		(width 0.127)
		(layer "In5.Cu")
		(net "T7_BLAD2_EN")
	)
	(segment
		(start 84.183982 -320.886836)
		(end 84.183982 -315.8236)
		(width 0.127)
		(layer "In5.Cu")
		(net "T7_BLAD2_EN")
	)
	(segment
		(start 8.449818 -285.669736)
		(end 22.323806 -285.669736)
		(width 0.127)
		(layer "In5.Cu")
		(net "T7_BLAD2_EN")
	)
	(segment
		(start 28.087574 -454.209912)
		(end 27.23388 -455.063606)
		(width 0.1524)
		(layer "F.Cu")
		(net "PSU6_PS_ON_N")
	)
	(segment
		(start 27.23388 -455.063606)
		(end 27.069288 -455.063606)
		(width 0.1524)
		(layer "F.Cu")
		(net "PSU6_PS_ON_N")
	)
	(segment
		(start 30.45968 -454.209912)
		(end 28.087574 -454.209912)
		(width 0.1524)
		(layer "F.Cu")
		(net "PSU6_PS_ON_N")
	)
	(segment
		(start 27.069288 -455.063606)
		(end 26.65222 -454.646538)
		(width 0.1524)
		(layer "F.Cu")
		(net "PSU6_PS_ON_N")
	)
	(via
		(at 27.23388 -455.063606)
		(size 0.508)
		(drill 0.254)
		(layers "F.Cu" "B.Cu")
		(net "PSU6_PS_ON_N")
	)
	(via
		(at 87.401146 -281.126692)
		(size 0.508)
		(drill 0.254)
		(layers "F.Cu" "B.Cu")
		(net "T7_BLAD3_EN")
	)
	(segment
		(start 44.287186 -351.610676)
		(end 29.968444 -351.610676)
		(width 0.127)
		(layer "In5.Cu")
		(net "T7_BLAD3_EN")
	)
	(segment
		(start 22.011386 -284.829504)
		(end 7.5057 -284.829504)
		(width 0.127)
		(layer "In5.Cu")
		(net "T7_BLAD3_EN")
	)
	(segment
		(start 29.968444 -351.610676)
		(end 27.95524 -349.597472)
		(width 0.127)
		(layer "In5.Cu")
		(net "T7_BLAD3_EN")
	)
	(segment
		(start 92.053664 -307.467)
		(end 83.839812 -315.680852)
		(width 0.127)
		(layer "In5.Cu")
		(net "T7_BLAD3_EN")
	)
	(segment
		(start 87.401146 -281.126692)
		(end 85.18652 -283.341318)
		(width 0.127)
		(layer "In5.Cu")
		(net "T7_BLAD3_EN")
	)
	(segment
		(start 7.346188 -284.669992)
		(end 6.449822 -284.669992)
		(width 0.127)
		(layer "In5.Cu")
		(net "T7_BLAD3_EN")
	)
	(segment
		(start 85.18652 -283.341318)
		(end 85.18652 -291.15893)
		(width 0.127)
		(layer "In5.Cu")
		(net "T7_BLAD3_EN")
	)
	(segment
		(start 92.053664 -298.026074)
		(end 92.053664 -307.467)
		(width 0.127)
		(layer "In5.Cu")
		(net "T7_BLAD3_EN")
	)
	(segment
		(start 85.18652 -291.15893)
		(end 92.053664 -298.026074)
		(width 0.127)
		(layer "In5.Cu")
		(net "T7_BLAD3_EN")
	)
	(segment
		(start 80.931512 -329.885548)
		(end 61.176154 -349.640906)
		(width 0.127)
		(layer "In5.Cu")
		(net "T7_BLAD3_EN")
	)
	(segment
		(start 46.256956 -349.640906)
		(end 44.287186 -351.610676)
		(width 0.127)
		(layer "In5.Cu")
		(net "T7_BLAD3_EN")
	)
	(segment
		(start 83.839812 -320.744088)
		(end 80.931512 -323.652388)
		(width 0.127)
		(layer "In5.Cu")
		(net "T7_BLAD3_EN")
	)
	(segment
		(start 7.5057 -284.829504)
		(end 7.346188 -284.669992)
		(width 0.127)
		(layer "In5.Cu")
		(net "T7_BLAD3_EN")
	)
	(segment
		(start 88.17991 -274.25269)
		(end 88.17991 -272.97507)
		(width 0.127)
		(layer "In5.Cu")
		(net "T7_BLAD3_EN")
	)
	(segment
		(start 61.176154 -349.640906)
		(end 46.256956 -349.640906)
		(width 0.127)
		(layer "In5.Cu")
		(net "T7_BLAD3_EN")
	)
	(segment
		(start 80.931512 -323.652388)
		(end 80.931512 -329.885548)
		(width 0.127)
		(layer "In5.Cu")
		(net "T7_BLAD3_EN")
	)
	(segment
		(start 87.401146 -281.126692)
		(end 89.036906 -279.490932)
		(width 0.127)
		(layer "In5.Cu")
		(net "T7_BLAD3_EN")
	)
	(segment
		(start 89.036906 -275.109686)
		(end 88.17991 -274.25269)
		(width 0.127)
		(layer "In5.Cu")
		(net "T7_BLAD3_EN")
	)
	(segment
		(start 83.839812 -315.680852)
		(end 83.839812 -320.744088)
		(width 0.127)
		(layer "In5.Cu")
		(net "T7_BLAD3_EN")
	)
	(segment
		(start 89.036906 -279.490932)
		(end 89.036906 -275.109686)
		(width 0.127)
		(layer "In5.Cu")
		(net "T7_BLAD3_EN")
	)
	(segment
		(start 27.95524 -349.597472)
		(end 27.95524 -290.773358)
		(width 0.127)
		(layer "In5.Cu")
		(net "T7_BLAD3_EN")
	)
	(segment
		(start 27.95524 -290.773358)
		(end 22.011386 -284.829504)
		(width 0.127)
		(layer "In5.Cu")
		(net "T7_BLAD3_EN")
	)
	(via
		(at 21.021802 -269.252954)
		(size 0.508)
		(drill 0.254)
		(layers "F.Cu" "B.Cu")
		(net "T7_BLAD2_RXD")
	)
	(segment
		(start 22.18436 -268.090396)
		(end 79.922116 -268.090396)
		(width 0.127)
		(layer "In2.Cu")
		(net "T7_BLAD2_RXD")
	)
	(segment
		(start 21.021802 -269.252954)
		(end 22.18436 -268.090396)
		(width 0.127)
		(layer "In2.Cu")
		(net "T7_BLAD2_RXD")
	)
	(segment
		(start 85.142832 -277.718774)
		(end 89.800684 -277.718774)
		(width 0.127)
		(layer "In2.Cu")
		(net "T7_BLAD2_RXD")
	)
	(segment
		(start 84.169504 -272.337784)
		(end 84.169504 -276.745446)
		(width 0.127)
		(layer "In2.Cu")
		(net "T7_BLAD2_RXD")
	)
	(segment
		(start 79.922116 -268.090396)
		(end 84.169504 -272.337784)
		(width 0.127)
		(layer "In2.Cu")
		(net "T7_BLAD2_RXD")
	)
	(segment
		(start 13.274294 -277.000462)
		(end 21.021802 -269.252954)
		(width 0.127)
		(layer "In2.Cu")
		(net "T7_BLAD2_RXD")
	)
	(segment
		(start 84.169504 -276.745446)
		(end 85.142832 -277.718774)
		(width 0.127)
		(layer "In2.Cu")
		(net "T7_BLAD2_RXD")
	)
	(segment
		(start 89.800684 -277.718774)
		(end 91.98991 -275.529548)
		(width 0.127)
		(layer "In2.Cu")
		(net "T7_BLAD2_RXD")
	)
	(segment
		(start 8.449818 -279.669748)
		(end 11.119104 -277.000462)
		(width 0.127)
		(layer "In2.Cu")
		(net "T7_BLAD2_RXD")
	)
	(segment
		(start 11.119104 -277.000462)
		(end 13.274294 -277.000462)
		(width 0.127)
		(layer "In2.Cu")
		(net "T7_BLAD2_RXD")
	)
	(segment
		(start 91.98991 -275.529548)
		(end 91.98991 -274.24507)
		(width 0.127)
		(layer "In2.Cu")
		(net "T7_BLAD2_RXD")
	)
	(segment
		(start 9.353804 -322.420742)
		(end 7.616698 -322.420742)
		(width 0.1524)
		(layer "F.Cu")
		(net "FAN3_TACH")
	)
	(segment
		(start 10.946384 -320.828162)
		(end 9.353804 -322.420742)
		(width 0.1524)
		(layer "F.Cu")
		(net "FAN3_TACH")
	)
	(segment
		(start 7.063232 -321.867276)
		(end 4.752594 -321.867276)
		(width 0.1524)
		(layer "F.Cu")
		(net "FAN3_TACH")
	)
	(segment
		(start 4.752594 -321.867276)
		(end 3.949954 -322.669916)
		(width 0.1524)
		(layer "F.Cu")
		(net "FAN3_TACH")
	)
	(segment
		(start 7.616698 -322.420742)
		(end 7.063232 -321.867276)
		(width 0.1524)
		(layer "F.Cu")
		(net "FAN3_TACH")
	)
	(segment
		(start 12.96924 -320.828162)
		(end 10.946384 -320.828162)
		(width 0.1524)
		(layer "F.Cu")
		(net "FAN3_TACH")
	)
	(segment
		(start 7.053326 -321.945254)
		(end 7.875016 -322.766944)
		(width 0.127)
		(layer "In2.Cu")
		(net "FAN3_TACH")
	)
	(segment
		(start 10.569702 -324.775576)
		(end 10.569702 -332.14945)
		(width 0.127)
		(layer "In2.Cu")
		(net "FAN3_TACH")
	)
	(segment
		(start 21.917914 -426.02023)
		(end 11.444224 -436.49392)
		(width 0.127)
		(layer "In2.Cu")
		(net "FAN3_TACH")
	)
	(segment
		(start 12.484354 -370.145056)
		(end 21.917914 -379.578616)
		(width 0.127)
		(layer "In2.Cu")
		(net "FAN3_TACH")
	)
	(segment
		(start 10.569702 -332.14945)
		(end 12.484354 -334.064102)
		(width 0.127)
		(layer "In2.Cu")
		(net "FAN3_TACH")
	)
	(segment
		(start 7.875016 -322.766944)
		(end 8.56107 -322.766944)
		(width 0.127)
		(layer "In2.Cu")
		(net "FAN3_TACH")
	)
	(segment
		(start 21.917914 -379.578616)
		(end 21.917914 -426.02023)
		(width 0.127)
		(layer "In2.Cu")
		(net "FAN3_TACH")
	)
	(segment
		(start 8.56107 -322.766944)
		(end 10.569702 -324.775576)
		(width 0.127)
		(layer "In2.Cu")
		(net "FAN3_TACH")
	)
	(segment
		(start 12.484354 -334.064102)
		(end 12.484354 -370.145056)
		(width 0.127)
		(layer "In2.Cu")
		(net "FAN3_TACH")
	)
	(segment
		(start 3.949954 -322.669916)
		(end 4.674616 -321.945254)
		(width 0.127)
		(layer "In2.Cu")
		(net "FAN3_TACH")
	)
	(segment
		(start 4.674616 -321.945254)
		(end 7.053326 -321.945254)
		(width 0.127)
		(layer "In2.Cu")
		(net "FAN3_TACH")
	)
	(via
		(at 85.261958 -266.421616)
		(size 0.508)
		(drill 0.254)
		(layers "F.Cu" "B.Cu")
		(net "T7_BLAD4_RXD")
	)
	(segment
		(start 91.98991 -271.70507)
		(end 90.545666 -271.70507)
		(width 0.127)
		(layer "In2.Cu")
		(net "T7_BLAD4_RXD")
	)
	(segment
		(start 6.449822 -274.669758)
		(end 7.650226 -274.669758)
		(width 0.127)
		(layer "In2.Cu")
		(net "T7_BLAD4_RXD")
	)
	(segment
		(start 10.567162 -274.4089)
		(end 18.75155 -266.224512)
		(width 0.127)
		(layer "In2.Cu")
		(net "T7_BLAD4_RXD")
	)
	(segment
		(start 7.650226 -274.669758)
		(end 7.911084 -274.4089)
		(width 0.127)
		(layer "In2.Cu")
		(net "T7_BLAD4_RXD")
	)
	(segment
		(start 18.75155 -266.224512)
		(end 85.065108 -266.224512)
		(width 0.127)
		(layer "In2.Cu")
		(net "T7_BLAD4_RXD")
	)
	(segment
		(start 85.065108 -266.224512)
		(end 85.261958 -266.421362)
		(width 0.127)
		(layer "In2.Cu")
		(net "T7_BLAD4_RXD")
	)
	(segment
		(start 90.545666 -271.70507)
		(end 85.261958 -266.421362)
		(width 0.127)
		(layer "In2.Cu")
		(net "T7_BLAD4_RXD")
	)
	(segment
		(start 7.911084 -274.4089)
		(end 10.567162 -274.4089)
		(width 0.127)
		(layer "In2.Cu")
		(net "T7_BLAD4_RXD")
	)
	(segment
		(start 85.261958 -266.421362)
		(end 85.261958 -266.421616)
		(width 0.127)
		(layer "In2.Cu")
		(net "T7_BLAD4_RXD")
	)
	(segment
		(start 8.92556 -326.145652)
		(end 8.449818 -325.66991)
		(width 0.1524)
		(layer "F.Cu")
		(net "FAN4_TACH")
	)
	(segment
		(start 13.029184 -326.145652)
		(end 8.92556 -326.145652)
		(width 0.1524)
		(layer "F.Cu")
		(net "FAN4_TACH")
	)
	(segment
		(start 22.947884 -382.202436)
		(end 12.937998 -372.19255)
		(width 0.1524)
		(layer "B.Cu")
		(net "FAN4_TACH")
	)
	(segment
		(start 10.687558 -343.432384)
		(end 10.687558 -327.90765)
		(width 0.1524)
		(layer "B.Cu")
		(net "FAN4_TACH")
	)
	(segment
		(start 12.937998 -372.19255)
		(end 12.937998 -345.682824)
		(width 0.1524)
		(layer "B.Cu")
		(net "FAN4_TACH")
	)
	(segment
		(start 10.687558 -327.90765)
		(end 8.449818 -325.66991)
		(width 0.1524)
		(layer "B.Cu")
		(net "FAN4_TACH")
	)
	(segment
		(start 11.444224 -418.453316)
		(end 22.947884 -406.949656)
		(width 0.1524)
		(layer "B.Cu")
		(net "FAN4_TACH")
	)
	(segment
		(start 22.947884 -406.949656)
		(end 22.947884 -382.202436)
		(width 0.1524)
		(layer "B.Cu")
		(net "FAN4_TACH")
	)
	(segment
		(start 11.444224 -423.893996)
		(end 11.444224 -418.453316)
		(width 0.1524)
		(layer "B.Cu")
		(net "FAN4_TACH")
	)
	(segment
		(start 12.937998 -345.682824)
		(end 10.687558 -343.432384)
		(width 0.1524)
		(layer "B.Cu")
		(net "FAN4_TACH")
	)
	(via
		(at 85.727286 -281.837892)
		(size 0.508)
		(drill 0.254)
		(layers "F.Cu" "B.Cu")
		(net "T7_BLAD1_EN")
	)
	(segment
		(start 88.17991 -279.385268)
		(end 88.17991 -275.51507)
		(width 0.127)
		(layer "In5.Cu")
		(net "T7_BLAD1_EN")
	)
	(segment
		(start 7.920228 -284.48254)
		(end 22.290278 -284.48254)
		(width 0.127)
		(layer "In5.Cu")
		(net "T7_BLAD1_EN")
	)
	(segment
		(start 5.941314 -283.814012)
		(end 7.2517 -283.814012)
		(width 0.127)
		(layer "In5.Cu")
		(net "T7_BLAD1_EN")
	)
	(segment
		(start 85.727286 -281.837892)
		(end 88.17991 -279.385268)
		(width 0.127)
		(layer "In5.Cu")
		(net "T7_BLAD1_EN")
	)
	(segment
		(start 80.589374 -329.743816)
		(end 80.589374 -323.510656)
		(width 0.127)
		(layer "In5.Cu")
		(net "T7_BLAD1_EN")
	)
	(segment
		(start 5.37845 -285.598616)
		(end 5.37845 -284.376876)
		(width 0.127)
		(layer "In5.Cu")
		(net "T7_BLAD1_EN")
	)
	(segment
		(start 5.37845 -284.376876)
		(end 5.941314 -283.814012)
		(width 0.127)
		(layer "In5.Cu")
		(net "T7_BLAD1_EN")
	)
	(segment
		(start 83.497674 -315.53912)
		(end 91.711526 -307.325268)
		(width 0.127)
		(layer "In5.Cu")
		(net "T7_BLAD1_EN")
	)
	(segment
		(start 7.2517 -283.814012)
		(end 7.920228 -284.48254)
		(width 0.127)
		(layer "In5.Cu")
		(net "T7_BLAD1_EN")
	)
	(segment
		(start 84.85632 -291.3126)
		(end 84.85632 -282.708858)
		(width 0.127)
		(layer "In5.Cu")
		(net "T7_BLAD1_EN")
	)
	(segment
		(start 91.711526 -298.167806)
		(end 84.85632 -291.3126)
		(width 0.127)
		(layer "In5.Cu")
		(net "T7_BLAD1_EN")
	)
	(segment
		(start 30.110176 -351.268538)
		(end 44.030646 -351.268538)
		(width 0.127)
		(layer "In5.Cu")
		(net "T7_BLAD1_EN")
	)
	(segment
		(start 46.076108 -349.223076)
		(end 61.110114 -349.223076)
		(width 0.127)
		(layer "In5.Cu")
		(net "T7_BLAD1_EN")
	)
	(segment
		(start 44.030646 -351.268538)
		(end 46.076108 -349.223076)
		(width 0.127)
		(layer "In5.Cu")
		(net "T7_BLAD1_EN")
	)
	(segment
		(start 6.449822 -286.669988)
		(end 5.37845 -285.598616)
		(width 0.127)
		(layer "In5.Cu")
		(net "T7_BLAD1_EN")
	)
	(segment
		(start 83.497674 -320.602356)
		(end 83.497674 -315.53912)
		(width 0.127)
		(layer "In5.Cu")
		(net "T7_BLAD1_EN")
	)
	(segment
		(start 22.290278 -284.48254)
		(end 28.297378 -290.48964)
		(width 0.127)
		(layer "In5.Cu")
		(net "T7_BLAD1_EN")
	)
	(segment
		(start 28.297378 -349.45574)
		(end 30.110176 -351.268538)
		(width 0.127)
		(layer "In5.Cu")
		(net "T7_BLAD1_EN")
	)
	(segment
		(start 91.711526 -307.325268)
		(end 91.711526 -298.167806)
		(width 0.127)
		(layer "In5.Cu")
		(net "T7_BLAD1_EN")
	)
	(segment
		(start 80.589374 -323.510656)
		(end 83.497674 -320.602356)
		(width 0.127)
		(layer "In5.Cu")
		(net "T7_BLAD1_EN")
	)
	(segment
		(start 61.110114 -349.223076)
		(end 80.589374 -329.743816)
		(width 0.127)
		(layer "In5.Cu")
		(net "T7_BLAD1_EN")
	)
	(segment
		(start 28.297378 -290.48964)
		(end 28.297378 -349.45574)
		(width 0.127)
		(layer "In5.Cu")
		(net "T7_BLAD1_EN")
	)
	(segment
		(start 84.85632 -282.708858)
		(end 85.727286 -281.837892)
		(width 0.127)
		(layer "In5.Cu")
		(net "T7_BLAD1_EN")
	)
	(via
		(at 87.776812 -266.152376)
		(size 0.508)
		(drill 0.254)
		(layers "F.Cu" "B.Cu")
		(net "T7_BLAD4_TXD")
	)
	(segment
		(start 8.449818 -273.66976)
		(end 10.834624 -273.66976)
		(width 0.127)
		(layer "In2.Cu")
		(net "T7_BLAD4_TXD")
	)
	(segment
		(start 92.86113 -272.19529)
		(end 92.86113 -271.236694)
		(width 0.127)
		(layer "In2.Cu")
		(net "T7_BLAD4_TXD")
	)
	(segment
		(start 87.515446 -265.89101)
		(end 87.776812 -266.152376)
		(width 0.127)
		(layer "In2.Cu")
		(net "T7_BLAD4_TXD")
	)
	(segment
		(start 92.08135 -272.97507)
		(end 92.86113 -272.19529)
		(width 0.127)
		(layer "In2.Cu")
		(net "T7_BLAD4_TXD")
	)
	(segment
		(start 10.834624 -273.66976)
		(end 18.613374 -265.89101)
		(width 0.127)
		(layer "In2.Cu")
		(net "T7_BLAD4_TXD")
	)
	(segment
		(start 92.86113 -271.236694)
		(end 87.776812 -266.152376)
		(width 0.127)
		(layer "In2.Cu")
		(net "T7_BLAD4_TXD")
	)
	(segment
		(start 90.71991 -272.97507)
		(end 92.08135 -272.97507)
		(width 0.127)
		(layer "In2.Cu")
		(net "T7_BLAD4_TXD")
	)
	(segment
		(start 18.613374 -265.89101)
		(end 87.515446 -265.89101)
		(width 0.127)
		(layer "In2.Cu")
		(net "T7_BLAD4_TXD")
	)
	(via
		(at 82.358484 -267.153644)
		(size 0.508)
		(drill 0.254)
		(layers "F.Cu" "B.Cu")
		(net "T7_BLAD3_RXD")
	)
	(segment
		(start 81.81594 -266.6111)
		(end 82.358484 -267.153644)
		(width 0.127)
		(layer "In2.Cu")
		(net "T7_BLAD3_RXD")
	)
	(segment
		(start 6.449822 -276.669754)
		(end 8.303006 -274.81657)
		(width 0.127)
		(layer "In2.Cu")
		(net "T7_BLAD3_RXD")
	)
	(segment
		(start 10.64641 -274.81657)
		(end 18.85188 -266.6111)
		(width 0.127)
		(layer "In2.Cu")
		(net "T7_BLAD3_RXD")
	)
	(segment
		(start 82.358484 -267.153644)
		(end 86.90991 -271.70507)
		(width 0.127)
		(layer "In2.Cu")
		(net "T7_BLAD3_RXD")
	)
	(segment
		(start 8.303006 -274.81657)
		(end 10.64641 -274.81657)
		(width 0.127)
		(layer "In2.Cu")
		(net "T7_BLAD3_RXD")
	)
	(segment
		(start 18.85188 -266.6111)
		(end 81.81594 -266.6111)
		(width 0.127)
		(layer "In2.Cu")
		(net "T7_BLAD3_RXD")
	)
	(segment
		(start 28.23591 -365.810038)
		(end 27.117802 -366.928146)
		(width 0.1524)
		(layer "F.Cu")
		(net "PSU5_PS_ON_N")
	)
	(segment
		(start 27.117802 -366.928146)
		(end 26.274522 -367.771426)
		(width 0.1524)
		(layer "F.Cu")
		(net "PSU5_PS_ON_N")
	)
	(segment
		(start 30.45968 -365.810038)
		(end 28.23591 -365.810038)
		(width 0.1524)
		(layer "F.Cu")
		(net "PSU5_PS_ON_N")
	)
	(via
		(at 27.117802 -366.928146)
		(size 0.508)
		(drill 0.254)
		(layers "F.Cu" "B.Cu")
		(net "PSU5_PS_ON_N")
	)
	(via
		(at 82.945732 -286.097472)
		(size 0.508)
		(drill 0.254)
		(layers "F.Cu" "B.Cu")
		(net "T7_BLAD1_TXD")
	)
	(segment
		(start 82.945732 -291.337492)
		(end 90.343228 -298.734988)
		(width 0.127)
		(layer "In5.Cu")
		(net "T7_BLAD1_TXD")
	)
	(segment
		(start 45.251116 -348.083124)
		(end 43.183556 -350.150684)
		(width 0.127)
		(layer "In5.Cu")
		(net "T7_BLAD1_TXD")
	)
	(segment
		(start 11.10742 -283.292804)
		(end 8.484362 -280.669746)
		(width 0.127)
		(layer "In5.Cu")
		(net "T7_BLAD1_TXD")
	)
	(segment
		(start 29.415232 -349.04934)
		(end 29.415232 -290.00069)
		(width 0.127)
		(layer "In5.Cu")
		(net "T7_BLAD1_TXD")
	)
	(segment
		(start 80.91932 -321.599306)
		(end 79.47152 -323.047106)
		(width 0.127)
		(layer "In5.Cu")
		(net "T7_BLAD1_TXD")
	)
	(segment
		(start 90.343228 -298.734988)
		(end 90.343228 -306.758086)
		(width 0.127)
		(layer "In5.Cu")
		(net "T7_BLAD1_TXD")
	)
	(segment
		(start 82.945732 -282.10637)
		(end 82.945732 -286.097472)
		(width 0.127)
		(layer "In5.Cu")
		(net "T7_BLAD1_TXD")
	)
	(segment
		(start 43.183556 -350.150684)
		(end 30.516576 -350.150684)
		(width 0.127)
		(layer "In5.Cu")
		(net "T7_BLAD1_TXD")
	)
	(segment
		(start 30.516576 -350.150684)
		(end 29.415232 -349.04934)
		(width 0.127)
		(layer "In5.Cu")
		(net "T7_BLAD1_TXD")
	)
	(segment
		(start 79.47152 -323.047106)
		(end 79.47152 -329.280266)
		(width 0.127)
		(layer "In5.Cu")
		(net "T7_BLAD1_TXD")
	)
	(segment
		(start 29.415232 -290.00069)
		(end 22.707346 -283.292804)
		(width 0.127)
		(layer "In5.Cu")
		(net "T7_BLAD1_TXD")
	)
	(segment
		(start 60.668662 -348.083124)
		(end 45.251116 -348.083124)
		(width 0.127)
		(layer "In5.Cu")
		(net "T7_BLAD1_TXD")
	)
	(segment
		(start 82.945732 -286.097472)
		(end 82.945732 -291.337492)
		(width 0.127)
		(layer "In5.Cu")
		(net "T7_BLAD1_TXD")
	)
	(segment
		(start 79.47152 -329.280266)
		(end 60.668662 -348.083124)
		(width 0.127)
		(layer "In5.Cu")
		(net "T7_BLAD1_TXD")
	)
	(segment
		(start 22.707346 -283.292804)
		(end 11.10742 -283.292804)
		(width 0.127)
		(layer "In5.Cu")
		(net "T7_BLAD1_TXD")
	)
	(segment
		(start 85.63991 -279.412192)
		(end 82.945732 -282.10637)
		(width 0.127)
		(layer "In5.Cu")
		(net "T7_BLAD1_TXD")
	)
	(segment
		(start 90.343228 -306.758086)
		(end 80.91932 -316.181994)
		(width 0.127)
		(layer "In5.Cu")
		(net "T7_BLAD1_TXD")
	)
	(segment
		(start 85.63991 -275.51507)
		(end 85.63991 -279.412192)
		(width 0.127)
		(layer "In5.Cu")
		(net "T7_BLAD1_TXD")
	)
	(segment
		(start 80.91932 -316.181994)
		(end 80.91932 -321.599306)
		(width 0.127)
		(layer "In5.Cu")
		(net "T7_BLAD1_TXD")
	)
	(segment
		(start 8.484362 -280.669746)
		(end 6.449822 -280.669746)
		(width 0.127)
		(layer "In5.Cu")
		(net "T7_BLAD1_TXD")
	)
	(via
		(at 84.30768 -283.486352)
		(size 0.508)
		(drill 0.254)
		(layers "F.Cu" "B.Cu")
		(net "T7_BLAD4_EN")
	)
	(segment
		(start 8.449818 -283.66974)
		(end 8.849106 -284.069028)
		(width 0.127)
		(layer "In5.Cu")
		(net "T7_BLAD4_EN")
	)
	(segment
		(start 87.338408 -273.342354)
		(end 87.798402 -273.802348)
		(width 0.127)
		(layer "In5.Cu")
		(net "T7_BLAD4_EN")
	)
	(segment
		(start 87.333328 -279.397714)
		(end 84.30768 -282.423362)
		(width 0.127)
		(layer "In5.Cu")
		(net "T7_BLAD4_EN")
	)
	(segment
		(start 28.662376 -290.338256)
		(end 28.662376 -349.304356)
		(width 0.127)
		(layer "In5.Cu")
		(net "T7_BLAD4_EN")
	)
	(segment
		(start 30.26156 -350.90354)
		(end 43.76039 -350.90354)
		(width 0.127)
		(layer "In5.Cu")
		(net "T7_BLAD4_EN")
	)
	(segment
		(start 87.338408 -272.596864)
		(end 87.338408 -273.342354)
		(width 0.127)
		(layer "In5.Cu")
		(net "T7_BLAD4_EN")
	)
	(segment
		(start 43.76039 -350.90354)
		(end 45.875702 -348.788228)
		(width 0.127)
		(layer "In5.Cu")
		(net "T7_BLAD4_EN")
	)
	(segment
		(start 80.224376 -329.592432)
		(end 80.224376 -323.359272)
		(width 0.127)
		(layer "In5.Cu")
		(net "T7_BLAD4_EN")
	)
	(segment
		(start 89.44991 -271.70507)
		(end 88.230202 -271.70507)
		(width 0.127)
		(layer "In5.Cu")
		(net "T7_BLAD4_EN")
	)
	(segment
		(start 45.875702 -348.788228)
		(end 61.02858 -348.788228)
		(width 0.127)
		(layer "In5.Cu")
		(net "T7_BLAD4_EN")
	)
	(segment
		(start 91.346528 -307.173884)
		(end 91.346528 -298.31919)
		(width 0.127)
		(layer "In5.Cu")
		(net "T7_BLAD4_EN")
	)
	(segment
		(start 61.02858 -348.788228)
		(end 80.224376 -329.592432)
		(width 0.127)
		(layer "In5.Cu")
		(net "T7_BLAD4_EN")
	)
	(segment
		(start 91.346528 -298.31919)
		(end 84.30768 -291.280342)
		(width 0.127)
		(layer "In5.Cu")
		(net "T7_BLAD4_EN")
	)
	(segment
		(start 87.333328 -274.929092)
		(end 87.333328 -279.397714)
		(width 0.127)
		(layer "In5.Cu")
		(net "T7_BLAD4_EN")
	)
	(segment
		(start 83.132676 -315.387736)
		(end 91.346528 -307.173884)
		(width 0.127)
		(layer "In5.Cu")
		(net "T7_BLAD4_EN")
	)
	(segment
		(start 22.393148 -284.069028)
		(end 28.662376 -290.338256)
		(width 0.127)
		(layer "In5.Cu")
		(net "T7_BLAD4_EN")
	)
	(segment
		(start 84.30768 -282.423362)
		(end 84.30768 -283.486352)
		(width 0.127)
		(layer "In5.Cu")
		(net "T7_BLAD4_EN")
	)
	(segment
		(start 88.230202 -271.70507)
		(end 87.338408 -272.596864)
		(width 0.127)
		(layer "In5.Cu")
		(net "T7_BLAD4_EN")
	)
	(segment
		(start 80.224376 -323.359272)
		(end 83.132676 -320.450972)
		(width 0.127)
		(layer "In5.Cu")
		(net "T7_BLAD4_EN")
	)
	(segment
		(start 87.798402 -273.802348)
		(end 87.798402 -274.464018)
		(width 0.127)
		(layer "In5.Cu")
		(net "T7_BLAD4_EN")
	)
	(segment
		(start 87.798402 -274.464018)
		(end 87.333328 -274.929092)
		(width 0.127)
		(layer "In5.Cu")
		(net "T7_BLAD4_EN")
	)
	(segment
		(start 84.30768 -291.280342)
		(end 84.30768 -283.486352)
		(width 0.127)
		(layer "In5.Cu")
		(net "T7_BLAD4_EN")
	)
	(segment
		(start 8.849106 -284.069028)
		(end 22.393148 -284.069028)
		(width 0.127)
		(layer "In5.Cu")
		(net "T7_BLAD4_EN")
	)
	(segment
		(start 28.662376 -349.304356)
		(end 30.26156 -350.90354)
		(width 0.127)
		(layer "In5.Cu")
		(net "T7_BLAD4_EN")
	)
	(segment
		(start 83.132676 -320.450972)
		(end 83.132676 -315.387736)
		(width 0.127)
		(layer "In5.Cu")
		(net "T7_BLAD4_EN")
	)
	(via
		(at 83.563206 -284.75686)
		(size 0.508)
		(drill 0.254)
		(layers "F.Cu" "B.Cu")
		(net "T7_BLAD1_RXD")
	)
	(segment
		(start 83.563206 -282.344368)
		(end 86.90991 -278.997664)
		(width 0.127)
		(layer "In5.Cu")
		(net "T7_BLAD1_RXD")
	)
	(segment
		(start 79.87157 -329.446128)
		(end 60.880752 -348.436946)
		(width 0.127)
		(layer "In5.Cu")
		(net "T7_BLAD1_RXD")
	)
	(segment
		(start 90.743278 -298.569126)
		(end 90.743278 -306.923948)
		(width 0.127)
		(layer "In5.Cu")
		(net "T7_BLAD1_RXD")
	)
	(segment
		(start 29.015182 -349.135192)
		(end 29.015182 -290.12642)
		(width 0.127)
		(layer "In5.Cu")
		(net "T7_BLAD1_RXD")
	)
	(segment
		(start 86.90991 -278.997664)
		(end 86.90991 -274.24507)
		(width 0.127)
		(layer "In5.Cu")
		(net "T7_BLAD1_RXD")
	)
	(segment
		(start 83.563206 -291.389054)
		(end 90.743278 -298.569126)
		(width 0.127)
		(layer "In5.Cu")
		(net "T7_BLAD1_RXD")
	)
	(segment
		(start 79.87157 -323.212968)
		(end 79.87157 -329.446128)
		(width 0.127)
		(layer "In5.Cu")
		(net "T7_BLAD1_RXD")
	)
	(segment
		(start 83.563206 -284.75686)
		(end 83.563206 -291.389054)
		(width 0.127)
		(layer "In5.Cu")
		(net "T7_BLAD1_RXD")
	)
	(segment
		(start 81.31937 -316.347856)
		(end 81.31937 -321.765168)
		(width 0.127)
		(layer "In5.Cu")
		(net "T7_BLAD1_RXD")
	)
	(segment
		(start 45.474382 -348.436946)
		(end 43.360594 -350.550734)
		(width 0.127)
		(layer "In5.Cu")
		(net "T7_BLAD1_RXD")
	)
	(segment
		(start 60.880752 -348.436946)
		(end 45.474382 -348.436946)
		(width 0.127)
		(layer "In5.Cu")
		(net "T7_BLAD1_RXD")
	)
	(segment
		(start 29.015182 -290.12642)
		(end 22.564344 -283.675836)
		(width 0.127)
		(layer "In5.Cu")
		(net "T7_BLAD1_RXD")
	)
	(segment
		(start 81.31937 -321.765168)
		(end 79.87157 -323.212968)
		(width 0.127)
		(layer "In5.Cu")
		(net "T7_BLAD1_RXD")
	)
	(segment
		(start 30.430724 -350.550734)
		(end 29.015182 -349.135192)
		(width 0.127)
		(layer "In5.Cu")
		(net "T7_BLAD1_RXD")
	)
	(segment
		(start 90.743278 -306.923948)
		(end 81.31937 -316.347856)
		(width 0.127)
		(layer "In5.Cu")
		(net "T7_BLAD1_RXD")
	)
	(segment
		(start 83.563206 -284.75686)
		(end 83.563206 -282.344368)
		(width 0.127)
		(layer "In5.Cu")
		(net "T7_BLAD1_RXD")
	)
	(segment
		(start 43.360594 -350.550734)
		(end 30.430724 -350.550734)
		(width 0.127)
		(layer "In5.Cu")
		(net "T7_BLAD1_RXD")
	)
	(segment
		(start 22.564344 -283.675836)
		(end 10.45591 -283.675836)
		(width 0.127)
		(layer "In5.Cu")
		(net "T7_BLAD1_RXD")
	)
	(segment
		(start 10.45591 -283.675836)
		(end 8.449818 -281.669744)
		(width 0.127)
		(layer "In5.Cu")
		(net "T7_BLAD1_RXD")
	)
	(via
		(at 78.658212 -267.528548)
		(size 0.508)
		(drill 0.254)
		(layers "F.Cu" "B.Cu")
		(net "T7_BLAD2_TXD")
	)
	(segment
		(start 21.29028 -267.528548)
		(end 78.658212 -267.528548)
		(width 0.127)
		(layer "In2.Cu")
		(net "T7_BLAD2_TXD")
	)
	(segment
		(start 78.658212 -267.528548)
		(end 79.848964 -267.528548)
		(width 0.127)
		(layer "In2.Cu")
		(net "T7_BLAD2_TXD")
	)
	(segment
		(start 6.449822 -278.66975)
		(end 8.72109 -276.398482)
		(width 0.127)
		(layer "In2.Cu")
		(net "T7_BLAD2_TXD")
	)
	(segment
		(start 88.99652 -277.23846)
		(end 90.71991 -275.51507)
		(width 0.127)
		(layer "In2.Cu")
		(net "T7_BLAD2_TXD")
	)
	(segment
		(start 79.848964 -267.528548)
		(end 84.57946 -272.259044)
		(width 0.127)
		(layer "In2.Cu")
		(net "T7_BLAD2_TXD")
	)
	(segment
		(start 84.57946 -272.259044)
		(end 84.57946 -276.57552)
		(width 0.127)
		(layer "In2.Cu")
		(net "T7_BLAD2_TXD")
	)
	(segment
		(start 12.420346 -276.398482)
		(end 21.29028 -267.528548)
		(width 0.127)
		(layer "In2.Cu")
		(net "T7_BLAD2_TXD")
	)
	(segment
		(start 84.57946 -276.57552)
		(end 85.2424 -277.23846)
		(width 0.127)
		(layer "In2.Cu")
		(net "T7_BLAD2_TXD")
	)
	(segment
		(start 85.2424 -277.23846)
		(end 88.99652 -277.23846)
		(width 0.127)
		(layer "In2.Cu")
		(net "T7_BLAD2_TXD")
	)
	(segment
		(start 8.72109 -276.398482)
		(end 12.420346 -276.398482)
		(width 0.127)
		(layer "In2.Cu")
		(net "T7_BLAD2_TXD")
	)
	(segment
		(start 27.267154 -277.744936)
		(end 27.60218 -277.40991)
		(width 0.1524)
		(layer "F.Cu")
		(net "PSU4_PS_ON_N")
	)
	(segment
		(start 26.525728 -278.486362)
		(end 27.267154 -277.744936)
		(width 0.1524)
		(layer "F.Cu")
		(net "PSU4_PS_ON_N")
	)
	(segment
		(start 27.60218 -277.40991)
		(end 30.45968 -277.40991)
		(width 0.1524)
		(layer "F.Cu")
		(net "PSU4_PS_ON_N")
	)
	(via
		(at 27.267154 -277.744936)
		(size 0.508)
		(drill 0.254)
		(layers "F.Cu" "B.Cu")
		(net "PSU4_PS_ON_N")
	)
	(segment
		(start 28.912566 -189.265306)
		(end 27.16149 -189.265306)
		(width 0.1524)
		(layer "F.Cu")
		(net "PSU3_PS_ON_N")
	)
	(segment
		(start 27.16149 -189.265306)
		(end 26.503884 -189.265306)
		(width 0.1524)
		(layer "F.Cu")
		(net "PSU3_PS_ON_N")
	)
	(segment
		(start 30.45968 -189.010036)
		(end 29.167836 -189.010036)
		(width 0.1524)
		(layer "F.Cu")
		(net "PSU3_PS_ON_N")
	)
	(segment
		(start 29.167836 -189.010036)
		(end 28.912566 -189.265306)
		(width 0.1524)
		(layer "F.Cu")
		(net "PSU3_PS_ON_N")
	)
	(via
		(at 27.16149 -189.265306)
		(size 0.508)
		(drill 0.254)
		(layers "F.Cu" "B.Cu")
		(net "PSU3_PS_ON_N")
	)
	(segment
		(start 26.174954 -307.573426)
		(end 23.667466 -310.080914)
		(width 0.1524)
		(layer "F.Cu")
		(net "PSU_ALERT_N")
	)
	(segment
		(start 26.174954 -290.513516)
		(end 26.174954 -307.573426)
		(width 0.1524)
		(layer "F.Cu")
		(net "PSU_ALERT_N")
	)
	(segment
		(start 30.45968 -269.78991)
		(end 28.037536 -267.367766)
		(width 0.1524)
		(layer "F.Cu")
		(net "PSU_ALERT_N")
	)
	(segment
		(start 29.957776 -270.291814)
		(end 23.805388 -270.291814)
		(width 0.1524)
		(layer "F.Cu")
		(net "PSU_ALERT_N")
	)
	(segment
		(start 23.805388 -270.291814)
		(end 23.09368 -271.003522)
		(width 0.1524)
		(layer "F.Cu")
		(net "PSU_ALERT_N")
	)
	(segment
		(start 28.037536 -267.367766)
		(end 12.751816 -267.367766)
		(width 0.1524)
		(layer "F.Cu")
		(net "PSU_ALERT_N")
	)
	(segment
		(start 23.667466 -334.58658)
		(end 25.582626 -336.50174)
		(width 0.1524)
		(layer "F.Cu")
		(net "PSU_ALERT_N")
	)
	(segment
		(start 23.667466 -310.080914)
		(end 23.667466 -334.58658)
		(width 0.1524)
		(layer "F.Cu")
		(net "PSU_ALERT_N")
	)
	(segment
		(start 23.09368 -271.003522)
		(end 23.09368 -287.432242)
		(width 0.1524)
		(layer "F.Cu")
		(net "PSU_ALERT_N")
	)
	(segment
		(start 12.751816 -267.367766)
		(end 8.449818 -271.669764)
		(width 0.1524)
		(layer "F.Cu")
		(net "PSU_ALERT_N")
	)
	(segment
		(start 23.09368 -287.432242)
		(end 26.174954 -290.513516)
		(width 0.1524)
		(layer "F.Cu")
		(net "PSU_ALERT_N")
	)
	(segment
		(start 30.45968 -269.78991)
		(end 29.957776 -270.291814)
		(width 0.1524)
		(layer "F.Cu")
		(net "PSU_ALERT_N")
	)
	(via
		(at 23.619206 -235.542836)
		(size 0.508)
		(drill 0.254)
		(layers "F.Cu" "B.Cu")
		(net "PSU_ALERT_N")
	)
	(via
		(at 25.582626 -336.50174)
		(size 0.508)
		(drill 0.254)
		(layers "F.Cu" "B.Cu")
		(net "PSU_ALERT_N")
	)
	(segment
		(start 30.45968 -181.390036)
		(end 31.55696 -182.487316)
		(width 0.1524)
		(layer "B.Cu")
		(net "PSU_ALERT_N")
	)
	(segment
		(start 32.00781 -370.778786)
		(end 30.859984 -371.926612)
		(width 0.1524)
		(layer "B.Cu")
		(net "PSU_ALERT_N")
	)
	(segment
		(start 23.910798 -13.582142)
		(end 23.910798 -87.03437)
		(width 0.1524)
		(layer "B.Cu")
		(net "PSU_ALERT_N")
	)
	(segment
		(start 25.582626 -336.50174)
		(end 24.511254 -337.573112)
		(width 0.1524)
		(layer "B.Cu")
		(net "PSU_ALERT_N")
	)
	(segment
		(start 21.853398 -221.912942)
		(end 21.853398 -232.206546)
		(width 0.1524)
		(layer "B.Cu")
		(net "PSU_ALERT_N")
	)
	(segment
		(start 21.998432 -237.16361)
		(end 23.619206 -235.542836)
		(width 0.1524)
		(layer "B.Cu")
		(net "PSU_ALERT_N")
	)
	(segment
		(start 23.619206 -233.972354)
		(end 23.619206 -235.542836)
		(width 0.1524)
		(layer "B.Cu")
		(net "PSU_ALERT_N")
	)
	(segment
		(start 26.445972 -375.122694)
		(end 26.445972 -439.974228)
		(width 0.1524)
		(layer "B.Cu")
		(net "PSU_ALERT_N")
	)
	(segment
		(start 30.816804 -190.08979)
		(end 26.627074 -190.08979)
		(width 0.1524)
		(layer "B.Cu")
		(net "PSU_ALERT_N")
	)
	(segment
		(start 29.866336 -92.989908)
		(end 30.45968 -92.989908)
		(width 0.1524)
		(layer "B.Cu")
		(net "PSU_ALERT_N")
	)
	(segment
		(start 26.627074 -190.08979)
		(end 22.539706 -194.177158)
		(width 0.1524)
		(layer "B.Cu")
		(net "PSU_ALERT_N")
	)
	(segment
		(start 22.813518 -111.50092)
		(end 25.24379 -109.070648)
		(width 0.1524)
		(layer "B.Cu")
		(net "PSU_ALERT_N")
	)
	(segment
		(start 29.642054 -371.926612)
		(end 26.445972 -375.122694)
		(width 0.1524)
		(layer "B.Cu")
		(net "PSU_ALERT_N")
	)
	(segment
		(start 25.24379 -109.070648)
		(end 25.24379 -104.140508)
		(width 0.1524)
		(layer "B.Cu")
		(net "PSU_ALERT_N")
	)
	(segment
		(start 26.445972 -439.974228)
		(end 30.45968 -443.987936)
		(width 0.1524)
		(layer "B.Cu")
		(net "PSU_ALERT_N")
	)
	(segment
		(start 30.859984 -371.926612)
		(end 29.642054 -371.926612)
		(width 0.1524)
		(layer "B.Cu")
		(net "PSU_ALERT_N")
	)
	(segment
		(start 24.511254 -352.241612)
		(end 30.45968 -358.190038)
		(width 0.1524)
		(layer "B.Cu")
		(net "PSU_ALERT_N")
	)
	(segment
		(start 26.867866 -11.585194)
		(end 25.907746 -11.585194)
		(width 0.1524)
		(layer "B.Cu")
		(net "PSU_ALERT_N")
	)
	(segment
		(start 22.539706 -221.226634)
		(end 21.853398 -221.912942)
		(width 0.1524)
		(layer "B.Cu")
		(net "PSU_ALERT_N")
	)
	(segment
		(start 30.45968 -269.78991)
		(end 21.998432 -261.328662)
		(width 0.1524)
		(layer "B.Cu")
		(net "PSU_ALERT_N")
	)
	(segment
		(start 30.45968 -443.987936)
		(end 30.45968 -446.589912)
		(width 0.1524)
		(layer "B.Cu")
		(net "PSU_ALERT_N")
	)
	(segment
		(start 24.511254 -337.573112)
		(end 24.511254 -352.241612)
		(width 0.1524)
		(layer "B.Cu")
		(net "PSU_ALERT_N")
	)
	(segment
		(start 25.907746 -11.585194)
		(end 23.910798 -13.582142)
		(width 0.1524)
		(layer "B.Cu")
		(net "PSU_ALERT_N")
	)
	(segment
		(start 28.18257 -10.27049)
		(end 26.867866 -11.585194)
		(width 0.1524)
		(layer "B.Cu")
		(net "PSU_ALERT_N")
	)
	(segment
		(start 21.853398 -232.206546)
		(end 23.619206 -233.972354)
		(width 0.1524)
		(layer "B.Cu")
		(net "PSU_ALERT_N")
	)
	(segment
		(start 31.55696 -182.487316)
		(end 31.55696 -189.349634)
		(width 0.1524)
		(layer "B.Cu")
		(net "PSU_ALERT_N")
	)
	(segment
		(start 22.813518 -173.743874)
		(end 22.813518 -111.50092)
		(width 0.1524)
		(layer "B.Cu")
		(net "PSU_ALERT_N")
	)
	(segment
		(start 22.539706 -194.177158)
		(end 22.539706 -221.226634)
		(width 0.1524)
		(layer "B.Cu")
		(net "PSU_ALERT_N")
	)
	(segment
		(start 31.676086 -101.054154)
		(end 31.676086 -94.206314)
		(width 0.1524)
		(layer "B.Cu")
		(net "PSU_ALERT_N")
	)
	(segment
		(start 30.45968 -4.590034)
		(end 28.18257 -6.867144)
		(width 0.1524)
		(layer "B.Cu")
		(net "PSU_ALERT_N")
	)
	(segment
		(start 30.45968 -358.190038)
		(end 32.00781 -359.738168)
		(width 0.1524)
		(layer "B.Cu")
		(net "PSU_ALERT_N")
	)
	(segment
		(start 31.676086 -94.206314)
		(end 30.45968 -92.989908)
		(width 0.1524)
		(layer "B.Cu")
		(net "PSU_ALERT_N")
	)
	(segment
		(start 32.00781 -359.738168)
		(end 32.00781 -370.778786)
		(width 0.1524)
		(layer "B.Cu")
		(net "PSU_ALERT_N")
	)
	(segment
		(start 28.18257 -6.867144)
		(end 28.18257 -10.27049)
		(width 0.1524)
		(layer "B.Cu")
		(net "PSU_ALERT_N")
	)
	(segment
		(start 23.910798 -87.03437)
		(end 29.866336 -92.989908)
		(width 0.1524)
		(layer "B.Cu")
		(net "PSU_ALERT_N")
	)
	(segment
		(start 31.55696 -189.349634)
		(end 30.816804 -190.08979)
		(width 0.1524)
		(layer "B.Cu")
		(net "PSU_ALERT_N")
	)
	(segment
		(start 25.24379 -104.140508)
		(end 27.727402 -101.656896)
		(width 0.1524)
		(layer "B.Cu")
		(net "PSU_ALERT_N")
	)
	(segment
		(start 30.45968 -181.390036)
		(end 22.813518 -173.743874)
		(width 0.1524)
		(layer "B.Cu")
		(net "PSU_ALERT_N")
	)
	(segment
		(start 27.727402 -101.656896)
		(end 31.073344 -101.656896)
		(width 0.1524)
		(layer "B.Cu")
		(net "PSU_ALERT_N")
	)
	(segment
		(start 21.998432 -261.328662)
		(end 21.998432 -237.16361)
		(width 0.1524)
		(layer "B.Cu")
		(net "PSU_ALERT_N")
	)
	(segment
		(start 31.073344 -101.656896)
		(end 31.676086 -101.054154)
		(width 0.1524)
		(layer "B.Cu")
		(net "PSU_ALERT_N")
	)
	(segment
		(start 29.109162 -100.609908)
		(end 29.082492 -100.636578)
		(width 0.1524)
		(layer "F.Cu")
		(net "PSU2_PS_ON_N")
	)
	(segment
		(start 26.652728 -10.617962)
		(end 25.76322 -10.617962)
		(width 0.1524)
		(layer "F.Cu")
		(net "PSU2_PS_ON_N")
	)
	(segment
		(start 30.45968 -100.609908)
		(end 29.109162 -100.609908)
		(width 0.1524)
		(layer "F.Cu")
		(net "PSU2_PS_ON_N")
	)
	(via
		(at 29.082492 -100.636578)
		(size 0.508)
		(drill 0.254)
		(layers "F.Cu" "B.Cu")
		(net "PSU2_PS_ON_N")
	)
	(via
		(at 25.76322 -10.617962)
		(size 0.508)
		(drill 0.254)
		(layers "F.Cu" "B.Cu")
		(net "PSU2_PS_ON_N")
	)
	(via
		(at 17.99971 -228.0285)
		(size 0.508)
		(drill 0.254)
		(layers "F.Cu" "B.Cu")
		(net "PSU2_PS_ON_N")
	)
	(segment
		(start 23.531576 -88.61933)
		(end 23.531576 -12.849606)
		(width 0.1524)
		(layer "B.Cu")
		(net "PSU2_PS_ON_N")
	)
	(segment
		(start 29.082492 -100.636578)
		(end 29.082492 -94.170246)
		(width 0.1524)
		(layer "B.Cu")
		(net "PSU2_PS_ON_N")
	)
	(segment
		(start 29.082492 -94.170246)
		(end 23.531576 -88.61933)
		(width 0.1524)
		(layer "B.Cu")
		(net "PSU2_PS_ON_N")
	)
	(segment
		(start 23.531576 -12.849606)
		(end 25.76322 -10.617962)
		(width 0.1524)
		(layer "B.Cu")
		(net "PSU2_PS_ON_N")
	)
	(segment
		(start 23.783036 -200.961498)
		(end 23.783036 -221.61373)
		(width 0.127)
		(layer "In2.Cu")
		(net "PSU2_PS_ON_N")
	)
	(segment
		(start 19.089624 -226.938586)
		(end 17.99971 -228.0285)
		(width 0.127)
		(layer "In2.Cu")
		(net "PSU2_PS_ON_N")
	)
	(segment
		(start 29.082492 -104.780334)
		(end 29.413962 -105.111804)
		(width 0.127)
		(layer "In2.Cu")
		(net "PSU2_PS_ON_N")
	)
	(segment
		(start 20.036028 -180.169312)
		(end 20.036028 -197.21449)
		(width 0.127)
		(layer "In2.Cu")
		(net "PSU2_PS_ON_N")
	)
	(segment
		(start 19.089624 -226.307142)
		(end 19.089624 -226.938586)
		(width 0.127)
		(layer "In2.Cu")
		(net "PSU2_PS_ON_N")
	)
	(segment
		(start 29.082492 -100.636578)
		(end 29.082492 -104.780334)
		(width 0.127)
		(layer "In2.Cu")
		(net "PSU2_PS_ON_N")
	)
	(segment
		(start 29.413962 -105.111804)
		(end 29.413962 -111.66348)
		(width 0.127)
		(layer "In2.Cu")
		(net "PSU2_PS_ON_N")
	)
	(segment
		(start 20.036028 -197.21449)
		(end 23.783036 -200.961498)
		(width 0.127)
		(layer "In2.Cu")
		(net "PSU2_PS_ON_N")
	)
	(segment
		(start 28.97251 -112.104932)
		(end 28.97251 -171.23283)
		(width 0.127)
		(layer "In2.Cu")
		(net "PSU2_PS_ON_N")
	)
	(segment
		(start 28.97251 -171.23283)
		(end 20.036028 -180.169312)
		(width 0.127)
		(layer "In2.Cu")
		(net "PSU2_PS_ON_N")
	)
	(segment
		(start 29.413962 -111.66348)
		(end 28.97251 -112.104932)
		(width 0.127)
		(layer "In2.Cu")
		(net "PSU2_PS_ON_N")
	)
	(segment
		(start 23.783036 -221.61373)
		(end 19.089624 -226.307142)
		(width 0.127)
		(layer "In2.Cu")
		(net "PSU2_PS_ON_N")
	)
	(via
		(at 83.460082 -237.048548)
		(size 0.508)
		(drill 0.254)
		(layers "F.Cu" "B.Cu")
		(net "T6_BLAD1_EN")
	)
	(segment
		(start 3.646678 -271.856708)
		(end 3.058414 -272.444972)
		(width 0.127)
		(layer "In2.Cu")
		(net "T6_BLAD1_EN")
	)
	(segment
		(start 18.131282 -264.727944)
		(end 12.019534 -270.839692)
		(width 0.127)
		(layer "In2.Cu")
		(net "T6_BLAD1_EN")
	)
	(segment
		(start 83.460082 -242.246658)
		(end 83.460082 -246.419624)
		(width 0.127)
		(layer "In2.Cu")
		(net "T6_BLAD1_EN")
	)
	(segment
		(start 12.019534 -270.839692)
		(end 7.963154 -270.839692)
		(width 0.127)
		(layer "In2.Cu")
		(net "T6_BLAD1_EN")
	)
	(segment
		(start 84.257134 -240.62055)
		(end 84.257134 -241.449606)
		(width 0.127)
		(layer "In2.Cu")
		(net "T6_BLAD1_EN")
	)
	(segment
		(start 84.257134 -241.449606)
		(end 83.460082 -242.246658)
		(width 0.127)
		(layer "In2.Cu")
		(net "T6_BLAD1_EN")
	)
	(segment
		(start 7.963154 -270.839692)
		(end 6.946138 -271.856708)
		(width 0.127)
		(layer "In2.Cu")
		(net "T6_BLAD1_EN")
	)
	(segment
		(start 83.460082 -237.048548)
		(end 83.460082 -235.784898)
		(width 0.127)
		(layer "In2.Cu")
		(net "T6_BLAD1_EN")
	)
	(segment
		(start 3.058414 -272.444972)
		(end 3.058414 -274.5613)
		(width 0.127)
		(layer "In2.Cu")
		(net "T6_BLAD1_EN")
	)
	(segment
		(start 83.460082 -239.823498)
		(end 84.257134 -240.62055)
		(width 0.127)
		(layer "In2.Cu")
		(net "T6_BLAD1_EN")
	)
	(segment
		(start 3.058414 -274.5613)
		(end 1.949958 -275.669756)
		(width 0.127)
		(layer "In2.Cu")
		(net "T6_BLAD1_EN")
	)
	(segment
		(start 65.151762 -264.727944)
		(end 18.131282 -264.727944)
		(width 0.127)
		(layer "In2.Cu")
		(net "T6_BLAD1_EN")
	)
	(segment
		(start 83.460082 -235.784898)
		(end 88.17991 -231.06507)
		(width 0.127)
		(layer "In2.Cu")
		(net "T6_BLAD1_EN")
	)
	(segment
		(start 83.460082 -237.048548)
		(end 83.460082 -239.823498)
		(width 0.127)
		(layer "In2.Cu")
		(net "T6_BLAD1_EN")
	)
	(segment
		(start 83.460082 -246.419624)
		(end 65.151762 -264.727944)
		(width 0.127)
		(layer "In2.Cu")
		(net "T6_BLAD1_EN")
	)
	(segment
		(start 6.946138 -271.856708)
		(end 3.646678 -271.856708)
		(width 0.127)
		(layer "In2.Cu")
		(net "T6_BLAD1_EN")
	)
	(via
		(at 87.288624 -237.16615)
		(size 0.508)
		(drill 0.254)
		(layers "F.Cu" "B.Cu")
		(net "T6_BLAD2_RXD")
	)
	(segment
		(start 6.934708 -256.91719)
		(end 5.99313 -256.91719)
		(width 0.127)
		(layer "In5.Cu")
		(net "T6_BLAD2_RXD")
	)
	(segment
		(start 87.288624 -237.16615)
		(end 91.98991 -232.464864)
		(width 0.127)
		(layer "In5.Cu")
		(net "T6_BLAD2_RXD")
	)
	(segment
		(start 5.193538 -259.566664)
		(end 4.089654 -260.670548)
		(width 0.127)
		(layer "In5.Cu")
		(net "T6_BLAD2_RXD")
	)
	(segment
		(start 62.7761 -264.417302)
		(end 17.591024 -264.417302)
		(width 0.127)
		(layer "In5.Cu")
		(net "T6_BLAD2_RXD")
	)
	(segment
		(start 91.98991 -232.464864)
		(end 91.98991 -229.79507)
		(width 0.127)
		(layer "In5.Cu")
		(net "T6_BLAD2_RXD")
	)
	(segment
		(start 5.193538 -257.716782)
		(end 5.193538 -259.566664)
		(width 0.127)
		(layer "In5.Cu")
		(net "T6_BLAD2_RXD")
	)
	(segment
		(start 9.123934 -255.950212)
		(end 7.901686 -255.950212)
		(width 0.127)
		(layer "In5.Cu")
		(net "T6_BLAD2_RXD")
	)
	(segment
		(start 7.901686 -255.950212)
		(end 6.934708 -256.91719)
		(width 0.127)
		(layer "In5.Cu")
		(net "T6_BLAD2_RXD")
	)
	(segment
		(start 5.99313 -256.91719)
		(end 5.193538 -257.716782)
		(width 0.127)
		(layer "In5.Cu")
		(net "T6_BLAD2_RXD")
	)
	(segment
		(start 87.288624 -237.16615)
		(end 85.323934 -239.13084)
		(width 0.127)
		(layer "In5.Cu")
		(net "T6_BLAD2_RXD")
	)
	(segment
		(start 85.323934 -239.13084)
		(end 85.323934 -241.869214)
		(width 0.127)
		(layer "In5.Cu")
		(net "T6_BLAD2_RXD")
	)
	(segment
		(start 17.591024 -264.417302)
		(end 9.123934 -255.950212)
		(width 0.127)
		(layer "In5.Cu")
		(net "T6_BLAD2_RXD")
	)
	(segment
		(start 4.089654 -260.670548)
		(end 1.948942 -260.670548)
		(width 0.127)
		(layer "In5.Cu")
		(net "T6_BLAD2_RXD")
	)
	(segment
		(start 85.323934 -241.869214)
		(end 62.7761 -264.417302)
		(width 0.127)
		(layer "In5.Cu")
		(net "T6_BLAD2_RXD")
	)
	(via
		(at 85.38464 -238.064548)
		(size 0.508)
		(drill 0.254)
		(layers "F.Cu" "B.Cu")
		(net "T6_BLAD2_TXD")
	)
	(segment
		(start 7.75589 -255.58623)
		(end 9.276334 -255.58623)
		(width 0.127)
		(layer "In5.Cu")
		(net "T6_BLAD2_TXD")
	)
	(segment
		(start 90.71991 -232.729278)
		(end 85.38464 -238.064548)
		(width 0.127)
		(layer "In5.Cu")
		(net "T6_BLAD2_TXD")
	)
	(segment
		(start 3.948938 -259.67055)
		(end 4.833112 -258.786376)
		(width 0.127)
		(layer "In5.Cu")
		(net "T6_BLAD2_TXD")
	)
	(segment
		(start 9.276334 -255.58623)
		(end 17.742408 -264.052304)
		(width 0.127)
		(layer "In5.Cu")
		(net "T6_BLAD2_TXD")
	)
	(segment
		(start 4.833112 -257.56743)
		(end 5.843778 -256.556764)
		(width 0.127)
		(layer "In5.Cu")
		(net "T6_BLAD2_TXD")
	)
	(segment
		(start 17.742408 -264.052304)
		(end 62.648338 -264.052304)
		(width 0.127)
		(layer "In5.Cu")
		(net "T6_BLAD2_TXD")
	)
	(segment
		(start 84.9757 -238.473488)
		(end 85.38464 -238.064548)
		(width 0.127)
		(layer "In5.Cu")
		(net "T6_BLAD2_TXD")
	)
	(segment
		(start 84.9757 -241.724942)
		(end 84.9757 -238.473488)
		(width 0.127)
		(layer "In5.Cu")
		(net "T6_BLAD2_TXD")
	)
	(segment
		(start 62.648338 -264.052304)
		(end 84.9757 -241.724942)
		(width 0.127)
		(layer "In5.Cu")
		(net "T6_BLAD2_TXD")
	)
	(segment
		(start 4.833112 -258.786376)
		(end 4.833112 -257.56743)
		(width 0.127)
		(layer "In5.Cu")
		(net "T6_BLAD2_TXD")
	)
	(segment
		(start 90.71991 -231.06507)
		(end 90.71991 -232.729278)
		(width 0.127)
		(layer "In5.Cu")
		(net "T6_BLAD2_TXD")
	)
	(segment
		(start 5.843778 -256.556764)
		(end 6.785356 -256.556764)
		(width 0.127)
		(layer "In5.Cu")
		(net "T6_BLAD2_TXD")
	)
	(segment
		(start 6.785356 -256.556764)
		(end 7.75589 -255.58623)
		(width 0.127)
		(layer "In5.Cu")
		(net "T6_BLAD2_TXD")
	)
	(segment
		(start 27.123644 -308.32933)
		(end 24.953214 -310.49976)
		(width 0.1524)
		(layer "F.Cu")
		(net "PSU_CSAHRE")
	)
	(segment
		(start 26.092658 -14.7955)
		(end 26.092658 -15.41018)
		(width 0.4572)
		(layer "F.Cu")
		(net "PSU_CSAHRE")
	)
	(segment
		(start 22.87397 -354.579428)
		(end 22.87397 -367.82756)
		(width 0.1524)
		(layer "F.Cu")
		(net "PSU_CSAHRE")
	)
	(segment
		(start 25.008586 -283.48432)
		(end 25.008586 -287.595564)
		(width 0.1524)
		(layer "F.Cu")
		(net "PSU_CSAHRE")
	)
	(segment
		(start 26.092658 -15.41018)
		(end 26.5049 -15.822422)
		(width 0.4572)
		(layer "F.Cu")
		(net "PSU_CSAHRE")
	)
	(segment
		(start 24.238204 -369.095274)
		(end 25.404826 -369.095274)
		(width 0.1524)
		(layer "F.Cu")
		(net "PSU_CSAHRE")
	)
	(segment
		(start 24.953214 -310.49976)
		(end 24.953214 -332.824328)
		(width 0.1524)
		(layer "F.Cu")
		(net "PSU_CSAHRE")
	)
	(segment
		(start 25.601676 -101.689408)
		(end 25.601676 -102.143052)
		(width 0.1524)
		(layer "F.Cu")
		(net "PSU_CSAHRE")
	)
	(segment
		(start 25.601676 -102.143052)
		(end 26.784554 -103.32593)
		(width 0.1524)
		(layer "F.Cu")
		(net "PSU_CSAHRE")
	)
	(segment
		(start 26.767282 -455.79284)
		(end 26.332434 -456.227688)
		(width 0.1524)
		(layer "F.Cu")
		(net "PSU_CSAHRE")
	)
	(segment
		(start 26.332434 -456.227688)
		(end 26.332434 -456.748896)
		(width 0.1524)
		(layer "F.Cu")
		(net "PSU_CSAHRE")
	)
	(segment
		(start 27.123644 -289.710622)
		(end 27.123644 -308.32933)
		(width 0.1524)
		(layer "F.Cu")
		(net "PSU_CSAHRE")
	)
	(segment
		(start 24.953214 -332.824328)
		(end 25.582626 -333.45374)
		(width 0.1524)
		(layer "F.Cu")
		(net "PSU_CSAHRE")
	)
	(segment
		(start 27.629866 -280.86304)
		(end 25.008586 -283.48432)
		(width 0.1524)
		(layer "F.Cu")
		(net "PSU_CSAHRE")
	)
	(segment
		(start 25.582626 -351.870772)
		(end 22.87397 -354.579428)
		(width 0.1524)
		(layer "F.Cu")
		(net "PSU_CSAHRE")
	)
	(segment
		(start 27.277314 -455.79284)
		(end 26.767282 -455.79284)
		(width 0.1524)
		(layer "F.Cu")
		(net "PSU_CSAHRE")
	)
	(segment
		(start 25.008586 -287.595564)
		(end 27.123644 -289.710622)
		(width 0.1524)
		(layer "F.Cu")
		(net "PSU_CSAHRE")
	)
	(segment
		(start 26.89352 -280.126694)
		(end 27.629866 -280.86304)
		(width 0.1524)
		(layer "F.Cu")
		(net "PSU_CSAHRE")
	)
	(segment
		(start 25.582626 -341.90051)
		(end 25.582626 -351.870772)
		(width 0.1524)
		(layer "F.Cu")
		(net "PSU_CSAHRE")
	)
	(segment
		(start 25.78608 -190.368174)
		(end 25.78608 -190.641986)
		(width 0.1524)
		(layer "F.Cu")
		(net "PSU_CSAHRE")
	)
	(segment
		(start 22.87397 -367.82756)
		(end 24.189944 -369.143534)
		(width 0.1524)
		(layer "F.Cu")
		(net "PSU_CSAHRE")
	)
	(segment
		(start 24.189944 -369.143534)
		(end 24.238204 -369.095274)
		(width 0.1524)
		(layer "F.Cu")
		(net "PSU_CSAHRE")
	)
	(segment
		(start 26.89352 -280.04389)
		(end 26.89352 -280.126694)
		(width 0.1524)
		(layer "F.Cu")
		(net "PSU_CSAHRE")
	)
	(segment
		(start 25.78608 -190.641986)
		(end 26.692098 -191.548004)
		(width 0.1524)
		(layer "F.Cu")
		(net "PSU_CSAHRE")
	)
	(via
		(at 26.692098 -191.548004)
		(size 0.508)
		(drill 0.254)
		(layers "F.Cu" "B.Cu")
		(net "PSU_CSAHRE")
	)
	(via
		(at 26.784554 -103.32593)
		(size 0.508)
		(drill 0.254)
		(layers "F.Cu" "B.Cu")
		(net "PSU_CSAHRE")
	)
	(via
		(at 26.5049 -15.822422)
		(size 0.508)
		(drill 0.254)
		(layers "F.Cu" "B.Cu")
		(net "PSU_CSAHRE")
	)
	(via
		(at 27.629866 -280.86304)
		(size 0.508)
		(drill 0.254)
		(layers "F.Cu" "B.Cu")
		(net "PSU_CSAHRE")
	)
	(via
		(at 24.189944 -369.143534)
		(size 0.508)
		(drill 0.254)
		(layers "F.Cu" "B.Cu")
		(net "PSU_CSAHRE")
	)
	(via
		(at 27.277314 -455.79284)
		(size 0.508)
		(drill 0.254)
		(layers "F.Cu" "B.Cu")
		(net "PSU_CSAHRE")
	)
	(via
		(at 25.582626 -341.90051)
		(size 0.508)
		(drill 0.254)
		(layers "F.Cu" "B.Cu")
		(net "PSU_CSAHRE")
	)
	(via
		(at 25.582626 -333.45374)
		(size 0.508)
		(drill 0.254)
		(layers "F.Cu" "B.Cu")
		(net "PSU_CSAHRE")
	)
	(segment
		(start 24.190198 -233.446066)
		(end 24.190198 -236.053376)
		(width 0.1524)
		(layer "B.Cu")
		(net "PSU_CSAHRE")
	)
	(segment
		(start 32.489902 -268.16685)
		(end 32.489902 -277.247604)
		(width 0.1524)
		(layer "B.Cu")
		(net "PSU_CSAHRE")
	)
	(segment
		(start 30.987746 -278.74976)
		(end 29.239464 -278.74976)
		(width 0.1524)
		(layer "B.Cu")
		(net "PSU_CSAHRE")
	)
	(segment
		(start 32.253682 -100.979478)
		(end 31.110174 -102.122986)
		(width 0.1524)
		(layer "B.Cu")
		(net "PSU_CSAHRE")
	)
	(segment
		(start 22.895306 -221.55023)
		(end 22.25929 -222.186246)
		(width 0.1524)
		(layer "B.Cu")
		(net "PSU_CSAHRE")
	)
	(segment
		(start 24.398478 -84.977224)
		(end 32.253682 -92.832428)
		(width 0.1524)
		(layer "B.Cu")
		(net "PSU_CSAHRE")
	)
	(segment
		(start 27.987752 -102.122986)
		(end 27.10815 -103.002588)
		(width 0.1524)
		(layer "B.Cu")
		(net "PSU_CSAHRE")
	)
	(segment
		(start 26.784554 -103.32593)
		(end 26.784554 -108.532422)
		(width 0.1524)
		(layer "B.Cu")
		(net "PSU_CSAHRE")
	)
	(segment
		(start 32.253682 -92.832428)
		(end 32.253682 -100.979478)
		(width 0.1524)
		(layer "B.Cu")
		(net "PSU_CSAHRE")
	)
	(segment
		(start 28.014422 -442.253878)
		(end 28.014422 -455.055732)
		(width 0.1524)
		(layer "B.Cu")
		(net "PSU_CSAHRE")
	)
	(segment
		(start 23.236174 -112.080802)
		(end 23.236174 -172.513244)
		(width 0.1524)
		(layer "B.Cu")
		(net "PSU_CSAHRE")
	)
	(segment
		(start 24.189944 -369.143534)
		(end 26.025602 -370.979192)
		(width 0.1524)
		(layer "B.Cu")
		(net "PSU_CSAHRE")
	)
	(segment
		(start 24.398478 -17.928844)
		(end 24.398478 -84.977224)
		(width 0.1524)
		(layer "B.Cu")
		(net "PSU_CSAHRE")
	)
	(segment
		(start 31.999174 -189.770258)
		(end 31.246064 -190.523368)
		(width 0.1524)
		(layer "B.Cu")
		(net "PSU_CSAHRE")
	)
	(segment
		(start 26.025602 -440.265058)
		(end 28.014422 -442.253878)
		(width 0.1524)
		(layer "B.Cu")
		(net "PSU_CSAHRE")
	)
	(segment
		(start 27.10815 -103.002588)
		(end 27.107896 -103.002588)
		(width 0.1524)
		(layer "B.Cu")
		(net "PSU_CSAHRE")
	)
	(segment
		(start 23.236174 -172.513244)
		(end 31.999174 -181.276244)
		(width 0.1524)
		(layer "B.Cu")
		(net "PSU_CSAHRE")
	)
	(segment
		(start 28.014422 -455.055732)
		(end 27.277314 -455.79284)
		(width 0.1524)
		(layer "B.Cu")
		(net "PSU_CSAHRE")
	)
	(segment
		(start 26.5049 -15.822422)
		(end 24.398478 -17.928844)
		(width 0.1524)
		(layer "B.Cu")
		(net "PSU_CSAHRE")
	)
	(segment
		(start 22.505924 -237.73765)
		(end 22.505924 -258.182872)
		(width 0.1524)
		(layer "B.Cu")
		(net "PSU_CSAHRE")
	)
	(segment
		(start 28.648406 -190.523368)
		(end 27.62377 -191.548004)
		(width 0.1524)
		(layer "B.Cu")
		(net "PSU_CSAHRE")
	)
	(segment
		(start 26.784554 -108.532422)
		(end 23.236174 -112.080802)
		(width 0.1524)
		(layer "B.Cu")
		(net "PSU_CSAHRE")
	)
	(segment
		(start 22.505924 -258.182872)
		(end 32.489902 -268.16685)
		(width 0.1524)
		(layer "B.Cu")
		(net "PSU_CSAHRE")
	)
	(segment
		(start 32.489902 -277.247604)
		(end 30.987746 -278.74976)
		(width 0.1524)
		(layer "B.Cu")
		(net "PSU_CSAHRE")
	)
	(segment
		(start 22.25929 -222.186246)
		(end 22.25929 -231.515158)
		(width 0.1524)
		(layer "B.Cu")
		(net "PSU_CSAHRE")
	)
	(segment
		(start 24.190198 -236.053376)
		(end 22.505924 -237.73765)
		(width 0.1524)
		(layer "B.Cu")
		(net "PSU_CSAHRE")
	)
	(segment
		(start 31.999174 -181.276244)
		(end 31.999174 -189.770258)
		(width 0.1524)
		(layer "B.Cu")
		(net "PSU_CSAHRE")
	)
	(segment
		(start 31.246064 -190.523368)
		(end 28.648406 -190.523368)
		(width 0.1524)
		(layer "B.Cu")
		(net "PSU_CSAHRE")
	)
	(segment
		(start 31.110174 -102.122986)
		(end 27.987752 -102.122986)
		(width 0.1524)
		(layer "B.Cu")
		(net "PSU_CSAHRE")
	)
	(segment
		(start 26.692098 -191.548004)
		(end 22.895306 -195.344796)
		(width 0.1524)
		(layer "B.Cu")
		(net "PSU_CSAHRE")
	)
	(segment
		(start 26.025602 -370.979192)
		(end 26.025602 -440.265058)
		(width 0.1524)
		(layer "B.Cu")
		(net "PSU_CSAHRE")
	)
	(segment
		(start 22.895306 -195.344796)
		(end 22.895306 -221.55023)
		(width 0.1524)
		(layer "B.Cu")
		(net "PSU_CSAHRE")
	)
	(segment
		(start 22.25929 -231.515158)
		(end 24.190198 -233.446066)
		(width 0.1524)
		(layer "B.Cu")
		(net "PSU_CSAHRE")
	)
	(segment
		(start 27.62377 -191.548004)
		(end 26.692098 -191.548004)
		(width 0.1524)
		(layer "B.Cu")
		(net "PSU_CSAHRE")
	)
	(segment
		(start 27.107896 -103.002588)
		(end 26.784554 -103.32593)
		(width 0.1524)
		(layer "B.Cu")
		(net "PSU_CSAHRE")
	)
	(segment
		(start 27.629866 -280.359358)
		(end 27.629866 -280.86304)
		(width 0.1524)
		(layer "B.Cu")
		(net "PSU_CSAHRE")
	)
	(segment
		(start 29.239464 -278.74976)
		(end 27.629866 -280.359358)
		(width 0.1524)
		(layer "B.Cu")
		(net "PSU_CSAHRE")
	)
	(segment
		(start 25.025604 -334.010762)
		(end 25.582626 -333.45374)
		(width 0.127)
		(layer "In2.Cu")
		(net "PSU_CSAHRE")
	)
	(segment
		(start 25.582626 -341.90051)
		(end 25.025604 -341.343488)
		(width 0.127)
		(layer "In2.Cu")
		(net "PSU_CSAHRE")
	)
	(segment
		(start 25.025604 -341.343488)
		(end 25.025604 -334.010762)
		(width 0.127)
		(layer "In2.Cu")
		(net "PSU_CSAHRE")
	)
	(via
		(at 84.6582 -235.829856)
		(size 0.508)
		(drill 0.254)
		(layers "F.Cu" "B.Cu")
		(net "T6_BLAD4_EN")
	)
	(segment
		(start 88.567768 -230.16845)
		(end 88.978486 -230.579168)
		(width 0.127)
		(layer "In2.Cu")
		(net "T6_BLAD4_EN")
	)
	(segment
		(start 11.078464 -272.390108)
		(end 18.309844 -265.158728)
		(width 0.127)
		(layer "In2.Cu")
		(net "T6_BLAD4_EN")
	)
	(segment
		(start 4.737862 -273.45767)
		(end 6.833616 -273.45767)
		(width 0.127)
		(layer "In2.Cu")
		(net "T6_BLAD4_EN")
	)
	(segment
		(start 84.930742 -241.3635)
		(end 84.930742 -239.257078)
		(width 0.127)
		(layer "In2.Cu")
		(net "T6_BLAD4_EN")
	)
	(segment
		(start 84.433156 -236.0549)
		(end 84.6582 -235.829856)
		(width 0.127)
		(layer "In2.Cu")
		(net "T6_BLAD4_EN")
	)
	(segment
		(start 84.433156 -238.759492)
		(end 84.433156 -236.0549)
		(width 0.127)
		(layer "In2.Cu")
		(net "T6_BLAD4_EN")
	)
	(segment
		(start 3.949954 -272.669762)
		(end 4.737862 -273.45767)
		(width 0.127)
		(layer "In2.Cu")
		(net "T6_BLAD4_EN")
	)
	(segment
		(start 7.901178 -272.390108)
		(end 11.078464 -272.390108)
		(width 0.127)
		(layer "In2.Cu")
		(net "T6_BLAD4_EN")
	)
	(segment
		(start 18.309844 -265.158728)
		(end 65.574418 -265.158728)
		(width 0.127)
		(layer "In2.Cu")
		(net "T6_BLAD4_EN")
	)
	(segment
		(start 84.037678 -246.695468)
		(end 84.037678 -242.256564)
		(width 0.127)
		(layer "In2.Cu")
		(net "T6_BLAD4_EN")
	)
	(segment
		(start 84.930742 -239.257078)
		(end 84.433156 -238.759492)
		(width 0.127)
		(layer "In2.Cu")
		(net "T6_BLAD4_EN")
	)
	(segment
		(start 6.833616 -273.45767)
		(end 7.901178 -272.390108)
		(width 0.127)
		(layer "In2.Cu")
		(net "T6_BLAD4_EN")
	)
	(segment
		(start 88.978486 -230.579168)
		(end 88.978486 -231.50957)
		(width 0.127)
		(layer "In2.Cu")
		(net "T6_BLAD4_EN")
	)
	(segment
		(start 65.574418 -265.158728)
		(end 84.037678 -246.695468)
		(width 0.127)
		(layer "In2.Cu")
		(net "T6_BLAD4_EN")
	)
	(segment
		(start 88.567768 -229.427024)
		(end 88.567768 -230.16845)
		(width 0.127)
		(layer "In2.Cu")
		(net "T6_BLAD4_EN")
	)
	(segment
		(start 84.037678 -242.256564)
		(end 84.930742 -241.3635)
		(width 0.127)
		(layer "In2.Cu")
		(net "T6_BLAD4_EN")
	)
	(segment
		(start 88.978486 -231.50957)
		(end 84.6582 -235.829856)
		(width 0.127)
		(layer "In2.Cu")
		(net "T6_BLAD4_EN")
	)
	(segment
		(start 89.44102 -227.26396)
		(end 89.44102 -228.553772)
		(width 0.127)
		(layer "In2.Cu")
		(net "T6_BLAD4_EN")
	)
	(segment
		(start 89.44991 -227.25507)
		(end 89.44102 -227.26396)
		(width 0.127)
		(layer "In2.Cu")
		(net "T6_BLAD4_EN")
	)
	(segment
		(start 89.44102 -228.553772)
		(end 88.567768 -229.427024)
		(width 0.127)
		(layer "In2.Cu")
		(net "T6_BLAD4_EN")
	)
	(via
		(at 82.968084 -238.706152)
		(size 0.508)
		(drill 0.254)
		(layers "F.Cu" "B.Cu")
		(net "T6_BLAD3_EN")
	)
	(segment
		(start 11.940794 -270.451326)
		(end 7.802118 -270.451326)
		(width 0.127)
		(layer "In2.Cu")
		(net "T6_BLAD3_EN")
	)
	(segment
		(start 7.802118 -270.451326)
		(end 6.785102 -271.468342)
		(width 0.127)
		(layer "In2.Cu")
		(net "T6_BLAD3_EN")
	)
	(segment
		(start 82.968084 -246.444516)
		(end 65.014856 -264.397744)
		(width 0.127)
		(layer "In2.Cu")
		(net "T6_BLAD3_EN")
	)
	(segment
		(start 3.485642 -271.468342)
		(end 2.650998 -272.302986)
		(width 0.127)
		(layer "In2.Cu")
		(net "T6_BLAD3_EN")
	)
	(segment
		(start 17.994376 -264.397744)
		(end 11.940794 -270.451326)
		(width 0.127)
		(layer "In2.Cu")
		(net "T6_BLAD3_EN")
	)
	(segment
		(start 88.17102 -229.889812)
		(end 87.313008 -230.747824)
		(width 0.127)
		(layer "In2.Cu")
		(net "T6_BLAD3_EN")
	)
	(segment
		(start 82.968084 -235.637324)
		(end 82.968084 -238.706152)
		(width 0.127)
		(layer "In2.Cu")
		(net "T6_BLAD3_EN")
	)
	(segment
		(start 87.313008 -231.2924)
		(end 82.968084 -235.637324)
		(width 0.127)
		(layer "In2.Cu")
		(net "T6_BLAD3_EN")
	)
	(segment
		(start 2.650998 -272.302986)
		(end 2.650998 -272.96872)
		(width 0.127)
		(layer "In2.Cu")
		(net "T6_BLAD3_EN")
	)
	(segment
		(start 65.014856 -264.397744)
		(end 17.994376 -264.397744)
		(width 0.127)
		(layer "In2.Cu")
		(net "T6_BLAD3_EN")
	)
	(segment
		(start 6.785102 -271.468342)
		(end 3.485642 -271.468342)
		(width 0.127)
		(layer "In2.Cu")
		(net "T6_BLAD3_EN")
	)
	(segment
		(start 87.313008 -230.747824)
		(end 87.313008 -231.2924)
		(width 0.127)
		(layer "In2.Cu")
		(net "T6_BLAD3_EN")
	)
	(segment
		(start 2.650998 -272.96872)
		(end 1.949958 -273.66976)
		(width 0.127)
		(layer "In2.Cu")
		(net "T6_BLAD3_EN")
	)
	(segment
		(start 82.968084 -238.706152)
		(end 82.968084 -246.444516)
		(width 0.127)
		(layer "In2.Cu")
		(net "T6_BLAD3_EN")
	)
	(segment
		(start 88.17991 -228.52507)
		(end 88.17102 -228.53396)
		(width 0.127)
		(layer "In2.Cu")
		(net "T6_BLAD3_EN")
	)
	(segment
		(start 88.17102 -228.53396)
		(end 88.17102 -229.889812)
		(width 0.127)
		(layer "In2.Cu")
		(net "T6_BLAD3_EN")
	)
	(via
		(at 82.262472 -236.214412)
		(size 0.508)
		(drill 0.254)
		(layers "F.Cu" "B.Cu")
		(net "T6_BLAD4_RXD")
	)
	(segment
		(start 10.641076 -253.550928)
		(end 8.893048 -251.8029)
		(width 0.127)
		(layer "In5.Cu")
		(net "T6_BLAD4_RXD")
	)
	(segment
		(start 82.262472 -239.444276)
		(end 82.807556 -239.98936)
		(width 0.127)
		(layer "In5.Cu")
		(net "T6_BLAD4_RXD")
	)
	(segment
		(start 82.807556 -242.231926)
		(end 64.161162 -260.87832)
		(width 0.127)
		(layer "In5.Cu")
		(net "T6_BLAD4_RXD")
	)
	(segment
		(start 64.161162 -260.87832)
		(end 48.518064 -260.87832)
		(width 0.127)
		(layer "In5.Cu")
		(net "T6_BLAD4_RXD")
	)
	(segment
		(start 10.641076 -255.329182)
		(end 10.641076 -253.550928)
		(width 0.127)
		(layer "In5.Cu")
		(net "T6_BLAD4_RXD")
	)
	(segment
		(start 82.807556 -239.98936)
		(end 82.807556 -242.231926)
		(width 0.127)
		(layer "In5.Cu")
		(net "T6_BLAD4_RXD")
	)
	(segment
		(start 47.845726 -261.550658)
		(end 16.862552 -261.550658)
		(width 0.127)
		(layer "In5.Cu")
		(net "T6_BLAD4_RXD")
	)
	(segment
		(start 86.536784 -226.234244)
		(end 90.969084 -226.234244)
		(width 0.127)
		(layer "In5.Cu")
		(net "T6_BLAD4_RXD")
	)
	(segment
		(start 8.045196 -251.8029)
		(end 6.967982 -252.880114)
		(width 0.127)
		(layer "In5.Cu")
		(net "T6_BLAD4_RXD")
	)
	(segment
		(start 82.262472 -235.645198)
		(end 83.53298 -234.37469)
		(width 0.127)
		(layer "In5.Cu")
		(net "T6_BLAD4_RXD")
	)
	(segment
		(start 90.969084 -226.234244)
		(end 91.98991 -227.25507)
		(width 0.127)
		(layer "In5.Cu")
		(net "T6_BLAD4_RXD")
	)
	(segment
		(start 6.967982 -252.880114)
		(end 5.76453 -252.880114)
		(width 0.127)
		(layer "In5.Cu")
		(net "T6_BLAD4_RXD")
	)
	(segment
		(start 5.27304 -253.371604)
		(end 5.27304 -254.346456)
		(width 0.127)
		(layer "In5.Cu")
		(net "T6_BLAD4_RXD")
	)
	(segment
		(start 8.893048 -251.8029)
		(end 8.045196 -251.8029)
		(width 0.127)
		(layer "In5.Cu")
		(net "T6_BLAD4_RXD")
	)
	(segment
		(start 5.27304 -254.346456)
		(end 3.948938 -255.670558)
		(width 0.127)
		(layer "In5.Cu")
		(net "T6_BLAD4_RXD")
	)
	(segment
		(start 82.262472 -236.214412)
		(end 82.262472 -239.444276)
		(width 0.127)
		(layer "In5.Cu")
		(net "T6_BLAD4_RXD")
	)
	(segment
		(start 83.53298 -229.238048)
		(end 86.536784 -226.234244)
		(width 0.127)
		(layer "In5.Cu")
		(net "T6_BLAD4_RXD")
	)
	(segment
		(start 16.862552 -261.550658)
		(end 10.641076 -255.329182)
		(width 0.127)
		(layer "In5.Cu")
		(net "T6_BLAD4_RXD")
	)
	(segment
		(start 48.518064 -260.87832)
		(end 47.845726 -261.550658)
		(width 0.127)
		(layer "In5.Cu")
		(net "T6_BLAD4_RXD")
	)
	(segment
		(start 5.76453 -252.880114)
		(end 5.27304 -253.371604)
		(width 0.127)
		(layer "In5.Cu")
		(net "T6_BLAD4_RXD")
	)
	(segment
		(start 83.53298 -234.37469)
		(end 83.53298 -229.238048)
		(width 0.127)
		(layer "In5.Cu")
		(net "T6_BLAD4_RXD")
	)
	(segment
		(start 82.262472 -236.214412)
		(end 82.262472 -235.645198)
		(width 0.127)
		(layer "In5.Cu")
		(net "T6_BLAD4_RXD")
	)
	(via
		(at 80.913478 -239.059212)
		(size 0.508)
		(drill 0.254)
		(layers "F.Cu" "B.Cu")
		(net "T6_BLAD4_TXD")
	)
	(segment
		(start 80.913478 -239.059212)
		(end 80.913478 -236.008926)
		(width 0.127)
		(layer "In5.Cu")
		(net "T6_BLAD4_TXD")
	)
	(segment
		(start 1.948942 -254.67056)
		(end 4.094988 -254.67056)
		(width 0.127)
		(layer "In5.Cu")
		(net "T6_BLAD4_TXD")
	)
	(segment
		(start 80.913478 -243.581682)
		(end 80.913478 -239.059212)
		(width 0.127)
		(layer "In5.Cu")
		(net "T6_BLAD4_TXD")
	)
	(segment
		(start 47.658528 -261.2009)
		(end 48.354996 -260.504432)
		(width 0.127)
		(layer "In5.Cu")
		(net "T6_BLAD4_TXD")
	)
	(segment
		(start 5.61086 -252.509528)
		(end 6.814312 -252.509528)
		(width 0.127)
		(layer "In5.Cu")
		(net "T6_BLAD4_TXD")
	)
	(segment
		(start 86.370414 -225.832924)
		(end 91.813888 -225.832924)
		(width 0.127)
		(layer "In5.Cu")
		(net "T6_BLAD4_TXD")
	)
	(segment
		(start 92.871544 -227.76815)
		(end 92.114624 -228.52507)
		(width 0.127)
		(layer "In5.Cu")
		(net "T6_BLAD4_TXD")
	)
	(segment
		(start 17.063974 -261.2009)
		(end 47.658528 -261.2009)
		(width 0.127)
		(layer "In5.Cu")
		(net "T6_BLAD4_TXD")
	)
	(segment
		(start 7.891526 -251.432314)
		(end 9.046718 -251.432314)
		(width 0.127)
		(layer "In5.Cu")
		(net "T6_BLAD4_TXD")
	)
	(segment
		(start 63.990728 -260.504432)
		(end 80.913478 -243.581682)
		(width 0.127)
		(layer "In5.Cu")
		(net "T6_BLAD4_TXD")
	)
	(segment
		(start 91.813888 -225.832924)
		(end 92.871544 -226.89058)
		(width 0.127)
		(layer "In5.Cu")
		(net "T6_BLAD4_TXD")
	)
	(segment
		(start 11.010138 -255.147064)
		(end 17.063974 -261.2009)
		(width 0.127)
		(layer "In5.Cu")
		(net "T6_BLAD4_TXD")
	)
	(segment
		(start 82.964782 -233.957622)
		(end 82.964782 -229.238556)
		(width 0.127)
		(layer "In5.Cu")
		(net "T6_BLAD4_TXD")
	)
	(segment
		(start 80.913478 -236.008926)
		(end 82.964782 -233.957622)
		(width 0.127)
		(layer "In5.Cu")
		(net "T6_BLAD4_TXD")
	)
	(segment
		(start 11.010138 -253.395734)
		(end 11.010138 -255.147064)
		(width 0.127)
		(layer "In5.Cu")
		(net "T6_BLAD4_TXD")
	)
	(segment
		(start 92.114624 -228.52507)
		(end 90.71991 -228.52507)
		(width 0.127)
		(layer "In5.Cu")
		(net "T6_BLAD4_TXD")
	)
	(segment
		(start 48.354996 -260.504432)
		(end 63.990728 -260.504432)
		(width 0.127)
		(layer "In5.Cu")
		(net "T6_BLAD4_TXD")
	)
	(segment
		(start 92.871544 -226.89058)
		(end 92.871544 -227.76815)
		(width 0.127)
		(layer "In5.Cu")
		(net "T6_BLAD4_TXD")
	)
	(segment
		(start 4.902454 -253.217934)
		(end 5.61086 -252.509528)
		(width 0.127)
		(layer "In5.Cu")
		(net "T6_BLAD4_TXD")
	)
	(segment
		(start 4.094988 -254.67056)
		(end 4.902454 -253.863094)
		(width 0.127)
		(layer "In5.Cu")
		(net "T6_BLAD4_TXD")
	)
	(segment
		(start 82.964782 -229.238556)
		(end 86.370414 -225.832924)
		(width 0.127)
		(layer "In5.Cu")
		(net "T6_BLAD4_TXD")
	)
	(segment
		(start 4.902454 -253.863094)
		(end 4.902454 -253.217934)
		(width 0.127)
		(layer "In5.Cu")
		(net "T6_BLAD4_TXD")
	)
	(segment
		(start 6.814312 -252.509528)
		(end 7.891526 -251.432314)
		(width 0.127)
		(layer "In5.Cu")
		(net "T6_BLAD4_TXD")
	)
	(segment
		(start 9.046718 -251.432314)
		(end 11.010138 -253.395734)
		(width 0.127)
		(layer "In5.Cu")
		(net "T6_BLAD4_TXD")
	)
	(via
		(at 82.320892 -240.310416)
		(size 0.508)
		(drill 0.254)
		(layers "F.Cu" "B.Cu")
		(net "T6_BLAD1_RXD")
	)
	(segment
		(start 86.90102 -229.80396)
		(end 86.90991 -229.79507)
		(width 0.127)
		(layer "In2.Cu")
		(net "T6_BLAD1_RXD")
	)
	(segment
		(start 64.765682 -263.998456)
		(end 82.320892 -246.443246)
		(width 0.127)
		(layer "In2.Cu")
		(net "T6_BLAD1_RXD")
	)
	(segment
		(start 81.759552 -237.75416)
		(end 81.759552 -236.054138)
		(width 0.127)
		(layer "In2.Cu")
		(net "T6_BLAD1_RXD")
	)
	(segment
		(start 6.61035 -269.925038)
		(end 7.658608 -268.87678)
		(width 0.127)
		(layer "In2.Cu")
		(net "T6_BLAD1_RXD")
	)
	(segment
		(start 81.759552 -236.054138)
		(end 86.90102 -230.91267)
		(width 0.127)
		(layer "In2.Cu")
		(net "T6_BLAD1_RXD")
	)
	(segment
		(start 82.320892 -246.443246)
		(end 82.320892 -240.310416)
		(width 0.127)
		(layer "In2.Cu")
		(net "T6_BLAD1_RXD")
	)
	(segment
		(start 3.949954 -270.669766)
		(end 5.419344 -270.669766)
		(width 0.127)
		(layer "In2.Cu")
		(net "T6_BLAD1_RXD")
	)
	(segment
		(start 5.419344 -270.669766)
		(end 6.164072 -269.925038)
		(width 0.127)
		(layer "In2.Cu")
		(net "T6_BLAD1_RXD")
	)
	(segment
		(start 12.794996 -268.87678)
		(end 17.67332 -263.998456)
		(width 0.127)
		(layer "In2.Cu")
		(net "T6_BLAD1_RXD")
	)
	(segment
		(start 86.90102 -230.91267)
		(end 86.90102 -229.80396)
		(width 0.127)
		(layer "In2.Cu")
		(net "T6_BLAD1_RXD")
	)
	(segment
		(start 82.320892 -240.310416)
		(end 82.320892 -238.3155)
		(width 0.127)
		(layer "In2.Cu")
		(net "T6_BLAD1_RXD")
	)
	(segment
		(start 6.164072 -269.925038)
		(end 6.61035 -269.925038)
		(width 0.127)
		(layer "In2.Cu")
		(net "T6_BLAD1_RXD")
	)
	(segment
		(start 17.67332 -263.998456)
		(end 64.765682 -263.998456)
		(width 0.127)
		(layer "In2.Cu")
		(net "T6_BLAD1_RXD")
	)
	(segment
		(start 82.320892 -238.3155)
		(end 81.759552 -237.75416)
		(width 0.127)
		(layer "In2.Cu")
		(net "T6_BLAD1_RXD")
	)
	(segment
		(start 7.658608 -268.87678)
		(end 12.794996 -268.87678)
		(width 0.127)
		(layer "In2.Cu")
		(net "T6_BLAD1_RXD")
	)
	(via
		(at 81.64195 -241.700558)
		(size 0.508)
		(drill 0.254)
		(layers "F.Cu" "B.Cu")
		(net "T6_BLAD1_TXD")
	)
	(segment
		(start 17.526254 -263.643618)
		(end 64.546734 -263.643618)
		(width 0.127)
		(layer "In2.Cu")
		(net "T6_BLAD1_TXD")
	)
	(segment
		(start 81.374488 -235.956602)
		(end 85.63991 -231.69118)
		(width 0.127)
		(layer "In2.Cu")
		(net "T6_BLAD1_TXD")
	)
	(segment
		(start 81.64195 -246.548402)
		(end 81.64195 -241.700558)
		(width 0.127)
		(layer "In2.Cu")
		(net "T6_BLAD1_TXD")
	)
	(segment
		(start 5.662422 -269.669768)
		(end 5.737352 -269.594838)
		(width 0.127)
		(layer "In2.Cu")
		(net "T6_BLAD1_TXD")
	)
	(segment
		(start 5.737352 -269.594838)
		(end 6.473444 -269.594838)
		(width 0.127)
		(layer "In2.Cu")
		(net "T6_BLAD1_TXD")
	)
	(segment
		(start 1.949958 -269.669768)
		(end 5.662422 -269.669768)
		(width 0.127)
		(layer "In2.Cu")
		(net "T6_BLAD1_TXD")
	)
	(segment
		(start 85.63991 -231.69118)
		(end 85.63991 -231.06507)
		(width 0.127)
		(layer "In2.Cu")
		(net "T6_BLAD1_TXD")
	)
	(segment
		(start 12.623292 -268.54658)
		(end 17.526254 -263.643618)
		(width 0.127)
		(layer "In2.Cu")
		(net "T6_BLAD1_TXD")
	)
	(segment
		(start 7.521702 -268.54658)
		(end 12.623292 -268.54658)
		(width 0.127)
		(layer "In2.Cu")
		(net "T6_BLAD1_TXD")
	)
	(segment
		(start 64.546734 -263.643618)
		(end 81.64195 -246.548402)
		(width 0.127)
		(layer "In2.Cu")
		(net "T6_BLAD1_TXD")
	)
	(segment
		(start 81.64195 -241.700558)
		(end 81.374488 -241.433096)
		(width 0.127)
		(layer "In2.Cu")
		(net "T6_BLAD1_TXD")
	)
	(segment
		(start 6.473444 -269.594838)
		(end 7.521702 -268.54658)
		(width 0.127)
		(layer "In2.Cu")
		(net "T6_BLAD1_TXD")
	)
	(segment
		(start 81.374488 -241.433096)
		(end 81.374488 -235.956602)
		(width 0.127)
		(layer "In2.Cu")
		(net "T6_BLAD1_TXD")
	)
	(via
		(at 86.26221 -235.294678)
		(size 0.508)
		(drill 0.254)
		(layers "F.Cu" "B.Cu")
		(net "T6_BLAD2_EN")
	)
	(segment
		(start 3.949954 -274.669758)
		(end 4.764024 -273.855688)
		(width 0.127)
		(layer "In2.Cu")
		(net "T6_BLAD2_EN")
	)
	(segment
		(start 86.26221 -238.694976)
		(end 86.26221 -235.294678)
		(width 0.127)
		(layer "In2.Cu")
		(net "T6_BLAD2_EN")
	)
	(segment
		(start 89.44102 -232.115868)
		(end 89.44102 -229.80396)
		(width 0.127)
		(layer "In2.Cu")
		(net "T6_BLAD2_EN")
	)
	(segment
		(start 86.26221 -235.294678)
		(end 89.44102 -232.115868)
		(width 0.127)
		(layer "In2.Cu")
		(net "T6_BLAD2_EN")
	)
	(segment
		(start 8.053578 -272.839434)
		(end 11.145774 -272.839434)
		(width 0.127)
		(layer "In2.Cu")
		(net "T6_BLAD2_EN")
	)
	(segment
		(start 7.037324 -273.855688)
		(end 8.053578 -272.839434)
		(width 0.127)
		(layer "In2.Cu")
		(net "T6_BLAD2_EN")
	)
	(segment
		(start 89.44102 -229.80396)
		(end 89.44991 -229.79507)
		(width 0.127)
		(layer "In2.Cu")
		(net "T6_BLAD2_EN")
	)
	(segment
		(start 4.764024 -273.855688)
		(end 7.037324 -273.855688)
		(width 0.127)
		(layer "In2.Cu")
		(net "T6_BLAD2_EN")
	)
	(segment
		(start 65.842134 -265.52398)
		(end 85.29955 -246.066564)
		(width 0.127)
		(layer "In2.Cu")
		(net "T6_BLAD2_EN")
	)
	(segment
		(start 11.145774 -272.839434)
		(end 18.461228 -265.52398)
		(width 0.127)
		(layer "In2.Cu")
		(net "T6_BLAD2_EN")
	)
	(segment
		(start 18.461228 -265.52398)
		(end 65.842134 -265.52398)
		(width 0.127)
		(layer "In2.Cu")
		(net "T6_BLAD2_EN")
	)
	(segment
		(start 85.29955 -246.066564)
		(end 85.29955 -239.657636)
		(width 0.127)
		(layer "In2.Cu")
		(net "T6_BLAD2_EN")
	)
	(segment
		(start 85.29955 -239.657636)
		(end 86.26221 -238.694976)
		(width 0.127)
		(layer "In2.Cu")
		(net "T6_BLAD2_EN")
	)
	(via
		(at 84.461858 -239.711484)
		(size 0.508)
		(drill 0.254)
		(layers "F.Cu" "B.Cu")
		(net "T6_BLAD3_RXD")
	)
	(segment
		(start 9.64311 -255.296162)
		(end 18.034 -263.687052)
		(width 0.127)
		(layer "In5.Cu")
		(net "T6_BLAD3_RXD")
	)
	(segment
		(start 62.374018 -263.687052)
		(end 84.461858 -241.599212)
		(width 0.127)
		(layer "In5.Cu")
		(net "T6_BLAD3_RXD")
	)
	(segment
		(start 84.461858 -239.711484)
		(end 84.461858 -237.86465)
		(width 0.127)
		(layer "In5.Cu")
		(net "T6_BLAD3_RXD")
	)
	(segment
		(start 8.910066 -253.843028)
		(end 9.64311 -254.576072)
		(width 0.127)
		(layer "In5.Cu")
		(net "T6_BLAD3_RXD")
	)
	(segment
		(start 3.948938 -257.670554)
		(end 5.566664 -256.052828)
		(width 0.127)
		(layer "In5.Cu")
		(net "T6_BLAD3_RXD")
	)
	(segment
		(start 18.034 -263.687052)
		(end 62.374018 -263.687052)
		(width 0.127)
		(layer "In5.Cu")
		(net "T6_BLAD3_RXD")
	)
	(segment
		(start 84.461858 -241.599212)
		(end 84.461858 -239.711484)
		(width 0.127)
		(layer "In5.Cu")
		(net "T6_BLAD3_RXD")
	)
	(segment
		(start 85.278214 -237.048294)
		(end 85.278214 -234.759754)
		(width 0.127)
		(layer "In5.Cu")
		(net "T6_BLAD3_RXD")
	)
	(segment
		(start 84.461858 -237.86465)
		(end 85.278214 -237.048294)
		(width 0.127)
		(layer "In5.Cu")
		(net "T6_BLAD3_RXD")
	)
	(segment
		(start 8.007858 -253.843028)
		(end 8.910066 -253.843028)
		(width 0.127)
		(layer "In5.Cu")
		(net "T6_BLAD3_RXD")
	)
	(segment
		(start 6.920484 -254.930402)
		(end 8.007858 -253.843028)
		(width 0.127)
		(layer "In5.Cu")
		(net "T6_BLAD3_RXD")
	)
	(segment
		(start 5.566664 -255.17348)
		(end 5.809742 -254.930402)
		(width 0.127)
		(layer "In5.Cu")
		(net "T6_BLAD3_RXD")
	)
	(segment
		(start 84.775294 -234.256834)
		(end 84.775294 -230.550212)
		(width 0.127)
		(layer "In5.Cu")
		(net "T6_BLAD3_RXD")
	)
	(segment
		(start 85.278214 -234.759754)
		(end 84.775294 -234.256834)
		(width 0.127)
		(layer "In5.Cu")
		(net "T6_BLAD3_RXD")
	)
	(segment
		(start 86.90991 -228.415596)
		(end 86.90991 -227.25507)
		(width 0.127)
		(layer "In5.Cu")
		(net "T6_BLAD3_RXD")
	)
	(segment
		(start 9.64311 -254.576072)
		(end 9.64311 -255.296162)
		(width 0.127)
		(layer "In5.Cu")
		(net "T6_BLAD3_RXD")
	)
	(segment
		(start 84.775294 -230.550212)
		(end 86.90991 -228.415596)
		(width 0.127)
		(layer "In5.Cu")
		(net "T6_BLAD3_RXD")
	)
	(segment
		(start 5.809742 -254.930402)
		(end 6.920484 -254.930402)
		(width 0.127)
		(layer "In5.Cu")
		(net "T6_BLAD3_RXD")
	)
	(segment
		(start 5.566664 -256.052828)
		(end 5.566664 -255.17348)
		(width 0.127)
		(layer "In5.Cu")
		(net "T6_BLAD3_RXD")
	)
	(via
		(at 83.804252 -240.984024)
		(size 0.508)
		(drill 0.254)
		(layers "F.Cu" "B.Cu")
		(net "T6_BLAD3_TXD")
	)
	(segment
		(start 82.98942 -235.914692)
		(end 84.115402 -234.78871)
		(width 0.127)
		(layer "In5.Cu")
		(net "T6_BLAD3_TXD")
	)
	(segment
		(start 5.20319 -255.509014)
		(end 5.20319 -255.022858)
		(width 0.127)
		(layer "In5.Cu")
		(net "T6_BLAD3_TXD")
	)
	(segment
		(start 18.17116 -263.356344)
		(end 62.214506 -263.356344)
		(width 0.127)
		(layer "In5.Cu")
		(net "T6_BLAD3_TXD")
	)
	(segment
		(start 10.108946 -255.29413)
		(end 18.17116 -263.356344)
		(width 0.127)
		(layer "In5.Cu")
		(net "T6_BLAD3_TXD")
	)
	(segment
		(start 84.115402 -230.049578)
		(end 85.63991 -228.52507)
		(width 0.127)
		(layer "In5.Cu")
		(net "T6_BLAD3_TXD")
	)
	(segment
		(start 1.948942 -256.670556)
		(end 4.041648 -256.670556)
		(width 0.127)
		(layer "In5.Cu")
		(net "T6_BLAD3_TXD")
	)
	(segment
		(start 5.635244 -254.590804)
		(end 6.745986 -254.590804)
		(width 0.127)
		(layer "In5.Cu")
		(net "T6_BLAD3_TXD")
	)
	(segment
		(start 4.041648 -256.670556)
		(end 5.20319 -255.509014)
		(width 0.127)
		(layer "In5.Cu")
		(net "T6_BLAD3_TXD")
	)
	(segment
		(start 83.804252 -240.984024)
		(end 83.804252 -238.258604)
		(width 0.127)
		(layer "In5.Cu")
		(net "T6_BLAD3_TXD")
	)
	(segment
		(start 84.115402 -234.78871)
		(end 84.115402 -230.049578)
		(width 0.127)
		(layer "In5.Cu")
		(net "T6_BLAD3_TXD")
	)
	(segment
		(start 82.98942 -237.443772)
		(end 82.98942 -235.914692)
		(width 0.127)
		(layer "In5.Cu")
		(net "T6_BLAD3_TXD")
	)
	(segment
		(start 83.804252 -241.766598)
		(end 83.804252 -240.984024)
		(width 0.127)
		(layer "In5.Cu")
		(net "T6_BLAD3_TXD")
	)
	(segment
		(start 5.20319 -255.022858)
		(end 5.635244 -254.590804)
		(width 0.127)
		(layer "In5.Cu")
		(net "T6_BLAD3_TXD")
	)
	(segment
		(start 62.214506 -263.356344)
		(end 83.804252 -241.766598)
		(width 0.127)
		(layer "In5.Cu")
		(net "T6_BLAD3_TXD")
	)
	(segment
		(start 9.060688 -253.479554)
		(end 10.108946 -254.527812)
		(width 0.127)
		(layer "In5.Cu")
		(net "T6_BLAD3_TXD")
	)
	(segment
		(start 83.804252 -238.258604)
		(end 82.98942 -237.443772)
		(width 0.127)
		(layer "In5.Cu")
		(net "T6_BLAD3_TXD")
	)
	(segment
		(start 6.745986 -254.590804)
		(end 7.857236 -253.479554)
		(width 0.127)
		(layer "In5.Cu")
		(net "T6_BLAD3_TXD")
	)
	(segment
		(start 7.857236 -253.479554)
		(end 9.060688 -253.479554)
		(width 0.127)
		(layer "In5.Cu")
		(net "T6_BLAD3_TXD")
	)
	(segment
		(start 10.108946 -254.527812)
		(end 10.108946 -255.29413)
		(width 0.127)
		(layer "In5.Cu")
		(net "T6_BLAD3_TXD")
	)
	(via
		(at 83.191096 -192.53708)
		(size 0.508)
		(drill 0.254)
		(layers "F.Cu" "B.Cu")
		(net "T5_BLAD4_RXD")
	)
	(segment
		(start 82.935572 -231.096566)
		(end 82.935572 -216.372948)
		(width 0.127)
		(layer "In2.Cu")
		(net "T5_BLAD4_RXD")
	)
	(segment
		(start 83.191096 -201.505566)
		(end 83.191096 -192.53708)
		(width 0.127)
		(layer "In2.Cu")
		(net "T5_BLAD4_RXD")
	)
	(segment
		(start 8.448802 -248.670572)
		(end 8.448802 -250.881388)
		(width 0.127)
		(layer "In2.Cu")
		(net "T5_BLAD4_RXD")
	)
	(segment
		(start 78.310994 -235.721144)
		(end 82.935572 -231.096566)
		(width 0.127)
		(layer "In2.Cu")
		(net "T5_BLAD4_RXD")
	)
	(segment
		(start 42.857674 -260.79323)
		(end 45.440854 -260.79323)
		(width 0.127)
		(layer "In2.Cu")
		(net "T5_BLAD4_RXD")
	)
	(segment
		(start 78.310994 -246.247158)
		(end 78.310994 -235.721144)
		(width 0.127)
		(layer "In2.Cu")
		(net "T5_BLAD4_RXD")
	)
	(segment
		(start 17.066006 -261.178548)
		(end 42.472356 -261.178548)
		(width 0.127)
		(layer "In2.Cu")
		(net "T5_BLAD4_RXD")
	)
	(segment
		(start 46.474126 -259.759958)
		(end 64.798448 -259.759958)
		(width 0.127)
		(layer "In2.Cu")
		(net "T5_BLAD4_RXD")
	)
	(segment
		(start 90.650822 -181.465728)
		(end 85.447632 -181.465728)
		(width 0.127)
		(layer "In2.Cu")
		(net "T5_BLAD4_RXD")
	)
	(segment
		(start 84.282026 -215.026494)
		(end 84.282026 -202.596496)
		(width 0.127)
		(layer "In2.Cu")
		(net "T5_BLAD4_RXD")
	)
	(segment
		(start 84.282026 -202.596496)
		(end 83.191096 -201.505566)
		(width 0.127)
		(layer "In2.Cu")
		(net "T5_BLAD4_RXD")
	)
	(segment
		(start 8.448802 -250.881388)
		(end 12.665964 -255.09855)
		(width 0.127)
		(layer "In2.Cu")
		(net "T5_BLAD4_RXD")
	)
	(segment
		(start 83.191096 -183.722264)
		(end 83.191096 -192.53708)
		(width 0.127)
		(layer "In2.Cu")
		(net "T5_BLAD4_RXD")
	)
	(segment
		(start 45.440854 -260.79323)
		(end 46.474126 -259.759958)
		(width 0.127)
		(layer "In2.Cu")
		(net "T5_BLAD4_RXD")
	)
	(segment
		(start 82.935572 -216.372948)
		(end 84.282026 -215.026494)
		(width 0.127)
		(layer "In2.Cu")
		(net "T5_BLAD4_RXD")
	)
	(segment
		(start 12.665964 -256.778506)
		(end 17.066006 -261.178548)
		(width 0.127)
		(layer "In2.Cu")
		(net "T5_BLAD4_RXD")
	)
	(segment
		(start 91.990164 -182.80507)
		(end 90.650822 -181.465728)
		(width 0.127)
		(layer "In2.Cu")
		(net "T5_BLAD4_RXD")
	)
	(segment
		(start 42.472356 -261.178548)
		(end 42.857674 -260.79323)
		(width 0.127)
		(layer "In2.Cu")
		(net "T5_BLAD4_RXD")
	)
	(segment
		(start 12.665964 -255.09855)
		(end 12.665964 -256.778506)
		(width 0.127)
		(layer "In2.Cu")
		(net "T5_BLAD4_RXD")
	)
	(segment
		(start 85.447632 -181.465728)
		(end 83.191096 -183.722264)
		(width 0.127)
		(layer "In2.Cu")
		(net "T5_BLAD4_RXD")
	)
	(segment
		(start 64.798448 -259.759958)
		(end 78.310994 -246.247158)
		(width 0.127)
		(layer "In2.Cu")
		(net "T5_BLAD4_RXD")
	)
	(via
		(at 96.567244 -193.482468)
		(size 0.508)
		(drill 0.254)
		(layers "F.Cu" "B.Cu")
		(net "T5_BLAD4_EN")
	)
	(segment
		(start 92.166948 -189.082172)
		(end 96.567244 -193.482468)
		(width 0.127)
		(layer "In5.Cu")
		(net "T5_BLAD4_EN")
	)
	(segment
		(start 80.61325 -249.182636)
		(end 63.95339 -265.842496)
		(width 0.127)
		(layer "In5.Cu")
		(net "T5_BLAD4_EN")
	)
	(segment
		(start 96.567244 -193.482468)
		(end 100.64242 -197.557644)
		(width 0.127)
		(layer "In5.Cu")
		(net "T5_BLAD4_EN")
	)
	(segment
		(start 87.340694 -186.959494)
		(end 89.463372 -189.082172)
		(width 0.127)
		(layer "In5.Cu")
		(net "T5_BLAD4_EN")
	)
	(segment
		(start 89.450164 -184.11317)
		(end 87.340694 -186.22264)
		(width 0.127)
		(layer "In5.Cu")
		(net "T5_BLAD4_EN")
	)
	(segment
		(start 89.463372 -189.082172)
		(end 92.166948 -189.082172)
		(width 0.127)
		(layer "In5.Cu")
		(net "T5_BLAD4_EN")
	)
	(segment
		(start 100.64242 -242.38712)
		(end 93.846904 -249.182636)
		(width 0.127)
		(layer "In5.Cu")
		(net "T5_BLAD4_EN")
	)
	(segment
		(start 63.95339 -265.842496)
		(end 11.810492 -265.842496)
		(width 0.127)
		(layer "In5.Cu")
		(net "T5_BLAD4_EN")
	)
	(segment
		(start 89.450164 -182.80507)
		(end 89.450164 -184.11317)
		(width 0.127)
		(layer "In5.Cu")
		(net "T5_BLAD4_EN")
	)
	(segment
		(start 87.340694 -186.22264)
		(end 87.340694 -186.959494)
		(width 0.127)
		(layer "In5.Cu")
		(net "T5_BLAD4_EN")
	)
	(segment
		(start 11.810492 -265.842496)
		(end 6.448806 -260.48081)
		(width 0.127)
		(layer "In5.Cu")
		(net "T5_BLAD4_EN")
	)
	(segment
		(start 100.64242 -197.557644)
		(end 100.64242 -242.38712)
		(width 0.127)
		(layer "In5.Cu")
		(net "T5_BLAD4_EN")
	)
	(segment
		(start 93.846904 -249.182636)
		(end 80.61325 -249.182636)
		(width 0.127)
		(layer "In5.Cu")
		(net "T5_BLAD4_EN")
	)
	(segment
		(start 6.448806 -260.48081)
		(end 6.448806 -259.67055)
		(width 0.127)
		(layer "In5.Cu")
		(net "T5_BLAD4_EN")
	)
	(via
		(at 95.670116 -191.705992)
		(size 0.508)
		(drill 0.254)
		(layers "F.Cu" "B.Cu")
		(net "T5_BLAD1_EN")
	)
	(segment
		(start 9.92124 -266.19835)
		(end 6.449822 -269.669768)
		(width 0.127)
		(layer "In5.Cu")
		(net "T5_BLAD1_EN")
	)
	(segment
		(start 64.191134 -266.19835)
		(end 9.92124 -266.19835)
		(width 0.127)
		(layer "In5.Cu")
		(net "T5_BLAD1_EN")
	)
	(segment
		(start 88.180164 -186.61507)
		(end 90.19413 -188.629036)
		(width 0.127)
		(layer "In5.Cu")
		(net "T5_BLAD1_EN")
	)
	(segment
		(start 92.59316 -188.629036)
		(end 95.670116 -191.705992)
		(width 0.127)
		(layer "In5.Cu")
		(net "T5_BLAD1_EN")
	)
	(segment
		(start 80.531716 -249.857768)
		(end 64.191134 -266.19835)
		(width 0.127)
		(layer "In5.Cu")
		(net "T5_BLAD1_EN")
	)
	(segment
		(start 101.097588 -242.575842)
		(end 93.815662 -249.857768)
		(width 0.127)
		(layer "In5.Cu")
		(net "T5_BLAD1_EN")
	)
	(segment
		(start 93.815662 -249.857768)
		(end 80.531716 -249.857768)
		(width 0.127)
		(layer "In5.Cu")
		(net "T5_BLAD1_EN")
	)
	(segment
		(start 90.19413 -188.629036)
		(end 92.59316 -188.629036)
		(width 0.127)
		(layer "In5.Cu")
		(net "T5_BLAD1_EN")
	)
	(segment
		(start 6.449822 -269.669768)
		(end 6.449822 -270.669766)
		(width 0.127)
		(layer "In5.Cu")
		(net "T5_BLAD1_EN")
	)
	(segment
		(start 101.097588 -197.133464)
		(end 101.097588 -242.575842)
		(width 0.127)
		(layer "In5.Cu")
		(net "T5_BLAD1_EN")
	)
	(segment
		(start 95.670116 -191.705992)
		(end 101.097588 -197.133464)
		(width 0.127)
		(layer "In5.Cu")
		(net "T5_BLAD1_EN")
	)
	(via
		(at 99.384612 -194.537076)
		(size 0.508)
		(drill 0.254)
		(layers "F.Cu" "B.Cu")
		(net "T5_BLAD2_EN")
	)
	(segment
		(start 89.450164 -185.34507)
		(end 89.450164 -186.913774)
		(width 0.127)
		(layer "In5.Cu")
		(net "T5_BLAD2_EN")
	)
	(segment
		(start 89.450164 -186.913774)
		(end 90.7034 -188.16701)
		(width 0.127)
		(layer "In5.Cu")
		(net "T5_BLAD2_EN")
	)
	(segment
		(start 99.384612 -194.558666)
		(end 99.384612 -194.537076)
		(width 0.127)
		(layer "In5.Cu")
		(net "T5_BLAD2_EN")
	)
	(segment
		(start 10.581894 -266.537694)
		(end 8.449818 -268.66977)
		(width 0.127)
		(layer "In5.Cu")
		(net "T5_BLAD2_EN")
	)
	(segment
		(start 80.665828 -250.27128)
		(end 64.399414 -266.537694)
		(width 0.127)
		(layer "In5.Cu")
		(net "T5_BLAD2_EN")
	)
	(segment
		(start 101.529388 -242.754912)
		(end 94.01302 -250.27128)
		(width 0.127)
		(layer "In5.Cu")
		(net "T5_BLAD2_EN")
	)
	(segment
		(start 90.7034 -188.16701)
		(end 92.992956 -188.16701)
		(width 0.127)
		(layer "In5.Cu")
		(net "T5_BLAD2_EN")
	)
	(segment
		(start 92.992956 -188.16701)
		(end 99.384612 -194.558666)
		(width 0.127)
		(layer "In5.Cu")
		(net "T5_BLAD2_EN")
	)
	(segment
		(start 99.384612 -194.558666)
		(end 101.529388 -196.703442)
		(width 0.127)
		(layer "In5.Cu")
		(net "T5_BLAD2_EN")
	)
	(segment
		(start 64.399414 -266.537694)
		(end 10.581894 -266.537694)
		(width 0.127)
		(layer "In5.Cu")
		(net "T5_BLAD2_EN")
	)
	(segment
		(start 94.01302 -250.27128)
		(end 80.665828 -250.27128)
		(width 0.127)
		(layer "In5.Cu")
		(net "T5_BLAD2_EN")
	)
	(segment
		(start 8.449818 -268.66977)
		(end 8.449818 -269.669768)
		(width 0.127)
		(layer "In5.Cu")
		(net "T5_BLAD2_EN")
	)
	(segment
		(start 101.529388 -196.703442)
		(end 101.529388 -242.754912)
		(width 0.127)
		(layer "In5.Cu")
		(net "T5_BLAD2_EN")
	)
	(via
		(at 84.83854 -192.681352)
		(size 0.508)
		(drill 0.254)
		(layers "F.Cu" "B.Cu")
		(net "T5_BLAD3_TXD")
	)
	(segment
		(start 11.404092 -256.918714)
		(end 17.03578 -262.550402)
		(width 0.127)
		(layer "In2.Cu")
		(net "T5_BLAD3_TXD")
	)
	(segment
		(start 8.050276 -253.440184)
		(end 8.871458 -253.440184)
		(width 0.127)
		(layer "In2.Cu")
		(net "T5_BLAD3_TXD")
	)
	(segment
		(start 17.03578 -262.550402)
		(end 46.75378 -262.550402)
		(width 0.127)
		(layer "In2.Cu")
		(net "T5_BLAD3_TXD")
	)
	(segment
		(start 84.83854 -201.092816)
		(end 84.83854 -192.681352)
		(width 0.127)
		(layer "In2.Cu")
		(net "T5_BLAD3_TXD")
	)
	(segment
		(start 84.125308 -231.731312)
		(end 84.125308 -216.863676)
		(width 0.127)
		(layer "In2.Cu")
		(net "T5_BLAD3_TXD")
	)
	(segment
		(start 6.448806 -251.670566)
		(end 7.551674 -252.773434)
		(width 0.127)
		(layer "In2.Cu")
		(net "T5_BLAD3_TXD")
	)
	(segment
		(start 85.640164 -184.07507)
		(end 84.83854 -184.876694)
		(width 0.127)
		(layer "In2.Cu")
		(net "T5_BLAD3_TXD")
	)
	(segment
		(start 85.485732 -215.503252)
		(end 85.485732 -201.740008)
		(width 0.127)
		(layer "In2.Cu")
		(net "T5_BLAD3_TXD")
	)
	(segment
		(start 7.551674 -252.773434)
		(end 7.551674 -252.941582)
		(width 0.127)
		(layer "In2.Cu")
		(net "T5_BLAD3_TXD")
	)
	(segment
		(start 65.511934 -260.831584)
		(end 79.572866 -246.770398)
		(width 0.127)
		(layer "In2.Cu")
		(net "T5_BLAD3_TXD")
	)
	(segment
		(start 85.485732 -201.740008)
		(end 84.83854 -201.092816)
		(width 0.127)
		(layer "In2.Cu")
		(net "T5_BLAD3_TXD")
	)
	(segment
		(start 46.75378 -262.550402)
		(end 48.472598 -260.831584)
		(width 0.127)
		(layer "In2.Cu")
		(net "T5_BLAD3_TXD")
	)
	(segment
		(start 84.83854 -184.876694)
		(end 84.83854 -192.681352)
		(width 0.127)
		(layer "In2.Cu")
		(net "T5_BLAD3_TXD")
	)
	(segment
		(start 79.572866 -236.283754)
		(end 84.125308 -231.731312)
		(width 0.127)
		(layer "In2.Cu")
		(net "T5_BLAD3_TXD")
	)
	(segment
		(start 8.871458 -253.440184)
		(end 11.404092 -255.972818)
		(width 0.127)
		(layer "In2.Cu")
		(net "T5_BLAD3_TXD")
	)
	(segment
		(start 11.404092 -255.972818)
		(end 11.404092 -256.918714)
		(width 0.127)
		(layer "In2.Cu")
		(net "T5_BLAD3_TXD")
	)
	(segment
		(start 84.125308 -216.863676)
		(end 85.485732 -215.503252)
		(width 0.127)
		(layer "In2.Cu")
		(net "T5_BLAD3_TXD")
	)
	(segment
		(start 79.572866 -246.770398)
		(end 79.572866 -236.283754)
		(width 0.127)
		(layer "In2.Cu")
		(net "T5_BLAD3_TXD")
	)
	(segment
		(start 48.472598 -260.831584)
		(end 65.511934 -260.831584)
		(width 0.127)
		(layer "In2.Cu")
		(net "T5_BLAD3_TXD")
	)
	(segment
		(start 7.551674 -252.941582)
		(end 8.050276 -253.440184)
		(width 0.127)
		(layer "In2.Cu")
		(net "T5_BLAD3_TXD")
	)
	(via
		(at 98.24466 -196.681852)
		(size 0.508)
		(drill 0.254)
		(layers "F.Cu" "B.Cu")
		(net "T5_BLAD3_EN")
	)
	(segment
		(start 86.52256 -187.386976)
		(end 89.158572 -190.022988)
		(width 0.127)
		(layer "In5.Cu")
		(net "T5_BLAD3_EN")
	)
	(segment
		(start 99.828858 -198.26605)
		(end 98.24466 -196.681852)
		(width 0.127)
		(layer "In5.Cu")
		(net "T5_BLAD3_EN")
	)
	(segment
		(start 93.397578 -248.40692)
		(end 99.828858 -241.97564)
		(width 0.127)
		(layer "In5.Cu")
		(net "T5_BLAD3_EN")
	)
	(segment
		(start 89.158572 -190.022988)
		(end 91.585796 -190.022988)
		(width 0.127)
		(layer "In5.Cu")
		(net "T5_BLAD3_EN")
	)
	(segment
		(start 86.027768 -184.89803)
		(end 86.027768 -185.868564)
		(width 0.127)
		(layer "In5.Cu")
		(net "T5_BLAD3_EN")
	)
	(segment
		(start 63.637922 -265.118342)
		(end 80.349344 -248.40692)
		(width 0.127)
		(layer "In5.Cu")
		(net "T5_BLAD3_EN")
	)
	(segment
		(start 12.896596 -265.118342)
		(end 63.637922 -265.118342)
		(width 0.127)
		(layer "In5.Cu")
		(net "T5_BLAD3_EN")
	)
	(segment
		(start 8.448802 -260.670548)
		(end 12.896596 -265.118342)
		(width 0.127)
		(layer "In5.Cu")
		(net "T5_BLAD3_EN")
	)
	(segment
		(start 99.828858 -241.97564)
		(end 99.828858 -198.26605)
		(width 0.127)
		(layer "In5.Cu")
		(net "T5_BLAD3_EN")
	)
	(segment
		(start 91.585796 -190.022988)
		(end 98.24466 -196.681852)
		(width 0.127)
		(layer "In5.Cu")
		(net "T5_BLAD3_EN")
	)
	(segment
		(start 88.162892 -184.092342)
		(end 86.833456 -184.092342)
		(width 0.127)
		(layer "In5.Cu")
		(net "T5_BLAD3_EN")
	)
	(segment
		(start 86.027768 -185.868564)
		(end 86.52256 -186.363356)
		(width 0.127)
		(layer "In5.Cu")
		(net "T5_BLAD3_EN")
	)
	(segment
		(start 80.349344 -248.40692)
		(end 93.397578 -248.40692)
		(width 0.127)
		(layer "In5.Cu")
		(net "T5_BLAD3_EN")
	)
	(segment
		(start 88.180164 -184.07507)
		(end 88.162892 -184.092342)
		(width 0.127)
		(layer "In5.Cu")
		(net "T5_BLAD3_EN")
	)
	(segment
		(start 86.52256 -186.363356)
		(end 86.52256 -187.386976)
		(width 0.127)
		(layer "In5.Cu")
		(net "T5_BLAD3_EN")
	)
	(segment
		(start 86.833456 -184.092342)
		(end 86.027768 -184.89803)
		(width 0.127)
		(layer "In5.Cu")
		(net "T5_BLAD3_EN")
	)
	(via
		(at 97.254568 -194.99834)
		(size 0.508)
		(drill 0.254)
		(layers "F.Cu" "B.Cu")
		(net "T5_BLAD1_RXD")
	)
	(segment
		(start 86.910164 -187.134246)
		(end 86.910164 -185.34507)
		(width 0.127)
		(layer "In5.Cu")
		(net "T5_BLAD1_RXD")
	)
	(segment
		(start 97.254568 -194.99834)
		(end 100.18141 -197.925182)
		(width 0.127)
		(layer "In5.Cu")
		(net "T5_BLAD1_RXD")
	)
	(segment
		(start 63.84925 -265.469878)
		(end 12.190984 -265.469878)
		(width 0.127)
		(layer "In5.Cu")
		(net "T5_BLAD1_RXD")
	)
	(segment
		(start 12.190984 -265.469878)
		(end 7.513066 -260.79196)
		(width 0.127)
		(layer "In5.Cu")
		(net "T5_BLAD1_RXD")
	)
	(segment
		(start 100.18141 -242.196112)
		(end 93.606112 -248.77141)
		(width 0.127)
		(layer "In5.Cu")
		(net "T5_BLAD1_RXD")
	)
	(segment
		(start 80.547718 -248.77141)
		(end 63.84925 -265.469878)
		(width 0.127)
		(layer "In5.Cu")
		(net "T5_BLAD1_RXD")
	)
	(segment
		(start 89.342722 -189.566804)
		(end 86.910164 -187.134246)
		(width 0.127)
		(layer "In5.Cu")
		(net "T5_BLAD1_RXD")
	)
	(segment
		(start 7.513066 -260.79196)
		(end 7.513066 -258.734814)
		(width 0.127)
		(layer "In5.Cu")
		(net "T5_BLAD1_RXD")
	)
	(segment
		(start 100.18141 -197.925182)
		(end 100.18141 -242.196112)
		(width 0.127)
		(layer "In5.Cu")
		(net "T5_BLAD1_RXD")
	)
	(segment
		(start 97.254568 -194.99834)
		(end 91.823032 -189.566804)
		(width 0.127)
		(layer "In5.Cu")
		(net "T5_BLAD1_RXD")
	)
	(segment
		(start 93.606112 -248.77141)
		(end 80.547718 -248.77141)
		(width 0.127)
		(layer "In5.Cu")
		(net "T5_BLAD1_RXD")
	)
	(segment
		(start 91.823032 -189.566804)
		(end 89.342722 -189.566804)
		(width 0.127)
		(layer "In5.Cu")
		(net "T5_BLAD1_RXD")
	)
	(segment
		(start 7.513066 -258.734814)
		(end 6.448806 -257.670554)
		(width 0.127)
		(layer "In5.Cu")
		(net "T5_BLAD1_RXD")
	)
	(via
		(at 86.109048 -191.226186)
		(size 0.508)
		(drill 0.254)
		(layers "F.Cu" "B.Cu")
		(net "T5_BLAD2_TXD")
	)
	(segment
		(start 8.761984 -253.93015)
		(end 7.711694 -253.93015)
		(width 0.127)
		(layer "In2.Cu")
		(net "T5_BLAD2_TXD")
	)
	(segment
		(start 86.109048 -191.226186)
		(end 90.720164 -186.61507)
		(width 0.127)
		(layer "In2.Cu")
		(net "T5_BLAD2_TXD")
	)
	(segment
		(start 86.109048 -191.226186)
		(end 85.83295 -191.502284)
		(width 0.127)
		(layer "In2.Cu")
		(net "T5_BLAD2_TXD")
	)
	(segment
		(start 79.920084 -236.427772)
		(end 79.920084 -246.914416)
		(width 0.127)
		(layer "In2.Cu")
		(net "T5_BLAD2_TXD")
	)
	(segment
		(start 65.554606 -261.280148)
		(end 48.76419 -261.280148)
		(width 0.127)
		(layer "In2.Cu")
		(net "T5_BLAD2_TXD")
	)
	(segment
		(start 84.472526 -217.095578)
		(end 84.472526 -231.87533)
		(width 0.127)
		(layer "In2.Cu")
		(net "T5_BLAD2_TXD")
	)
	(segment
		(start 10.907776 -256.075942)
		(end 8.761984 -253.93015)
		(width 0.127)
		(layer "In2.Cu")
		(net "T5_BLAD2_TXD")
	)
	(segment
		(start 7.711694 -253.93015)
		(end 7.452106 -253.670562)
		(width 0.127)
		(layer "In2.Cu")
		(net "T5_BLAD2_TXD")
	)
	(segment
		(start 85.83295 -191.502284)
		(end 85.83295 -215.735154)
		(width 0.127)
		(layer "In2.Cu")
		(net "T5_BLAD2_TXD")
	)
	(segment
		(start 85.83295 -215.735154)
		(end 84.472526 -217.095578)
		(width 0.127)
		(layer "In2.Cu")
		(net "T5_BLAD2_TXD")
	)
	(segment
		(start 48.76419 -261.280148)
		(end 47.146718 -262.89762)
		(width 0.127)
		(layer "In2.Cu")
		(net "T5_BLAD2_TXD")
	)
	(segment
		(start 7.452106 -253.670562)
		(end 6.448806 -253.670562)
		(width 0.127)
		(layer "In2.Cu")
		(net "T5_BLAD2_TXD")
	)
	(segment
		(start 10.907776 -257.134868)
		(end 10.907776 -256.075942)
		(width 0.127)
		(layer "In2.Cu")
		(net "T5_BLAD2_TXD")
	)
	(segment
		(start 79.920084 -246.914416)
		(end 65.554606 -261.280148)
		(width 0.127)
		(layer "In2.Cu")
		(net "T5_BLAD2_TXD")
	)
	(segment
		(start 84.472526 -231.87533)
		(end 79.920084 -236.427772)
		(width 0.127)
		(layer "In2.Cu")
		(net "T5_BLAD2_TXD")
	)
	(segment
		(start 16.670528 -262.89762)
		(end 10.907776 -257.134868)
		(width 0.127)
		(layer "In2.Cu")
		(net "T5_BLAD2_TXD")
	)
	(segment
		(start 47.146718 -262.89762)
		(end 16.670528 -262.89762)
		(width 0.127)
		(layer "In2.Cu")
		(net "T5_BLAD2_TXD")
	)
	(via
		(at 83.651344 -193.724022)
		(size 0.508)
		(drill 0.254)
		(layers "F.Cu" "B.Cu")
		(net "T5_BLAD4_TXD")
	)
	(segment
		(start 90.720164 -182.389018)
		(end 90.220292 -181.889146)
		(width 0.127)
		(layer "In2.Cu")
		(net "T5_BLAD4_TXD")
	)
	(segment
		(start 90.720164 -184.07507)
		(end 90.720164 -182.389018)
		(width 0.127)
		(layer "In2.Cu")
		(net "T5_BLAD4_TXD")
	)
	(segment
		(start 43.158156 -261.153402)
		(end 42.671746 -261.639812)
		(width 0.127)
		(layer "In2.Cu")
		(net "T5_BLAD4_TXD")
	)
	(segment
		(start 45.904658 -261.153402)
		(end 43.158156 -261.153402)
		(width 0.127)
		(layer "In2.Cu")
		(net "T5_BLAD4_TXD")
	)
	(segment
		(start 83.651344 -201.235564)
		(end 84.705444 -202.289664)
		(width 0.127)
		(layer "In2.Cu")
		(net "T5_BLAD4_TXD")
	)
	(segment
		(start 85.623146 -181.889146)
		(end 83.651344 -183.860948)
		(width 0.127)
		(layer "In2.Cu")
		(net "T5_BLAD4_TXD")
	)
	(segment
		(start 90.220292 -181.889146)
		(end 85.623146 -181.889146)
		(width 0.127)
		(layer "In2.Cu")
		(net "T5_BLAD4_TXD")
	)
	(segment
		(start 83.651344 -193.724022)
		(end 83.651344 -201.235564)
		(width 0.127)
		(layer "In2.Cu")
		(net "T5_BLAD4_TXD")
	)
	(segment
		(start 42.671746 -261.639812)
		(end 17.05991 -261.639812)
		(width 0.127)
		(layer "In2.Cu")
		(net "T5_BLAD4_TXD")
	)
	(segment
		(start 78.772258 -235.951776)
		(end 78.772258 -246.43842)
		(width 0.127)
		(layer "In2.Cu")
		(net "T5_BLAD4_TXD")
	)
	(segment
		(start 7.618984 -250.704096)
		(end 7.618984 -248.840752)
		(width 0.127)
		(layer "In2.Cu")
		(net "T5_BLAD4_TXD")
	)
	(segment
		(start 65.40373 -259.807202)
		(end 65.107058 -260.103874)
		(width 0.127)
		(layer "In2.Cu")
		(net "T5_BLAD4_TXD")
	)
	(segment
		(start 46.954186 -260.103874)
		(end 45.904658 -261.153402)
		(width 0.127)
		(layer "In2.Cu")
		(net "T5_BLAD4_TXD")
	)
	(segment
		(start 83.383374 -231.34066)
		(end 78.772258 -235.951776)
		(width 0.127)
		(layer "In2.Cu")
		(net "T5_BLAD4_TXD")
	)
	(segment
		(start 84.705444 -202.289664)
		(end 84.705444 -215.22309)
		(width 0.127)
		(layer "In2.Cu")
		(net "T5_BLAD4_TXD")
	)
	(segment
		(start 12.2047 -256.784602)
		(end 12.2047 -255.289812)
		(width 0.127)
		(layer "In2.Cu")
		(net "T5_BLAD4_TXD")
	)
	(segment
		(start 83.383374 -216.54516)
		(end 83.383374 -231.34066)
		(width 0.127)
		(layer "In2.Cu")
		(net "T5_BLAD4_TXD")
	)
	(segment
		(start 12.2047 -255.289812)
		(end 7.618984 -250.704096)
		(width 0.127)
		(layer "In2.Cu")
		(net "T5_BLAD4_TXD")
	)
	(segment
		(start 83.651344 -183.860948)
		(end 83.651344 -193.724022)
		(width 0.127)
		(layer "In2.Cu")
		(net "T5_BLAD4_TXD")
	)
	(segment
		(start 78.772258 -246.43842)
		(end 65.40373 -259.807202)
		(width 0.127)
		(layer "In2.Cu")
		(net "T5_BLAD4_TXD")
	)
	(segment
		(start 84.705444 -215.22309)
		(end 83.383374 -216.54516)
		(width 0.127)
		(layer "In2.Cu")
		(net "T5_BLAD4_TXD")
	)
	(segment
		(start 7.618984 -248.840752)
		(end 6.448806 -247.670574)
		(width 0.127)
		(layer "In2.Cu")
		(net "T5_BLAD4_TXD")
	)
	(segment
		(start 65.107058 -260.103874)
		(end 46.954186 -260.103874)
		(width 0.127)
		(layer "In2.Cu")
		(net "T5_BLAD4_TXD")
	)
	(segment
		(start 17.05991 -261.639812)
		(end 12.2047 -256.784602)
		(width 0.127)
		(layer "In2.Cu")
		(net "T5_BLAD4_TXD")
	)
	(via
		(at 84.218272 -191.253618)
		(size 0.508)
		(drill 0.254)
		(layers "F.Cu" "B.Cu")
		(net "T5_BLAD3_RXD")
	)
	(segment
		(start 17.021302 -262.068564)
		(end 11.775948 -256.82321)
		(width 0.127)
		(layer "In2.Cu")
		(net "T5_BLAD3_RXD")
	)
	(segment
		(start 84.218272 -183.865012)
		(end 85.278214 -182.80507)
		(width 0.127)
		(layer "In2.Cu")
		(net "T5_BLAD3_RXD")
	)
	(segment
		(start 8.784336 -252.670564)
		(end 8.448802 -252.670564)
		(width 0.127)
		(layer "In2.Cu")
		(net "T5_BLAD3_RXD")
	)
	(segment
		(start 85.113876 -202.03033)
		(end 85.113876 -215.314784)
		(width 0.127)
		(layer "In2.Cu")
		(net "T5_BLAD3_RXD")
	)
	(segment
		(start 84.218272 -191.253618)
		(end 84.218272 -201.134726)
		(width 0.127)
		(layer "In2.Cu")
		(net "T5_BLAD3_RXD")
	)
	(segment
		(start 85.278214 -182.80507)
		(end 86.910164 -182.80507)
		(width 0.127)
		(layer "In2.Cu")
		(net "T5_BLAD3_RXD")
	)
	(segment
		(start 11.775948 -256.82321)
		(end 11.775948 -255.662176)
		(width 0.127)
		(layer "In2.Cu")
		(net "T5_BLAD3_RXD")
	)
	(segment
		(start 83.753452 -231.577134)
		(end 79.20101 -236.129576)
		(width 0.127)
		(layer "In2.Cu")
		(net "T5_BLAD3_RXD")
	)
	(segment
		(start 42.792904 -262.068564)
		(end 17.021302 -262.068564)
		(width 0.127)
		(layer "In2.Cu")
		(net "T5_BLAD3_RXD")
	)
	(segment
		(start 85.113876 -215.314784)
		(end 83.753452 -216.675208)
		(width 0.127)
		(layer "In2.Cu")
		(net "T5_BLAD3_RXD")
	)
	(segment
		(start 79.20101 -246.61622)
		(end 65.356994 -260.460236)
		(width 0.127)
		(layer "In2.Cu")
		(net "T5_BLAD3_RXD")
	)
	(segment
		(start 79.20101 -236.129576)
		(end 79.20101 -246.61622)
		(width 0.127)
		(layer "In2.Cu")
		(net "T5_BLAD3_RXD")
	)
	(segment
		(start 83.753452 -216.675208)
		(end 83.753452 -231.577134)
		(width 0.127)
		(layer "In2.Cu")
		(net "T5_BLAD3_RXD")
	)
	(segment
		(start 11.775948 -255.662176)
		(end 8.784336 -252.670564)
		(width 0.127)
		(layer "In2.Cu")
		(net "T5_BLAD3_RXD")
	)
	(segment
		(start 43.307762 -261.553706)
		(end 42.792904 -262.068564)
		(width 0.127)
		(layer "In2.Cu")
		(net "T5_BLAD3_RXD")
	)
	(segment
		(start 84.218272 -201.134726)
		(end 85.113876 -202.03033)
		(width 0.127)
		(layer "In2.Cu")
		(net "T5_BLAD3_RXD")
	)
	(segment
		(start 47.331884 -260.460236)
		(end 46.238414 -261.553706)
		(width 0.127)
		(layer "In2.Cu")
		(net "T5_BLAD3_RXD")
	)
	(segment
		(start 46.238414 -261.553706)
		(end 43.307762 -261.553706)
		(width 0.127)
		(layer "In2.Cu")
		(net "T5_BLAD3_RXD")
	)
	(segment
		(start 84.218272 -191.253618)
		(end 84.218272 -183.865012)
		(width 0.127)
		(layer "In2.Cu")
		(net "T5_BLAD3_RXD")
	)
	(segment
		(start 65.356994 -260.460236)
		(end 47.331884 -260.460236)
		(width 0.127)
		(layer "In2.Cu")
		(net "T5_BLAD3_RXD")
	)
	(via
		(at 87.403686 -190.959486)
		(size 0.508)
		(drill 0.254)
		(layers "F.Cu" "B.Cu")
		(net "T5_BLAD2_RXD")
	)
	(segment
		(start 90.468704 -187.894468)
		(end 90.536522 -187.894468)
		(width 0.127)
		(layer "In2.Cu")
		(net "T5_BLAD2_RXD")
	)
	(segment
		(start 64.08293 -263.249156)
		(end 80.27162 -247.060212)
		(width 0.127)
		(layer "In2.Cu")
		(net "T5_BLAD2_RXD")
	)
	(segment
		(start 16.169894 -263.249156)
		(end 64.08293 -263.249156)
		(width 0.127)
		(layer "In2.Cu")
		(net "T5_BLAD2_RXD")
	)
	(segment
		(start 86.164674 -215.89492)
		(end 86.164674 -192.198498)
		(width 0.127)
		(layer "In2.Cu")
		(net "T5_BLAD2_RXD")
	)
	(segment
		(start 86.164674 -192.198498)
		(end 87.403686 -190.959486)
		(width 0.127)
		(layer "In2.Cu")
		(net "T5_BLAD2_RXD")
	)
	(segment
		(start 90.536522 -187.894468)
		(end 91.990164 -186.440826)
		(width 0.127)
		(layer "In2.Cu")
		(net "T5_BLAD2_RXD")
	)
	(segment
		(start 84.824062 -232.021126)
		(end 84.824062 -217.235532)
		(width 0.127)
		(layer "In2.Cu")
		(net "T5_BLAD2_RXD")
	)
	(segment
		(start 87.403686 -190.959486)
		(end 90.468704 -187.894468)
		(width 0.127)
		(layer "In2.Cu")
		(net "T5_BLAD2_RXD")
	)
	(segment
		(start 84.824062 -217.235532)
		(end 86.164674 -215.89492)
		(width 0.127)
		(layer "In2.Cu")
		(net "T5_BLAD2_RXD")
	)
	(segment
		(start 80.27162 -247.060212)
		(end 80.27162 -236.573568)
		(width 0.127)
		(layer "In2.Cu")
		(net "T5_BLAD2_RXD")
	)
	(segment
		(start 10.296906 -257.376168)
		(end 16.169894 -263.249156)
		(width 0.127)
		(layer "In2.Cu")
		(net "T5_BLAD2_RXD")
	)
	(segment
		(start 8.448802 -254.67056)
		(end 10.296906 -256.518664)
		(width 0.127)
		(layer "In2.Cu")
		(net "T5_BLAD2_RXD")
	)
	(segment
		(start 91.990164 -186.440826)
		(end 91.990164 -185.34507)
		(width 0.127)
		(layer "In2.Cu")
		(net "T5_BLAD2_RXD")
	)
	(segment
		(start 10.296906 -256.518664)
		(end 10.296906 -257.376168)
		(width 0.127)
		(layer "In2.Cu")
		(net "T5_BLAD2_RXD")
	)
	(segment
		(start 80.27162 -236.573568)
		(end 84.824062 -232.021126)
		(width 0.127)
		(layer "In2.Cu")
		(net "T5_BLAD2_RXD")
	)
	(via
		(at 92.094558 -191.206882)
		(size 0.508)
		(drill 0.254)
		(layers "F.Cu" "B.Cu")
		(net "T5_BLAD1_TXD")
	)
	(segment
		(start 91.390978 -190.503302)
		(end 88.69045 -190.503302)
		(width 0.127)
		(layer "In5.Cu")
		(net "T5_BLAD1_TXD")
	)
	(segment
		(start 85.640164 -187.453016)
		(end 85.640164 -186.61507)
		(width 0.127)
		(layer "In5.Cu")
		(net "T5_BLAD1_TXD")
	)
	(segment
		(start 92.094558 -191.206882)
		(end 91.390978 -190.503302)
		(width 0.127)
		(layer "In5.Cu")
		(net "T5_BLAD1_TXD")
	)
	(segment
		(start 88.69045 -190.503302)
		(end 85.640164 -187.453016)
		(width 0.127)
		(layer "In5.Cu")
		(net "T5_BLAD1_TXD")
	)
	(segment
		(start 80.208628 -247.968262)
		(end 93.248734 -247.968262)
		(width 0.127)
		(layer "In5.Cu")
		(net "T5_BLAD1_TXD")
	)
	(segment
		(start 99.489514 -241.727482)
		(end 99.489514 -198.601838)
		(width 0.127)
		(layer "In5.Cu")
		(net "T5_BLAD1_TXD")
	)
	(segment
		(start 8.448802 -256.670556)
		(end 16.557244 -264.778998)
		(width 0.127)
		(layer "In5.Cu")
		(net "T5_BLAD1_TXD")
	)
	(segment
		(start 63.397892 -264.778998)
		(end 80.208628 -247.968262)
		(width 0.127)
		(layer "In5.Cu")
		(net "T5_BLAD1_TXD")
	)
	(segment
		(start 16.557244 -264.778998)
		(end 63.397892 -264.778998)
		(width 0.127)
		(layer "In5.Cu")
		(net "T5_BLAD1_TXD")
	)
	(segment
		(start 93.248734 -247.968262)
		(end 99.489514 -241.727482)
		(width 0.127)
		(layer "In5.Cu")
		(net "T5_BLAD1_TXD")
	)
	(segment
		(start 99.489514 -198.601838)
		(end 92.094558 -191.206882)
		(width 0.127)
		(layer "In5.Cu")
		(net "T5_BLAD1_TXD")
	)
	(via
		(at 81.37652 -146.428714)
		(size 0.508)
		(drill 0.254)
		(layers "F.Cu" "B.Cu")
		(net "T4_BLAD1_TXD")
	)
	(segment
		(start 2.86131 -242.670584)
		(end 3.13309 -242.398804)
		(width 0.127)
		(layer "In2.Cu")
		(net "T4_BLAD1_TXD")
	)
	(segment
		(start 8.124952 -243.513102)
		(end 13.522706 -243.513102)
		(width 0.127)
		(layer "In2.Cu")
		(net "T4_BLAD1_TXD")
	)
	(segment
		(start 21.37918 -235.656628)
		(end 21.37918 -234.650026)
		(width 0.127)
		(layer "In2.Cu")
		(net "T4_BLAD1_TXD")
	)
	(segment
		(start 26.311606 -195.545202)
		(end 23.082504 -192.3161)
		(width 0.127)
		(layer "In2.Cu")
		(net "T4_BLAD1_TXD")
	)
	(segment
		(start 79.631794 -158.172404)
		(end 79.631794 -148.17344)
		(width 0.127)
		(layer "In2.Cu")
		(net "T4_BLAD1_TXD")
	)
	(segment
		(start 7.010654 -242.398804)
		(end 8.124952 -243.513102)
		(width 0.127)
		(layer "In2.Cu")
		(net "T4_BLAD1_TXD")
	)
	(segment
		(start 23.082504 -192.3161)
		(end 23.082504 -182.741316)
		(width 0.127)
		(layer "In2.Cu")
		(net "T4_BLAD1_TXD")
	)
	(segment
		(start 81.37652 -146.428714)
		(end 85.640164 -142.16507)
		(width 0.127)
		(layer "In2.Cu")
		(net "T4_BLAD1_TXD")
	)
	(segment
		(start 59.964574 -177.839624)
		(end 79.631794 -158.172404)
		(width 0.127)
		(layer "In2.Cu")
		(net "T4_BLAD1_TXD")
	)
	(segment
		(start 27.984196 -177.839624)
		(end 59.964574 -177.839624)
		(width 0.127)
		(layer "In2.Cu")
		(net "T4_BLAD1_TXD")
	)
	(segment
		(start 23.082504 -182.741316)
		(end 27.984196 -177.839624)
		(width 0.127)
		(layer "In2.Cu")
		(net "T4_BLAD1_TXD")
	)
	(segment
		(start 79.631794 -148.17344)
		(end 81.37652 -146.428714)
		(width 0.127)
		(layer "In2.Cu")
		(net "T4_BLAD1_TXD")
	)
	(segment
		(start 1.948942 -242.670584)
		(end 2.86131 -242.670584)
		(width 0.127)
		(layer "In2.Cu")
		(net "T4_BLAD1_TXD")
	)
	(segment
		(start 13.522706 -243.513102)
		(end 21.37918 -235.656628)
		(width 0.127)
		(layer "In2.Cu")
		(net "T4_BLAD1_TXD")
	)
	(segment
		(start 3.13309 -242.398804)
		(end 7.010654 -242.398804)
		(width 0.127)
		(layer "In2.Cu")
		(net "T4_BLAD1_TXD")
	)
	(segment
		(start 26.311606 -229.7176)
		(end 26.311606 -195.545202)
		(width 0.127)
		(layer "In2.Cu")
		(net "T4_BLAD1_TXD")
	)
	(segment
		(start 21.37918 -234.650026)
		(end 26.311606 -229.7176)
		(width 0.127)
		(layer "In2.Cu")
		(net "T4_BLAD1_TXD")
	)
	(via
		(at 87.0966 -147.352004)
		(size 0.508)
		(drill 0.254)
		(layers "F.Cu" "B.Cu")
		(net "T4_BLAD2_RXD")
	)
	(segment
		(start 23.088346 -181.651656)
		(end 27.79649 -176.943512)
		(width 0.127)
		(layer "In5.Cu")
		(net "T4_BLAD2_RXD")
	)
	(segment
		(start 5.1308 -240.488724)
		(end 5.1308 -239.87887)
		(width 0.127)
		(layer "In5.Cu")
		(net "T4_BLAD2_RXD")
	)
	(segment
		(start 91.990164 -140.89507)
		(end 91.990164 -142.45844)
		(width 0.127)
		(layer "In5.Cu")
		(net "T4_BLAD2_RXD")
	)
	(segment
		(start 91.990164 -142.45844)
		(end 87.0966 -147.352004)
		(width 0.127)
		(layer "In5.Cu")
		(net "T4_BLAD2_RXD")
	)
	(segment
		(start 27.79649 -176.943512)
		(end 61.502798 -176.943512)
		(width 0.127)
		(layer "In5.Cu")
		(net "T4_BLAD2_RXD")
	)
	(segment
		(start 20.424394 -234.841034)
		(end 22.460458 -232.80497)
		(width 0.127)
		(layer "In5.Cu")
		(net "T4_BLAD2_RXD")
	)
	(segment
		(start 3.948938 -241.670586)
		(end 5.1308 -240.488724)
		(width 0.127)
		(layer "In5.Cu")
		(net "T4_BLAD2_RXD")
	)
	(segment
		(start 6.110986 -238.898684)
		(end 7.01167 -238.898684)
		(width 0.127)
		(layer "In5.Cu")
		(net "T4_BLAD2_RXD")
	)
	(segment
		(start 5.1308 -239.87887)
		(end 6.110986 -238.898684)
		(width 0.127)
		(layer "In5.Cu")
		(net "T4_BLAD2_RXD")
	)
	(segment
		(start 26.100024 -217.43797)
		(end 26.100024 -201.12355)
		(width 0.127)
		(layer "In5.Cu")
		(net "T4_BLAD2_RXD")
	)
	(segment
		(start 20.424394 -236.193076)
		(end 20.424394 -234.841034)
		(width 0.127)
		(layer "In5.Cu")
		(net "T4_BLAD2_RXD")
	)
	(segment
		(start 7.01167 -238.898684)
		(end 7.981442 -237.928912)
		(width 0.127)
		(layer "In5.Cu")
		(net "T4_BLAD2_RXD")
	)
	(segment
		(start 61.502798 -176.943512)
		(end 86.144354 -152.301956)
		(width 0.127)
		(layer "In5.Cu")
		(net "T4_BLAD2_RXD")
	)
	(segment
		(start 22.460458 -221.077536)
		(end 26.100024 -217.43797)
		(width 0.127)
		(layer "In5.Cu")
		(net "T4_BLAD2_RXD")
	)
	(segment
		(start 23.088346 -198.111872)
		(end 23.088346 -181.651656)
		(width 0.127)
		(layer "In5.Cu")
		(net "T4_BLAD2_RXD")
	)
	(segment
		(start 86.144354 -148.30425)
		(end 87.0966 -147.352004)
		(width 0.127)
		(layer "In5.Cu")
		(net "T4_BLAD2_RXD")
	)
	(segment
		(start 26.100024 -201.12355)
		(end 23.088346 -198.111872)
		(width 0.127)
		(layer "In5.Cu")
		(net "T4_BLAD2_RXD")
	)
	(segment
		(start 22.460458 -232.80497)
		(end 22.460458 -221.077536)
		(width 0.127)
		(layer "In5.Cu")
		(net "T4_BLAD2_RXD")
	)
	(segment
		(start 86.144354 -152.301956)
		(end 86.144354 -148.30425)
		(width 0.127)
		(layer "In5.Cu")
		(net "T4_BLAD2_RXD")
	)
	(segment
		(start 7.981442 -237.928912)
		(end 18.688558 -237.928912)
		(width 0.127)
		(layer "In5.Cu")
		(net "T4_BLAD2_RXD")
	)
	(segment
		(start 18.688558 -237.928912)
		(end 20.424394 -236.193076)
		(width 0.127)
		(layer "In5.Cu")
		(net "T4_BLAD2_RXD")
	)
	(via
		(at 81.722468 -152.156414)
		(size 0.508)
		(drill 0.254)
		(layers "F.Cu" "B.Cu")
		(net "T4_BLAD1_EN")
	)
	(segment
		(start 30.599126 -179.248562)
		(end 60.548774 -179.248562)
		(width 0.127)
		(layer "In2.Cu")
		(net "T4_BLAD1_EN")
	)
	(segment
		(start 81.722468 -158.074868)
		(end 81.722468 -152.156414)
		(width 0.127)
		(layer "In2.Cu")
		(net "T4_BLAD1_EN")
	)
	(segment
		(start 7.96671 -247.420892)
		(end 11.801602 -247.420892)
		(width 0.127)
		(layer "In2.Cu")
		(net "T4_BLAD1_EN")
	)
	(segment
		(start 4.224274 -246.39524)
		(end 6.941058 -246.39524)
		(width 0.127)
		(layer "In2.Cu")
		(net "T4_BLAD1_EN")
	)
	(segment
		(start 27.736038 -188.087508)
		(end 28.469082 -187.354464)
		(width 0.127)
		(layer "In2.Cu")
		(net "T4_BLAD1_EN")
	)
	(segment
		(start 88.180164 -142.710408)
		(end 81.722468 -149.168104)
		(width 0.127)
		(layer "In2.Cu")
		(net "T4_BLAD1_EN")
	)
	(segment
		(start 11.801602 -247.420892)
		(end 23.157688 -236.064806)
		(width 0.127)
		(layer "In2.Cu")
		(net "T4_BLAD1_EN")
	)
	(segment
		(start 1.948942 -248.670572)
		(end 4.224274 -246.39524)
		(width 0.127)
		(layer "In2.Cu")
		(net "T4_BLAD1_EN")
	)
	(segment
		(start 81.722468 -149.168104)
		(end 81.722468 -152.156414)
		(width 0.127)
		(layer "In2.Cu")
		(net "T4_BLAD1_EN")
	)
	(segment
		(start 28.469082 -181.378606)
		(end 30.599126 -179.248562)
		(width 0.127)
		(layer "In2.Cu")
		(net "T4_BLAD1_EN")
	)
	(segment
		(start 23.157688 -236.064806)
		(end 23.157688 -234.816904)
		(width 0.127)
		(layer "In2.Cu")
		(net "T4_BLAD1_EN")
	)
	(segment
		(start 23.157688 -234.816904)
		(end 27.736038 -230.238554)
		(width 0.127)
		(layer "In2.Cu")
		(net "T4_BLAD1_EN")
	)
	(segment
		(start 88.180164 -142.16507)
		(end 88.180164 -142.710408)
		(width 0.127)
		(layer "In2.Cu")
		(net "T4_BLAD1_EN")
	)
	(segment
		(start 60.548774 -179.248562)
		(end 81.722468 -158.074868)
		(width 0.127)
		(layer "In2.Cu")
		(net "T4_BLAD1_EN")
	)
	(segment
		(start 6.941058 -246.39524)
		(end 7.96671 -247.420892)
		(width 0.127)
		(layer "In2.Cu")
		(net "T4_BLAD1_EN")
	)
	(segment
		(start 28.469082 -187.354464)
		(end 28.469082 -181.378606)
		(width 0.127)
		(layer "In2.Cu")
		(net "T4_BLAD1_EN")
	)
	(segment
		(start 27.736038 -230.238554)
		(end 27.736038 -188.087508)
		(width 0.127)
		(layer "In2.Cu")
		(net "T4_BLAD1_EN")
	)
	(via
		(at 81.242408 -150.70582)
		(size 0.508)
		(drill 0.254)
		(layers "F.Cu" "B.Cu")
		(net "T4_BLAD4_EN")
	)
	(segment
		(start 3.948938 -245.670578)
		(end 4.78663 -244.832886)
		(width 0.127)
		(layer "In2.Cu")
		(net "T4_BLAD4_EN")
	)
	(segment
		(start 26.39314 -190.504826)
		(end 26.39314 -182.6895)
		(width 0.127)
		(layer "In2.Cu")
		(net "T4_BLAD4_EN")
	)
	(segment
		(start 22.79269 -234.699302)
		(end 27.339798 -230.152194)
		(width 0.127)
		(layer "In2.Cu")
		(net "T4_BLAD4_EN")
	)
	(segment
		(start 27.339798 -191.451484)
		(end 26.39314 -190.504826)
		(width 0.127)
		(layer "In2.Cu")
		(net "T4_BLAD4_EN")
	)
	(segment
		(start 89.450164 -139.62888)
		(end 89.450164 -138.35507)
		(width 0.127)
		(layer "In2.Cu")
		(net "T4_BLAD4_EN")
	)
	(segment
		(start 81.242408 -150.70582)
		(end 81.242408 -148.967952)
		(width 0.127)
		(layer "In2.Cu")
		(net "T4_BLAD4_EN")
	)
	(segment
		(start 27.339798 -230.152194)
		(end 27.339798 -191.451484)
		(width 0.127)
		(layer "In2.Cu")
		(net "T4_BLAD4_EN")
	)
	(segment
		(start 4.78663 -244.832886)
		(end 6.892544 -244.832886)
		(width 0.127)
		(layer "In2.Cu")
		(net "T4_BLAD4_EN")
	)
	(segment
		(start 81.242408 -148.967952)
		(end 87.268812 -142.941548)
		(width 0.127)
		(layer "In2.Cu")
		(net "T4_BLAD4_EN")
	)
	(segment
		(start 7.855966 -245.796308)
		(end 12.75334 -245.796308)
		(width 0.127)
		(layer "In2.Cu")
		(net "T4_BLAD4_EN")
	)
	(segment
		(start 22.79269 -235.756958)
		(end 22.79269 -234.699302)
		(width 0.127)
		(layer "In2.Cu")
		(net "T4_BLAD4_EN")
	)
	(segment
		(start 60.39739 -178.883564)
		(end 81.242408 -158.038546)
		(width 0.127)
		(layer "In2.Cu")
		(net "T4_BLAD4_EN")
	)
	(segment
		(start 81.242408 -158.038546)
		(end 81.242408 -150.70582)
		(width 0.127)
		(layer "In2.Cu")
		(net "T4_BLAD4_EN")
	)
	(segment
		(start 12.75334 -245.796308)
		(end 22.79269 -235.756958)
		(width 0.127)
		(layer "In2.Cu")
		(net "T4_BLAD4_EN")
	)
	(segment
		(start 26.39314 -182.6895)
		(end 30.199076 -178.883564)
		(width 0.127)
		(layer "In2.Cu")
		(net "T4_BLAD4_EN")
	)
	(segment
		(start 30.199076 -178.883564)
		(end 60.39739 -178.883564)
		(width 0.127)
		(layer "In2.Cu")
		(net "T4_BLAD4_EN")
	)
	(segment
		(start 87.268812 -141.810232)
		(end 89.450164 -139.62888)
		(width 0.127)
		(layer "In2.Cu")
		(net "T4_BLAD4_EN")
	)
	(segment
		(start 87.268812 -142.941548)
		(end 87.268812 -141.810232)
		(width 0.127)
		(layer "In2.Cu")
		(net "T4_BLAD4_EN")
	)
	(segment
		(start 6.892544 -244.832886)
		(end 7.855966 -245.796308)
		(width 0.127)
		(layer "In2.Cu")
		(net "T4_BLAD4_EN")
	)
	(segment
		(start 39.535862 -464.369912)
		(end 39.536624 -464.36915)
		(width 0.508)
		(layer "F.Cu")
		(net "PSU6_REMOTE_P")
	)
	(segment
		(start 35.53968 -464.369912)
		(end 39.535862 -464.369912)
		(width 0.508)
		(layer "F.Cu")
		(net "PSU6_REMOTE_P")
	)
	(via
		(at 82.232754 -149.64537)
		(size 0.508)
		(drill 0.254)
		(layers "F.Cu" "B.Cu")
		(net "T4_BLAD2_EN")
	)
	(segment
		(start 7.748778 -247.837706)
		(end 12.1285 -247.837706)
		(width 0.127)
		(layer "In2.Cu")
		(net "T4_BLAD2_EN")
	)
	(segment
		(start 6.76529 -246.854218)
		(end 7.748778 -247.837706)
		(width 0.127)
		(layer "In2.Cu")
		(net "T4_BLAD2_EN")
	)
	(segment
		(start 28.143708 -231.822498)
		(end 28.143708 -188.439298)
		(width 0.127)
		(layer "In2.Cu")
		(net "T4_BLAD2_EN")
	)
	(segment
		(start 4.765294 -246.854218)
		(end 6.76529 -246.854218)
		(width 0.127)
		(layer "In2.Cu")
		(net "T4_BLAD2_EN")
	)
	(segment
		(start 89.450164 -141.53896)
		(end 89.02573 -141.963394)
		(width 0.127)
		(layer "In2.Cu")
		(net "T4_BLAD2_EN")
	)
	(segment
		(start 89.02573 -142.41526)
		(end 82.232754 -149.208236)
		(width 0.127)
		(layer "In2.Cu")
		(net "T4_BLAD2_EN")
	)
	(segment
		(start 82.232754 -158.059628)
		(end 82.232754 -149.64537)
		(width 0.127)
		(layer "In2.Cu")
		(net "T4_BLAD2_EN")
	)
	(segment
		(start 28.850336 -187.73267)
		(end 28.850336 -181.521354)
		(width 0.127)
		(layer "In2.Cu")
		(net "T4_BLAD2_EN")
	)
	(segment
		(start 82.232754 -149.208236)
		(end 82.232754 -149.64537)
		(width 0.127)
		(layer "In2.Cu")
		(net "T4_BLAD2_EN")
	)
	(segment
		(start 30.773116 -179.598574)
		(end 60.693808 -179.598574)
		(width 0.127)
		(layer "In2.Cu")
		(net "T4_BLAD2_EN")
	)
	(segment
		(start 60.693808 -179.598574)
		(end 82.232754 -158.059628)
		(width 0.127)
		(layer "In2.Cu")
		(net "T4_BLAD2_EN")
	)
	(segment
		(start 28.850336 -181.521354)
		(end 30.773116 -179.598574)
		(width 0.127)
		(layer "In2.Cu")
		(net "T4_BLAD2_EN")
	)
	(segment
		(start 3.948938 -247.670574)
		(end 4.765294 -246.854218)
		(width 0.127)
		(layer "In2.Cu")
		(net "T4_BLAD2_EN")
	)
	(segment
		(start 12.1285 -247.837706)
		(end 28.143708 -231.822498)
		(width 0.127)
		(layer "In2.Cu")
		(net "T4_BLAD2_EN")
	)
	(segment
		(start 28.143708 -188.439298)
		(end 28.850336 -187.73267)
		(width 0.127)
		(layer "In2.Cu")
		(net "T4_BLAD2_EN")
	)
	(segment
		(start 89.02573 -141.963394)
		(end 89.02573 -142.41526)
		(width 0.127)
		(layer "In2.Cu")
		(net "T4_BLAD2_EN")
	)
	(segment
		(start 89.450164 -140.89507)
		(end 89.450164 -141.53896)
		(width 0.127)
		(layer "In2.Cu")
		(net "T4_BLAD2_EN")
	)
	(via
		(at 84.7725 -151.212804)
		(size 0.508)
		(drill 0.254)
		(layers "F.Cu" "B.Cu")
		(net "T4_BLAD3_TXD")
	)
	(segment
		(start 18.144998 -235.560108)
		(end 21.433536 -232.27157)
		(width 0.127)
		(layer "In5.Cu")
		(net "T4_BLAD3_TXD")
	)
	(segment
		(start 3.948938 -237.670594)
		(end 3.951732 -237.6678)
		(width 0.127)
		(layer "In5.Cu")
		(net "T4_BLAD3_TXD")
	)
	(segment
		(start 3.951732 -237.6678)
		(end 4.923536 -237.6678)
		(width 0.127)
		(layer "In5.Cu")
		(net "T4_BLAD3_TXD")
	)
	(segment
		(start 7.87527 -235.560108)
		(end 18.144998 -235.560108)
		(width 0.127)
		(layer "In5.Cu")
		(net "T4_BLAD3_TXD")
	)
	(segment
		(start 25.011634 -201.58456)
		(end 21.976842 -198.549768)
		(width 0.127)
		(layer "In5.Cu")
		(net "T4_BLAD3_TXD")
	)
	(segment
		(start 4.923536 -237.6678)
		(end 6.018276 -236.57306)
		(width 0.127)
		(layer "In5.Cu")
		(net "T4_BLAD3_TXD")
	)
	(segment
		(start 84.7725 -152.131268)
		(end 84.7725 -151.212804)
		(width 0.127)
		(layer "In5.Cu")
		(net "T4_BLAD3_TXD")
	)
	(segment
		(start 25.011634 -216.717626)
		(end 25.011634 -201.58456)
		(width 0.127)
		(layer "In5.Cu")
		(net "T4_BLAD3_TXD")
	)
	(segment
		(start 21.976842 -198.549768)
		(end 21.976842 -180.190648)
		(width 0.127)
		(layer "In5.Cu")
		(net "T4_BLAD3_TXD")
	)
	(segment
		(start 21.433536 -232.27157)
		(end 21.433536 -220.295724)
		(width 0.127)
		(layer "In5.Cu")
		(net "T4_BLAD3_TXD")
	)
	(segment
		(start 6.862318 -236.57306)
		(end 7.87527 -235.560108)
		(width 0.127)
		(layer "In5.Cu")
		(net "T4_BLAD3_TXD")
	)
	(segment
		(start 21.433536 -220.295724)
		(end 25.011634 -216.717626)
		(width 0.127)
		(layer "In5.Cu")
		(net "T4_BLAD3_TXD")
	)
	(segment
		(start 21.976842 -180.190648)
		(end 26.388568 -175.778922)
		(width 0.127)
		(layer "In5.Cu")
		(net "T4_BLAD3_TXD")
	)
	(segment
		(start 84.7725 -140.492734)
		(end 85.640164 -139.62507)
		(width 0.127)
		(layer "In5.Cu")
		(net "T4_BLAD3_TXD")
	)
	(segment
		(start 6.018276 -236.57306)
		(end 6.862318 -236.57306)
		(width 0.127)
		(layer "In5.Cu")
		(net "T4_BLAD3_TXD")
	)
	(segment
		(start 26.388568 -175.778922)
		(end 61.124846 -175.778922)
		(width 0.127)
		(layer "In5.Cu")
		(net "T4_BLAD3_TXD")
	)
	(segment
		(start 84.7725 -151.212804)
		(end 84.7725 -140.492734)
		(width 0.127)
		(layer "In5.Cu")
		(net "T4_BLAD3_TXD")
	)
	(segment
		(start 61.124846 -175.778922)
		(end 84.7725 -152.131268)
		(width 0.127)
		(layer "In5.Cu")
		(net "T4_BLAD3_TXD")
	)
	(via
		(at 85.696298 -148.90242)
		(size 0.508)
		(drill 0.254)
		(layers "F.Cu" "B.Cu")
		(net "T4_BLAD2_TXD")
	)
	(segment
		(start 4.688586 -239.804702)
		(end 5.959602 -238.533686)
		(width 0.127)
		(layer "In5.Cu")
		(net "T4_BLAD2_TXD")
	)
	(segment
		(start 20.059396 -234.68965)
		(end 22.115272 -232.633774)
		(width 0.127)
		(layer "In5.Cu")
		(net "T4_BLAD2_TXD")
	)
	(segment
		(start 22.115272 -220.90634)
		(end 25.735026 -217.286586)
		(width 0.127)
		(layer "In5.Cu")
		(net "T4_BLAD2_TXD")
	)
	(segment
		(start 61.351414 -176.578514)
		(end 85.696298 -152.23363)
		(width 0.127)
		(layer "In5.Cu")
		(net "T4_BLAD2_TXD")
	)
	(segment
		(start 1.951736 -240.667794)
		(end 4.262374 -240.667794)
		(width 0.127)
		(layer "In5.Cu")
		(net "T4_BLAD2_TXD")
	)
	(segment
		(start 22.115272 -232.633774)
		(end 22.115272 -220.90634)
		(width 0.127)
		(layer "In5.Cu")
		(net "T4_BLAD2_TXD")
	)
	(segment
		(start 27.294586 -176.578514)
		(end 61.351414 -176.578514)
		(width 0.127)
		(layer "In5.Cu")
		(net "T4_BLAD2_TXD")
	)
	(segment
		(start 85.696298 -147.864576)
		(end 90.720164 -142.84071)
		(width 0.127)
		(layer "In5.Cu")
		(net "T4_BLAD2_TXD")
	)
	(segment
		(start 7.841996 -237.563914)
		(end 18.537174 -237.563914)
		(width 0.127)
		(layer "In5.Cu")
		(net "T4_BLAD2_TXD")
	)
	(segment
		(start 85.696298 -148.90242)
		(end 85.696298 -147.864576)
		(width 0.127)
		(layer "In5.Cu")
		(net "T4_BLAD2_TXD")
	)
	(segment
		(start 6.872224 -238.533686)
		(end 7.841996 -237.563914)
		(width 0.127)
		(layer "In5.Cu")
		(net "T4_BLAD2_TXD")
	)
	(segment
		(start 18.537174 -237.563914)
		(end 20.059396 -236.041692)
		(width 0.127)
		(layer "In5.Cu")
		(net "T4_BLAD2_TXD")
	)
	(segment
		(start 22.749256 -181.123844)
		(end 27.294586 -176.578514)
		(width 0.127)
		(layer "In5.Cu")
		(net "T4_BLAD2_TXD")
	)
	(segment
		(start 1.948942 -240.670588)
		(end 1.951736 -240.667794)
		(width 0.127)
		(layer "In5.Cu")
		(net "T4_BLAD2_TXD")
	)
	(segment
		(start 25.735026 -217.286586)
		(end 25.735026 -201.23531)
		(width 0.127)
		(layer "In5.Cu")
		(net "T4_BLAD2_TXD")
	)
	(segment
		(start 4.262374 -240.667794)
		(end 4.688586 -240.241582)
		(width 0.127)
		(layer "In5.Cu")
		(net "T4_BLAD2_TXD")
	)
	(segment
		(start 4.688586 -240.241582)
		(end 4.688586 -239.804702)
		(width 0.127)
		(layer "In5.Cu")
		(net "T4_BLAD2_TXD")
	)
	(segment
		(start 22.749256 -198.24954)
		(end 22.749256 -181.123844)
		(width 0.127)
		(layer "In5.Cu")
		(net "T4_BLAD2_TXD")
	)
	(segment
		(start 20.059396 -236.041692)
		(end 20.059396 -234.68965)
		(width 0.127)
		(layer "In5.Cu")
		(net "T4_BLAD2_TXD")
	)
	(segment
		(start 90.720164 -142.84071)
		(end 90.720164 -142.16507)
		(width 0.127)
		(layer "In5.Cu")
		(net "T4_BLAD2_TXD")
	)
	(segment
		(start 5.959602 -238.533686)
		(end 6.872224 -238.533686)
		(width 0.127)
		(layer "In5.Cu")
		(net "T4_BLAD2_TXD")
	)
	(segment
		(start 85.696298 -152.23363)
		(end 85.696298 -148.90242)
		(width 0.127)
		(layer "In5.Cu")
		(net "T4_BLAD2_TXD")
	)
	(segment
		(start 25.735026 -201.23531)
		(end 22.749256 -198.24954)
		(width 0.127)
		(layer "In5.Cu")
		(net "T4_BLAD2_TXD")
	)
	(segment
		(start 39.738808 -458.515212)
		(end 39.738808 -457.408534)
		(width 0.1524)
		(layer "F.Cu")
		(net "PSU6_RETURN")
	)
	(segment
		(start 37.18687 -454.209912)
		(end 35.53968 -454.209912)
		(width 0.1524)
		(layer "F.Cu")
		(net "PSU6_RETURN")
	)
	(segment
		(start 39.738808 -456.76185)
		(end 37.18687 -454.209912)
		(width 0.1524)
		(layer "F.Cu")
		(net "PSU6_RETURN")
	)
	(segment
		(start 39.54526 -459.16596)
		(end 39.54526 -458.70876)
		(width 0.1524)
		(layer "F.Cu")
		(net "PSU6_RETURN")
	)
	(segment
		(start 39.54526 -458.70876)
		(end 39.738808 -458.515212)
		(width 0.1524)
		(layer "F.Cu")
		(net "PSU6_RETURN")
	)
	(segment
		(start 39.738808 -457.408534)
		(end 39.738808 -456.76185)
		(width 0.1524)
		(layer "F.Cu")
		(net "PSU6_RETURN")
	)
	(via
		(at 39.738808 -457.408534)
		(size 0.508)
		(drill 0.254)
		(layers "F.Cu" "B.Cu")
		(net "PSU6_RETURN")
	)
	(via
		(at 84.294218 -149.81174)
		(size 0.508)
		(drill 0.254)
		(layers "F.Cu" "B.Cu")
		(net "T4_BLAD4_RXD")
	)
	(segment
		(start 4.220972 -236.670596)
		(end 6.004814 -234.886754)
		(width 0.127)
		(layer "In5.Cu")
		(net "T4_BLAD4_RXD")
	)
	(segment
		(start 19.327114 -233.777536)
		(end 21.068538 -232.036112)
		(width 0.127)
		(layer "In5.Cu")
		(net "T4_BLAD4_RXD")
	)
	(segment
		(start 1.948942 -236.670596)
		(end 4.220972 -236.670596)
		(width 0.127)
		(layer "In5.Cu")
		(net "T4_BLAD4_RXD")
	)
	(segment
		(start 60.94222 -175.415956)
		(end 84.294218 -152.063958)
		(width 0.127)
		(layer "In5.Cu")
		(net "T4_BLAD4_RXD")
	)
	(segment
		(start 25.993344 -175.415956)
		(end 60.94222 -175.415956)
		(width 0.127)
		(layer "In5.Cu")
		(net "T4_BLAD4_RXD")
	)
	(segment
		(start 6.004814 -234.886754)
		(end 7.219188 -234.886754)
		(width 0.127)
		(layer "In5.Cu")
		(net "T4_BLAD4_RXD")
	)
	(segment
		(start 21.068538 -232.036112)
		(end 21.068538 -220.126306)
		(width 0.127)
		(layer "In5.Cu")
		(net "T4_BLAD4_RXD")
	)
	(segment
		(start 84.294218 -152.063958)
		(end 84.294218 -149.81174)
		(width 0.127)
		(layer "In5.Cu")
		(net "T4_BLAD4_RXD")
	)
	(segment
		(start 24.572468 -201.63028)
		(end 21.237956 -198.295768)
		(width 0.127)
		(layer "In5.Cu")
		(net "T4_BLAD4_RXD")
	)
	(segment
		(start 21.237956 -180.171344)
		(end 25.993344 -175.415956)
		(width 0.127)
		(layer "In5.Cu")
		(net "T4_BLAD4_RXD")
	)
	(segment
		(start 91.990164 -138.35507)
		(end 90.973402 -137.338308)
		(width 0.127)
		(layer "In5.Cu")
		(net "T4_BLAD4_RXD")
	)
	(segment
		(start 7.219188 -234.886754)
		(end 8.328406 -233.777536)
		(width 0.127)
		(layer "In5.Cu")
		(net "T4_BLAD4_RXD")
	)
	(segment
		(start 24.572468 -216.622376)
		(end 24.572468 -201.63028)
		(width 0.127)
		(layer "In5.Cu")
		(net "T4_BLAD4_RXD")
	)
	(segment
		(start 90.973402 -137.338308)
		(end 86.383368 -137.338308)
		(width 0.127)
		(layer "In5.Cu")
		(net "T4_BLAD4_RXD")
	)
	(segment
		(start 84.294218 -139.427458)
		(end 84.294218 -149.81174)
		(width 0.127)
		(layer "In5.Cu")
		(net "T4_BLAD4_RXD")
	)
	(segment
		(start 8.328406 -233.777536)
		(end 19.327114 -233.777536)
		(width 0.127)
		(layer "In5.Cu")
		(net "T4_BLAD4_RXD")
	)
	(segment
		(start 21.068538 -220.126306)
		(end 24.572468 -216.622376)
		(width 0.127)
		(layer "In5.Cu")
		(net "T4_BLAD4_RXD")
	)
	(segment
		(start 86.383368 -137.338308)
		(end 84.294218 -139.427458)
		(width 0.127)
		(layer "In5.Cu")
		(net "T4_BLAD4_RXD")
	)
	(segment
		(start 21.237956 -198.295768)
		(end 21.237956 -180.171344)
		(width 0.127)
		(layer "In5.Cu")
		(net "T4_BLAD4_RXD")
	)
	(via
		(at 80.701896 -149.4155)
		(size 0.508)
		(drill 0.254)
		(layers "F.Cu" "B.Cu")
		(net "T4_BLAD1_RXD")
	)
	(segment
		(start 25.922732 -194.07632)
		(end 27.009598 -195.163186)
		(width 0.127)
		(layer "In2.Cu")
		(net "T4_BLAD1_RXD")
	)
	(segment
		(start 22.334982 -235.739432)
		(end 13.496544 -244.578124)
		(width 0.127)
		(layer "In2.Cu")
		(net "T4_BLAD1_RXD")
	)
	(segment
		(start 13.49629 -244.578124)
		(end 12.70508 -245.369334)
		(width 0.127)
		(layer "In2.Cu")
		(net "T4_BLAD1_RXD")
	)
	(segment
		(start 27.009598 -195.163186)
		(end 27.009598 -229.985316)
		(width 0.127)
		(layer "In2.Cu")
		(net "T4_BLAD1_RXD")
	)
	(segment
		(start 4.735322 -244.456966)
		(end 3.948938 -243.670582)
		(width 0.127)
		(layer "In2.Cu")
		(net "T4_BLAD1_RXD")
	)
	(segment
		(start 86.910164 -142.7099)
		(end 86.910164 -140.89507)
		(width 0.127)
		(layer "In2.Cu")
		(net "T4_BLAD1_RXD")
	)
	(segment
		(start 25.922732 -182.028846)
		(end 25.922732 -194.07632)
		(width 0.127)
		(layer "In2.Cu")
		(net "T4_BLAD1_RXD")
	)
	(segment
		(start 8.076692 -245.369334)
		(end 7.164324 -244.456966)
		(width 0.127)
		(layer "In2.Cu")
		(net "T4_BLAD1_RXD")
	)
	(segment
		(start 7.164324 -244.456966)
		(end 4.735322 -244.456966)
		(width 0.127)
		(layer "In2.Cu")
		(net "T4_BLAD1_RXD")
	)
	(segment
		(start 12.70508 -245.369334)
		(end 8.076692 -245.369334)
		(width 0.127)
		(layer "In2.Cu")
		(net "T4_BLAD1_RXD")
	)
	(segment
		(start 27.009598 -229.985316)
		(end 22.334982 -234.659932)
		(width 0.127)
		(layer "In2.Cu")
		(net "T4_BLAD1_RXD")
	)
	(segment
		(start 80.701896 -149.4155)
		(end 80.701896 -158.07817)
		(width 0.127)
		(layer "In2.Cu")
		(net "T4_BLAD1_RXD")
	)
	(segment
		(start 29.42209 -178.529488)
		(end 25.922732 -182.028846)
		(width 0.127)
		(layer "In2.Cu")
		(net "T4_BLAD1_RXD")
	)
	(segment
		(start 13.496544 -244.578124)
		(end 13.49629 -244.578124)
		(width 0.127)
		(layer "In2.Cu")
		(net "T4_BLAD1_RXD")
	)
	(segment
		(start 80.701896 -158.07817)
		(end 60.250578 -178.529488)
		(width 0.127)
		(layer "In2.Cu")
		(net "T4_BLAD1_RXD")
	)
	(segment
		(start 60.250578 -178.529488)
		(end 29.42209 -178.529488)
		(width 0.127)
		(layer "In2.Cu")
		(net "T4_BLAD1_RXD")
	)
	(segment
		(start 22.334982 -234.659932)
		(end 22.334982 -235.739432)
		(width 0.127)
		(layer "In2.Cu")
		(net "T4_BLAD1_RXD")
	)
	(segment
		(start 80.701896 -148.918168)
		(end 86.910164 -142.7099)
		(width 0.127)
		(layer "In2.Cu")
		(net "T4_BLAD1_RXD")
	)
	(segment
		(start 80.701896 -149.4155)
		(end 80.701896 -148.918168)
		(width 0.127)
		(layer "In2.Cu")
		(net "T4_BLAD1_RXD")
	)
	(via
		(at 83.727544 -148.51761)
		(size 0.508)
		(drill 0.254)
		(layers "F.Cu" "B.Cu")
		(net "T4_BLAD4_TXD")
	)
	(segment
		(start 20.576286 -180.194204)
		(end 25.696672 -175.073818)
		(width 0.127)
		(layer "In5.Cu")
		(net "T4_BLAD4_TXD")
	)
	(segment
		(start 60.800488 -175.073818)
		(end 83.727544 -152.146762)
		(width 0.127)
		(layer "In5.Cu")
		(net "T4_BLAD4_TXD")
	)
	(segment
		(start 92.836492 -138.87831)
		(end 92.836492 -137.977118)
		(width 0.127)
		(layer "In5.Cu")
		(net "T4_BLAD4_TXD")
	)
	(segment
		(start 91.855544 -136.99617)
		(end 86.008972 -136.99617)
		(width 0.127)
		(layer "In5.Cu")
		(net "T4_BLAD4_TXD")
	)
	(segment
		(start 19.185382 -233.435398)
		(end 20.2438 -232.37698)
		(width 0.127)
		(layer "In5.Cu")
		(net "T4_BLAD4_TXD")
	)
	(segment
		(start 25.696672 -175.073818)
		(end 60.800488 -175.073818)
		(width 0.127)
		(layer "In5.Cu")
		(net "T4_BLAD4_TXD")
	)
	(segment
		(start 86.008972 -136.99617)
		(end 83.727544 -139.277598)
		(width 0.127)
		(layer "In5.Cu")
		(net "T4_BLAD4_TXD")
	)
	(segment
		(start 92.089732 -139.62507)
		(end 92.836492 -138.87831)
		(width 0.127)
		(layer "In5.Cu")
		(net "T4_BLAD4_TXD")
	)
	(segment
		(start 5.863082 -234.544616)
		(end 7.008114 -234.544616)
		(width 0.127)
		(layer "In5.Cu")
		(net "T4_BLAD4_TXD")
	)
	(segment
		(start 92.836492 -137.977118)
		(end 91.855544 -136.99617)
		(width 0.127)
		(layer "In5.Cu")
		(net "T4_BLAD4_TXD")
	)
	(segment
		(start 24.23033 -201.901552)
		(end 20.576286 -198.247508)
		(width 0.127)
		(layer "In5.Cu")
		(net "T4_BLAD4_TXD")
	)
	(segment
		(start 7.008114 -234.544616)
		(end 8.117332 -233.435398)
		(width 0.127)
		(layer "In5.Cu")
		(net "T4_BLAD4_TXD")
	)
	(segment
		(start 83.727544 -139.277598)
		(end 83.727544 -148.51761)
		(width 0.127)
		(layer "In5.Cu")
		(net "T4_BLAD4_TXD")
	)
	(segment
		(start 83.727544 -152.146762)
		(end 83.727544 -148.51761)
		(width 0.127)
		(layer "In5.Cu")
		(net "T4_BLAD4_TXD")
	)
	(segment
		(start 20.2438 -232.37698)
		(end 20.2438 -220.467174)
		(width 0.127)
		(layer "In5.Cu")
		(net "T4_BLAD4_TXD")
	)
	(segment
		(start 20.2438 -220.467174)
		(end 24.23033 -216.480644)
		(width 0.127)
		(layer "In5.Cu")
		(net "T4_BLAD4_TXD")
	)
	(segment
		(start 24.23033 -216.480644)
		(end 24.23033 -201.901552)
		(width 0.127)
		(layer "In5.Cu")
		(net "T4_BLAD4_TXD")
	)
	(segment
		(start 8.117332 -233.435398)
		(end 19.185382 -233.435398)
		(width 0.127)
		(layer "In5.Cu")
		(net "T4_BLAD4_TXD")
	)
	(segment
		(start 3.948938 -235.670598)
		(end 4.7371 -235.670598)
		(width 0.127)
		(layer "In5.Cu")
		(net "T4_BLAD4_TXD")
	)
	(segment
		(start 4.7371 -235.670598)
		(end 5.863082 -234.544616)
		(width 0.127)
		(layer "In5.Cu")
		(net "T4_BLAD4_TXD")
	)
	(segment
		(start 20.576286 -198.247508)
		(end 20.576286 -180.194204)
		(width 0.127)
		(layer "In5.Cu")
		(net "T4_BLAD4_TXD")
	)
	(segment
		(start 90.720164 -139.62507)
		(end 92.089732 -139.62507)
		(width 0.127)
		(layer "In5.Cu")
		(net "T4_BLAD4_TXD")
	)
	(via
		(at 81.10347 -147.856194)
		(size 0.508)
		(drill 0.254)
		(layers "F.Cu" "B.Cu")
		(net "T4_BLAD3_EN")
	)
	(segment
		(start 29.278834 -178.183794)
		(end 60.107322 -178.183794)
		(width 0.127)
		(layer "In2.Cu")
		(net "T4_BLAD3_EN")
	)
	(segment
		(start 80.23606 -158.055056)
		(end 80.23606 -148.723604)
		(width 0.127)
		(layer "In2.Cu")
		(net "T4_BLAD3_EN")
	)
	(segment
		(start 1.948942 -246.670576)
		(end 2.864612 -245.754906)
		(width 0.127)
		(layer "In2.Cu")
		(net "T4_BLAD3_EN")
	)
	(segment
		(start 26.653744 -229.85222)
		(end 26.653744 -195.366386)
		(width 0.127)
		(layer "In2.Cu")
		(net "T4_BLAD3_EN")
	)
	(segment
		(start 13.67917 -243.890546)
		(end 21.989288 -235.580428)
		(width 0.127)
		(layer "In2.Cu")
		(net "T4_BLAD3_EN")
	)
	(segment
		(start 25.559004 -194.271646)
		(end 25.559004 -181.903624)
		(width 0.127)
		(layer "In2.Cu")
		(net "T4_BLAD3_EN")
	)
	(segment
		(start 26.653744 -195.366386)
		(end 25.559004 -194.271646)
		(width 0.127)
		(layer "In2.Cu")
		(net "T4_BLAD3_EN")
	)
	(segment
		(start 85.969348 -141.287754)
		(end 85.969348 -140.544804)
		(width 0.127)
		(layer "In2.Cu")
		(net "T4_BLAD3_EN")
	)
	(segment
		(start 86.540594 -141.859)
		(end 85.969348 -141.287754)
		(width 0.127)
		(layer "In2.Cu")
		(net "T4_BLAD3_EN")
	)
	(segment
		(start 21.989288 -235.580428)
		(end 21.989288 -234.516676)
		(width 0.127)
		(layer "In2.Cu")
		(net "T4_BLAD3_EN")
	)
	(segment
		(start 21.989288 -234.516676)
		(end 26.653744 -229.85222)
		(width 0.127)
		(layer "In2.Cu")
		(net "T4_BLAD3_EN")
	)
	(segment
		(start 25.559004 -181.903624)
		(end 29.278834 -178.183794)
		(width 0.127)
		(layer "In2.Cu")
		(net "T4_BLAD3_EN")
	)
	(segment
		(start 60.107322 -178.183794)
		(end 80.23606 -158.055056)
		(width 0.127)
		(layer "In2.Cu")
		(net "T4_BLAD3_EN")
	)
	(segment
		(start 85.969348 -140.544804)
		(end 86.889082 -139.62507)
		(width 0.127)
		(layer "In2.Cu")
		(net "T4_BLAD3_EN")
	)
	(segment
		(start 80.23606 -148.723604)
		(end 81.10347 -147.856194)
		(width 0.127)
		(layer "In2.Cu")
		(net "T4_BLAD3_EN")
	)
	(segment
		(start 81.10347 -147.856194)
		(end 86.540594 -142.41907)
		(width 0.127)
		(layer "In2.Cu")
		(net "T4_BLAD3_EN")
	)
	(segment
		(start 3.42265 -242.857782)
		(end 6.935724 -242.857782)
		(width 0.127)
		(layer "In2.Cu")
		(net "T4_BLAD3_EN")
	)
	(segment
		(start 7.968488 -243.890546)
		(end 13.67917 -243.890546)
		(width 0.127)
		(layer "In2.Cu")
		(net "T4_BLAD3_EN")
	)
	(segment
		(start 86.540594 -142.41907)
		(end 86.540594 -141.859)
		(width 0.127)
		(layer "In2.Cu")
		(net "T4_BLAD3_EN")
	)
	(segment
		(start 2.864612 -245.754906)
		(end 2.864612 -243.41582)
		(width 0.127)
		(layer "In2.Cu")
		(net "T4_BLAD3_EN")
	)
	(segment
		(start 86.889082 -139.62507)
		(end 88.180164 -139.62507)
		(width 0.127)
		(layer "In2.Cu")
		(net "T4_BLAD3_EN")
	)
	(segment
		(start 6.935724 -242.857782)
		(end 7.968488 -243.890546)
		(width 0.127)
		(layer "In2.Cu")
		(net "T4_BLAD3_EN")
	)
	(segment
		(start 2.864612 -243.41582)
		(end 3.42265 -242.857782)
		(width 0.127)
		(layer "In2.Cu")
		(net "T4_BLAD3_EN")
	)
	(via
		(at 85.500718 -146.806412)
		(size 0.508)
		(drill 0.254)
		(layers "F.Cu" "B.Cu")
		(net "T4_BLAD3_RXD")
	)
	(segment
		(start 85.500464 -146.806412)
		(end 86.77275 -145.534126)
		(width 0.127)
		(layer "In5.Cu")
		(net "T4_BLAD3_RXD")
	)
	(segment
		(start 3.726688 -238.47298)
		(end 4.595622 -238.47298)
		(width 0.127)
		(layer "In5.Cu")
		(net "T4_BLAD3_RXD")
	)
	(segment
		(start 86.910164 -139.643612)
		(end 86.910164 -138.35507)
		(width 0.127)
		(layer "In5.Cu")
		(net "T4_BLAD3_RXD")
	)
	(segment
		(start 61.282072 -176.143158)
		(end 61.38545 -176.03978)
		(width 0.127)
		(layer "In5.Cu")
		(net "T4_BLAD3_RXD")
	)
	(segment
		(start 61.38545 -176.03978)
		(end 61.385704 -176.03978)
		(width 0.127)
		(layer "In5.Cu")
		(net "T4_BLAD3_RXD")
	)
	(segment
		(start 26.84399 -176.143158)
		(end 61.282072 -176.143158)
		(width 0.127)
		(layer "In5.Cu")
		(net "T4_BLAD3_RXD")
	)
	(segment
		(start 21.784056 -232.492042)
		(end 21.784056 -220.508068)
		(width 0.127)
		(layer "In5.Cu")
		(net "T4_BLAD3_RXD")
	)
	(segment
		(start 1.951736 -238.667798)
		(end 3.53187 -238.667798)
		(width 0.127)
		(layer "In5.Cu")
		(net "T4_BLAD3_RXD")
	)
	(segment
		(start 22.390608 -198.464932)
		(end 22.390608 -180.59654)
		(width 0.127)
		(layer "In5.Cu")
		(net "T4_BLAD3_RXD")
	)
	(segment
		(start 25.350978 -201.425302)
		(end 22.390608 -198.464932)
		(width 0.127)
		(layer "In5.Cu")
		(net "T4_BLAD3_RXD")
	)
	(segment
		(start 4.595622 -238.47298)
		(end 6.15823 -236.910372)
		(width 0.127)
		(layer "In5.Cu")
		(net "T4_BLAD3_RXD")
	)
	(segment
		(start 86.77275 -141.915896)
		(end 86.044532 -141.187678)
		(width 0.127)
		(layer "In5.Cu")
		(net "T4_BLAD3_RXD")
	)
	(segment
		(start 86.044532 -140.509244)
		(end 86.910164 -139.643612)
		(width 0.127)
		(layer "In5.Cu")
		(net "T4_BLAD3_RXD")
	)
	(segment
		(start 85.229954 -147.076922)
		(end 85.500464 -146.806412)
		(width 0.127)
		(layer "In5.Cu")
		(net "T4_BLAD3_RXD")
	)
	(segment
		(start 86.044532 -141.187678)
		(end 86.044532 -140.509244)
		(width 0.127)
		(layer "In5.Cu")
		(net "T4_BLAD3_RXD")
	)
	(segment
		(start 85.229954 -152.19553)
		(end 85.229954 -147.076922)
		(width 0.127)
		(layer "In5.Cu")
		(net "T4_BLAD3_RXD")
	)
	(segment
		(start 61.385704 -176.03978)
		(end 85.229954 -152.19553)
		(width 0.127)
		(layer "In5.Cu")
		(net "T4_BLAD3_RXD")
	)
	(segment
		(start 6.15823 -236.910372)
		(end 7.023608 -236.910372)
		(width 0.127)
		(layer "In5.Cu")
		(net "T4_BLAD3_RXD")
	)
	(segment
		(start 3.53187 -238.667798)
		(end 3.726688 -238.47298)
		(width 0.127)
		(layer "In5.Cu")
		(net "T4_BLAD3_RXD")
	)
	(segment
		(start 1.948942 -238.670592)
		(end 1.951736 -238.667798)
		(width 0.127)
		(layer "In5.Cu")
		(net "T4_BLAD3_RXD")
	)
	(segment
		(start 86.77275 -145.534126)
		(end 86.77275 -141.915896)
		(width 0.127)
		(layer "In5.Cu")
		(net "T4_BLAD3_RXD")
	)
	(segment
		(start 8.03656 -235.89742)
		(end 18.378678 -235.89742)
		(width 0.127)
		(layer "In5.Cu")
		(net "T4_BLAD3_RXD")
	)
	(segment
		(start 85.500464 -146.806412)
		(end 85.500718 -146.806412)
		(width 0.127)
		(layer "In5.Cu")
		(net "T4_BLAD3_RXD")
	)
	(segment
		(start 21.784056 -220.508068)
		(end 25.350978 -216.941146)
		(width 0.127)
		(layer "In5.Cu")
		(net "T4_BLAD3_RXD")
	)
	(segment
		(start 18.378678 -235.89742)
		(end 21.784056 -232.492042)
		(width 0.127)
		(layer "In5.Cu")
		(net "T4_BLAD3_RXD")
	)
	(segment
		(start 22.390608 -180.59654)
		(end 26.84399 -176.143158)
		(width 0.127)
		(layer "In5.Cu")
		(net "T4_BLAD3_RXD")
	)
	(segment
		(start 25.350978 -216.941146)
		(end 25.350978 -201.425302)
		(width 0.127)
		(layer "In5.Cu")
		(net "T4_BLAD3_RXD")
	)
	(segment
		(start 7.023608 -236.910372)
		(end 8.03656 -235.89742)
		(width 0.127)
		(layer "In5.Cu")
		(net "T4_BLAD3_RXD")
	)
	(segment
		(start 9.764268 -319.669922)
		(end 11.962384 -317.471806)
		(width 0.1524)
		(layer "F.Cu")
		(net "I2C_PSU3_SCL")
	)
	(segment
		(start 11.962384 -317.471806)
		(end 19.61388 -317.471806)
		(width 0.1524)
		(layer "F.Cu")
		(net "I2C_PSU3_SCL")
	)
	(segment
		(start 19.61388 -317.471806)
		(end 22.26691 -320.124836)
		(width 0.1524)
		(layer "F.Cu")
		(net "I2C_PSU3_SCL")
	)
	(segment
		(start 22.26691 -336.234024)
		(end 25.582626 -339.54974)
		(width 0.1524)
		(layer "F.Cu")
		(net "I2C_PSU3_SCL")
	)
	(segment
		(start 8.449818 -319.669922)
		(end 9.764268 -319.669922)
		(width 0.1524)
		(layer "F.Cu")
		(net "I2C_PSU3_SCL")
	)
	(segment
		(start 22.26691 -320.124836)
		(end 22.26691 -336.234024)
		(width 0.1524)
		(layer "F.Cu")
		(net "I2C_PSU3_SCL")
	)
	(via
		(at 25.582626 -339.54974)
		(size 0.508)
		(drill 0.254)
		(layers "F.Cu" "B.Cu")
		(net "I2C_PSU3_SCL")
	)
	(segment
		(start 29.912056 -372.396766)
		(end 26.941272 -375.36755)
		(width 0.1524)
		(layer "B.Cu")
		(net "I2C_PSU3_SCL")
	)
	(segment
		(start 35.53968 -362.603034)
		(end 35.53968 -363.270038)
		(width 0.1524)
		(layer "B.Cu")
		(net "I2C_PSU3_SCL")
	)
	(segment
		(start 33.11525 -365.694468)
		(end 33.11525 -370.47424)
		(width 0.1524)
		(layer "B.Cu")
		(net "I2C_PSU3_SCL")
	)
	(segment
		(start 25.582626 -339.54974)
		(end 24.937466 -340.1949)
		(width 0.1524)
		(layer "B.Cu")
		(net "I2C_PSU3_SCL")
	)
	(segment
		(start 34.23539 -360.26471)
		(end 34.23539 -361.298744)
		(width 0.1524)
		(layer "B.Cu")
		(net "I2C_PSU3_SCL")
	)
	(segment
		(start 34.454592 -450.584824)
		(end 35.53968 -451.669912)
		(width 0.1524)
		(layer "B.Cu")
		(net "I2C_PSU3_SCL")
	)
	(segment
		(start 34.454592 -447.1797)
		(end 34.454592 -450.584824)
		(width 0.1524)
		(layer "B.Cu")
		(net "I2C_PSU3_SCL")
	)
	(segment
		(start 34.23539 -361.298744)
		(end 35.53968 -362.603034)
		(width 0.1524)
		(layer "B.Cu")
		(net "I2C_PSU3_SCL")
	)
	(segment
		(start 31.192724 -372.396766)
		(end 29.912056 -372.396766)
		(width 0.1524)
		(layer "B.Cu")
		(net "I2C_PSU3_SCL")
	)
	(segment
		(start 33.11525 -370.47424)
		(end 31.192724 -372.396766)
		(width 0.1524)
		(layer "B.Cu")
		(net "I2C_PSU3_SCL")
	)
	(segment
		(start 26.941272 -375.36755)
		(end 26.941272 -439.66638)
		(width 0.1524)
		(layer "B.Cu")
		(net "I2C_PSU3_SCL")
	)
	(segment
		(start 24.937466 -350.966786)
		(end 34.23539 -360.26471)
		(width 0.1524)
		(layer "B.Cu")
		(net "I2C_PSU3_SCL")
	)
	(segment
		(start 24.937466 -340.1949)
		(end 24.937466 -350.966786)
		(width 0.1524)
		(layer "B.Cu")
		(net "I2C_PSU3_SCL")
	)
	(segment
		(start 35.53968 -363.270038)
		(end 33.11525 -365.694468)
		(width 0.1524)
		(layer "B.Cu")
		(net "I2C_PSU3_SCL")
	)
	(segment
		(start 26.941272 -439.66638)
		(end 34.454592 -447.1797)
		(width 0.1524)
		(layer "B.Cu")
		(net "I2C_PSU3_SCL")
	)
	(segment
		(start 37.775134 -105.422192)
		(end 37.507418 -105.689908)
		(width 0.1524)
		(layer "F.Cu")
		(net "PSU2_AD0")
	)
	(segment
		(start 39.706296 -105.42143)
		(end 39.705534 -105.422192)
		(width 0.1524)
		(layer "F.Cu")
		(net "PSU2_AD0")
	)
	(segment
		(start 37.507418 -105.689908)
		(end 35.53968 -105.689908)
		(width 0.1524)
		(layer "F.Cu")
		(net "PSU2_AD0")
	)
	(segment
		(start 39.705534 -105.422192)
		(end 37.775134 -105.422192)
		(width 0.1524)
		(layer "F.Cu")
		(net "PSU2_AD0")
	)
	(segment
		(start 40.959024 -105.42143)
		(end 39.706296 -105.42143)
		(width 0.1524)
		(layer "F.Cu")
		(net "PSU2_AD0")
	)
	(segment
		(start 39.840916 -279.661874)
		(end 39.840916 -280.119074)
		(width 0.1524)
		(layer "F.Cu")
		(net "PSU4_RETURN")
	)
	(segment
		(start 35.53968 -277.40991)
		(end 37.588952 -277.40991)
		(width 0.1524)
		(layer "F.Cu")
		(net "PSU4_RETURN")
	)
	(segment
		(start 37.588952 -277.40991)
		(end 39.840916 -279.661874)
		(width 0.1524)
		(layer "F.Cu")
		(net "PSU4_RETURN")
	)
	(segment
		(start 39.840916 -280.119074)
		(end 39.656512 -280.303478)
		(width 0.1524)
		(layer "F.Cu")
		(net "PSU4_RETURN")
	)
	(segment
		(start 39.656512 -280.303478)
		(end 39.656512 -281.140662)
		(width 0.1524)
		(layer "F.Cu")
		(net "PSU4_RETURN")
	)
	(via
		(at 39.840916 -279.661874)
		(size 0.508)
		(drill 0.254)
		(layers "F.Cu" "B.Cu")
		(net "PSU4_RETURN")
	)
	(via
		(at 93.702378 -102.694232)
		(size 0.508)
		(drill 0.254)
		(layers "F.Cu" "B.Cu")
		(net "T3_BLAD3_EN")
	)
	(segment
		(start 21.278088 -236.913166)
		(end 21.278088 -235.071158)
		(width 0.127)
		(layer "In5.Cu")
		(net "T3_BLAD3_EN")
	)
	(segment
		(start 25.870408 -190.64986)
		(end 25.870408 -181.48554)
		(width 0.127)
		(layer "In5.Cu")
		(net "T3_BLAD3_EN")
	)
	(segment
		(start 91.895676 -100.88753)
		(end 93.702378 -102.694232)
		(width 0.127)
		(layer "In5.Cu")
		(net "T3_BLAD3_EN")
	)
	(segment
		(start 21.278088 -235.071158)
		(end 24.398986 -231.95026)
		(width 0.127)
		(layer "In5.Cu")
		(net "T3_BLAD3_EN")
	)
	(segment
		(start 8.03148 -239.858804)
		(end 18.33245 -239.858804)
		(width 0.127)
		(layer "In5.Cu")
		(net "T3_BLAD3_EN")
	)
	(segment
		(start 7.425436 -242.693952)
		(end 7.425436 -240.464848)
		(width 0.127)
		(layer "In5.Cu")
		(net "T3_BLAD3_EN")
	)
	(segment
		(start 88.687402 -100.88753)
		(end 91.895676 -100.88753)
		(width 0.127)
		(layer "In5.Cu")
		(net "T3_BLAD3_EN")
	)
	(segment
		(start 24.727916 -198.581264)
		(end 24.727916 -191.792352)
		(width 0.127)
		(layer "In5.Cu")
		(net "T3_BLAD3_EN")
	)
	(segment
		(start 24.398986 -231.95026)
		(end 24.398986 -220.382846)
		(width 0.127)
		(layer "In5.Cu")
		(net "T3_BLAD3_EN")
	)
	(segment
		(start 6.448806 -243.670582)
		(end 7.425436 -242.693952)
		(width 0.127)
		(layer "In5.Cu")
		(net "T3_BLAD3_EN")
	)
	(segment
		(start 99.771454 -108.763308)
		(end 93.702378 -102.694232)
		(width 0.127)
		(layer "In5.Cu")
		(net "T3_BLAD3_EN")
	)
	(segment
		(start 25.870408 -181.48554)
		(end 29.533088 -177.82286)
		(width 0.127)
		(layer "In5.Cu")
		(net "T3_BLAD3_EN")
	)
	(segment
		(start 86.908132 -95.170244)
		(end 85.967316 -96.11106)
		(width 0.127)
		(layer "In5.Cu")
		(net "T3_BLAD3_EN")
	)
	(segment
		(start 26.79827 -200.651618)
		(end 24.727916 -198.581264)
		(width 0.127)
		(layer "In5.Cu")
		(net "T3_BLAD3_EN")
	)
	(segment
		(start 85.967316 -96.82353)
		(end 86.56574 -97.421954)
		(width 0.127)
		(layer "In5.Cu")
		(net "T3_BLAD3_EN")
	)
	(segment
		(start 86.56574 -97.421954)
		(end 86.56574 -98.765868)
		(width 0.127)
		(layer "In5.Cu")
		(net "T3_BLAD3_EN")
	)
	(segment
		(start 88.17991 -95.17507)
		(end 88.175084 -95.170244)
		(width 0.127)
		(layer "In5.Cu")
		(net "T3_BLAD3_EN")
	)
	(segment
		(start 78.546706 -160.852866)
		(end 91.38158 -160.852866)
		(width 0.127)
		(layer "In5.Cu")
		(net "T3_BLAD3_EN")
	)
	(segment
		(start 7.425436 -240.464848)
		(end 8.03148 -239.858804)
		(width 0.127)
		(layer "In5.Cu")
		(net "T3_BLAD3_EN")
	)
	(segment
		(start 61.576712 -177.82286)
		(end 78.546706 -160.852866)
		(width 0.127)
		(layer "In5.Cu")
		(net "T3_BLAD3_EN")
	)
	(segment
		(start 91.38158 -160.852866)
		(end 99.771454 -152.462992)
		(width 0.127)
		(layer "In5.Cu")
		(net "T3_BLAD3_EN")
	)
	(segment
		(start 88.175084 -95.170244)
		(end 86.908132 -95.170244)
		(width 0.127)
		(layer "In5.Cu")
		(net "T3_BLAD3_EN")
	)
	(segment
		(start 29.533088 -177.82286)
		(end 61.576712 -177.82286)
		(width 0.127)
		(layer "In5.Cu")
		(net "T3_BLAD3_EN")
	)
	(segment
		(start 99.771454 -152.462992)
		(end 99.771454 -108.763308)
		(width 0.127)
		(layer "In5.Cu")
		(net "T3_BLAD3_EN")
	)
	(segment
		(start 24.727916 -191.792352)
		(end 25.870408 -190.64986)
		(width 0.127)
		(layer "In5.Cu")
		(net "T3_BLAD3_EN")
	)
	(segment
		(start 24.398986 -220.382846)
		(end 26.79827 -217.983562)
		(width 0.127)
		(layer "In5.Cu")
		(net "T3_BLAD3_EN")
	)
	(segment
		(start 86.56574 -98.765868)
		(end 88.687402 -100.88753)
		(width 0.127)
		(layer "In5.Cu")
		(net "T3_BLAD3_EN")
	)
	(segment
		(start 85.967316 -96.11106)
		(end 85.967316 -96.82353)
		(width 0.127)
		(layer "In5.Cu")
		(net "T3_BLAD3_EN")
	)
	(segment
		(start 18.33245 -239.858804)
		(end 21.278088 -236.913166)
		(width 0.127)
		(layer "In5.Cu")
		(net "T3_BLAD3_EN")
	)
	(segment
		(start 26.79827 -217.983562)
		(end 26.79827 -200.651618)
		(width 0.127)
		(layer "In5.Cu")
		(net "T3_BLAD3_EN")
	)
	(via
		(at 92.41155 -102.049072)
		(size 0.508)
		(drill 0.254)
		(layers "F.Cu" "B.Cu")
		(net "T3_BLAD1_TXD")
	)
	(segment
		(start 24.03475 -231.828848)
		(end 24.03475 -220.101414)
		(width 0.127)
		(layer "In5.Cu")
		(net "T3_BLAD1_TXD")
	)
	(segment
		(start 7.741666 -239.380776)
		(end 18.16481 -239.380776)
		(width 0.127)
		(layer "In5.Cu")
		(net "T3_BLAD1_TXD")
	)
	(segment
		(start 7.454646 -239.667796)
		(end 7.741666 -239.380776)
		(width 0.127)
		(layer "In5.Cu")
		(net "T3_BLAD1_TXD")
	)
	(segment
		(start 26.444702 -217.691462)
		(end 26.444702 -200.926192)
		(width 0.127)
		(layer "In5.Cu")
		(net "T3_BLAD1_TXD")
	)
	(segment
		(start 91.939618 -101.57714)
		(end 88.502236 -101.57714)
		(width 0.127)
		(layer "In5.Cu")
		(net "T3_BLAD1_TXD")
	)
	(segment
		(start 6.448806 -239.67059)
		(end 6.4516 -239.667796)
		(width 0.127)
		(layer "In5.Cu")
		(net "T3_BLAD1_TXD")
	)
	(segment
		(start 20.82165 -236.723936)
		(end 20.82165 -235.041948)
		(width 0.127)
		(layer "In5.Cu")
		(net "T3_BLAD1_TXD")
	)
	(segment
		(start 6.4516 -239.667796)
		(end 7.454646 -239.667796)
		(width 0.127)
		(layer "In5.Cu")
		(net "T3_BLAD1_TXD")
	)
	(segment
		(start 18.16481 -239.380776)
		(end 20.82165 -236.723936)
		(width 0.127)
		(layer "In5.Cu")
		(net "T3_BLAD1_TXD")
	)
	(segment
		(start 23.494746 -181.952392)
		(end 28.080716 -177.366422)
		(width 0.127)
		(layer "In5.Cu")
		(net "T3_BLAD1_TXD")
	)
	(segment
		(start 88.502236 -101.57714)
		(end 85.63991 -98.714814)
		(width 0.127)
		(layer "In5.Cu")
		(net "T3_BLAD1_TXD")
	)
	(segment
		(start 92.41155 -102.049072)
		(end 91.939618 -101.57714)
		(width 0.127)
		(layer "In5.Cu")
		(net "T3_BLAD1_TXD")
	)
	(segment
		(start 20.82165 -235.041948)
		(end 24.03475 -231.828848)
		(width 0.127)
		(layer "In5.Cu")
		(net "T3_BLAD1_TXD")
	)
	(segment
		(start 78.521052 -160.396428)
		(end 91.19235 -160.396428)
		(width 0.127)
		(layer "In5.Cu")
		(net "T3_BLAD1_TXD")
	)
	(segment
		(start 91.19235 -160.396428)
		(end 99.315016 -152.273762)
		(width 0.127)
		(layer "In5.Cu")
		(net "T3_BLAD1_TXD")
	)
	(segment
		(start 99.315016 -108.952538)
		(end 92.41155 -102.049072)
		(width 0.127)
		(layer "In5.Cu")
		(net "T3_BLAD1_TXD")
	)
	(segment
		(start 28.080716 -177.366422)
		(end 61.551058 -177.366422)
		(width 0.127)
		(layer "In5.Cu")
		(net "T3_BLAD1_TXD")
	)
	(segment
		(start 24.03475 -220.101414)
		(end 26.444702 -217.691462)
		(width 0.127)
		(layer "In5.Cu")
		(net "T3_BLAD1_TXD")
	)
	(segment
		(start 85.63991 -98.714814)
		(end 85.63991 -97.71507)
		(width 0.127)
		(layer "In5.Cu")
		(net "T3_BLAD1_TXD")
	)
	(segment
		(start 23.494746 -197.976236)
		(end 23.494746 -181.952392)
		(width 0.127)
		(layer "In5.Cu")
		(net "T3_BLAD1_TXD")
	)
	(segment
		(start 26.444702 -200.926192)
		(end 23.494746 -197.976236)
		(width 0.127)
		(layer "In5.Cu")
		(net "T3_BLAD1_TXD")
	)
	(segment
		(start 61.551058 -177.366422)
		(end 78.521052 -160.396428)
		(width 0.127)
		(layer "In5.Cu")
		(net "T3_BLAD1_TXD")
	)
	(segment
		(start 99.315016 -152.273762)
		(end 99.315016 -108.952538)
		(width 0.127)
		(layer "In5.Cu")
		(net "T3_BLAD1_TXD")
	)
	(segment
		(start 39.84371 -101.906578)
		(end 39.84371 -102.417118)
		(width 0.1524)
		(layer "F.Cu")
		(net "PSU2_RETURN")
	)
	(segment
		(start 35.53968 -100.609908)
		(end 38.54704 -100.609908)
		(width 0.1524)
		(layer "F.Cu")
		(net "PSU2_RETURN")
	)
	(segment
		(start 38.54704 -100.609908)
		(end 39.84371 -101.906578)
		(width 0.1524)
		(layer "F.Cu")
		(net "PSU2_RETURN")
	)
	(segment
		(start 39.45636 -102.804468)
		(end 39.45636 -103.52405)
		(width 0.1524)
		(layer "F.Cu")
		(net "PSU2_RETURN")
	)
	(segment
		(start 39.84371 -102.417118)
		(end 39.45636 -102.804468)
		(width 0.1524)
		(layer "F.Cu")
		(net "PSU2_RETURN")
	)
	(via
		(at 39.84371 -101.906578)
		(size 0.508)
		(drill 0.254)
		(layers "F.Cu" "B.Cu")
		(net "PSU2_RETURN")
	)
	(via
		(at 83.5533 -103.940864)
		(size 0.508)
		(drill 0.254)
		(layers "F.Cu" "B.Cu")
		(net "T3_BLAD3_RXD")
	)
	(segment
		(start 86.910418 -93.905578)
		(end 86.910418 -95.276416)
		(width 0.127)
		(layer "In2.Cu")
		(net "T3_BLAD3_RXD")
	)
	(segment
		(start 81.553812 -144.422622)
		(end 81.894172 -144.422622)
		(width 0.127)
		(layer "In2.Cu")
		(net "T3_BLAD3_RXD")
	)
	(segment
		(start 87.68461 -96.050608)
		(end 87.68461 -97.04832)
		(width 0.127)
		(layer "In2.Cu")
		(net "T3_BLAD3_RXD")
	)
	(segment
		(start 20.158202 -230.706168)
		(end 20.158202 -229.333044)
		(width 0.127)
		(layer "In2.Cu")
		(net "T3_BLAD3_RXD")
	)
	(segment
		(start 78.187042 -157.493462)
		(end 78.187042 -147.789392)
		(width 0.127)
		(layer "In2.Cu")
		(net "T3_BLAD3_RXD")
	)
	(segment
		(start 25.25395 -200.01357)
		(end 21.818346 -196.577966)
		(width 0.127)
		(layer "In2.Cu")
		(net "T3_BLAD3_RXD")
	)
	(segment
		(start 20.158202 -229.333044)
		(end 25.25395 -224.237296)
		(width 0.127)
		(layer "In2.Cu")
		(net "T3_BLAD3_RXD")
	)
	(segment
		(start 27.031188 -176.819306)
		(end 58.861198 -176.819306)
		(width 0.127)
		(layer "In2.Cu")
		(net "T3_BLAD3_RXD")
	)
	(segment
		(start 6.448806 -235.670598)
		(end 15.193772 -235.670598)
		(width 0.127)
		(layer "In2.Cu")
		(net "T3_BLAD3_RXD")
	)
	(segment
		(start 86.90991 -93.90507)
		(end 86.910418 -93.905578)
		(width 0.127)
		(layer "In2.Cu")
		(net "T3_BLAD3_RXD")
	)
	(segment
		(start 83.5533 -103.164386)
		(end 83.5533 -103.940864)
		(width 0.127)
		(layer "In2.Cu")
		(net "T3_BLAD3_RXD")
	)
	(segment
		(start 15.193772 -235.670598)
		(end 20.158202 -230.706168)
		(width 0.127)
		(layer "In2.Cu")
		(net "T3_BLAD3_RXD")
	)
	(segment
		(start 84.80679 -114.860324)
		(end 83.5533 -113.606834)
		(width 0.127)
		(layer "In2.Cu")
		(net "T3_BLAD3_RXD")
	)
	(segment
		(start 21.818346 -182.032148)
		(end 27.031188 -176.819306)
		(width 0.127)
		(layer "In2.Cu")
		(net "T3_BLAD3_RXD")
	)
	(segment
		(start 78.187042 -147.789392)
		(end 81.553812 -144.422622)
		(width 0.127)
		(layer "In2.Cu")
		(net "T3_BLAD3_RXD")
	)
	(segment
		(start 58.861198 -176.819306)
		(end 78.187042 -157.493462)
		(width 0.127)
		(layer "In2.Cu")
		(net "T3_BLAD3_RXD")
	)
	(segment
		(start 81.894172 -144.422622)
		(end 84.049616 -142.267178)
		(width 0.127)
		(layer "In2.Cu")
		(net "T3_BLAD3_RXD")
	)
	(segment
		(start 83.5533 -113.606834)
		(end 83.5533 -103.940864)
		(width 0.127)
		(layer "In2.Cu")
		(net "T3_BLAD3_RXD")
	)
	(segment
		(start 87.1728 -99.544886)
		(end 83.5533 -103.164386)
		(width 0.127)
		(layer "In2.Cu")
		(net "T3_BLAD3_RXD")
	)
	(segment
		(start 87.1728 -97.56013)
		(end 87.1728 -99.544886)
		(width 0.127)
		(layer "In2.Cu")
		(net "T3_BLAD3_RXD")
	)
	(segment
		(start 84.049616 -137.696448)
		(end 84.80679 -136.939274)
		(width 0.127)
		(layer "In2.Cu")
		(net "T3_BLAD3_RXD")
	)
	(segment
		(start 25.25395 -224.237296)
		(end 25.25395 -200.01357)
		(width 0.127)
		(layer "In2.Cu")
		(net "T3_BLAD3_RXD")
	)
	(segment
		(start 84.80679 -136.939274)
		(end 84.80679 -114.860324)
		(width 0.127)
		(layer "In2.Cu")
		(net "T3_BLAD3_RXD")
	)
	(segment
		(start 86.910418 -95.276416)
		(end 87.68461 -96.050608)
		(width 0.127)
		(layer "In2.Cu")
		(net "T3_BLAD3_RXD")
	)
	(segment
		(start 84.049616 -142.267178)
		(end 84.049616 -137.696448)
		(width 0.127)
		(layer "In2.Cu")
		(net "T3_BLAD3_RXD")
	)
	(segment
		(start 21.818346 -196.577966)
		(end 21.818346 -182.032148)
		(width 0.127)
		(layer "In2.Cu")
		(net "T3_BLAD3_RXD")
	)
	(segment
		(start 87.68461 -97.04832)
		(end 87.1728 -97.56013)
		(width 0.127)
		(layer "In2.Cu")
		(net "T3_BLAD3_RXD")
	)
	(via
		(at 95.133668 -101.925628)
		(size 0.508)
		(drill 0.254)
		(layers "F.Cu" "B.Cu")
		(net "T3_BLAD1_EN")
	)
	(segment
		(start 92.762324 -99.554284)
		(end 90.019124 -99.554284)
		(width 0.127)
		(layer "In5.Cu")
		(net "T3_BLAD1_EN")
	)
	(segment
		(start 91.831922 -161.939224)
		(end 100.857812 -152.913334)
		(width 0.127)
		(layer "In5.Cu")
		(net "T3_BLAD1_EN")
	)
	(segment
		(start 78.997048 -161.939224)
		(end 91.831922 -161.939224)
		(width 0.127)
		(layer "In5.Cu")
		(net "T3_BLAD1_EN")
	)
	(segment
		(start 30.614874 -178.909218)
		(end 62.027054 -178.909218)
		(width 0.127)
		(layer "In5.Cu")
		(net "T3_BLAD1_EN")
	)
	(segment
		(start 22.41423 -235.504736)
		(end 27.08783 -230.831136)
		(width 0.127)
		(layer "In5.Cu")
		(net "T3_BLAD1_EN")
	)
	(segment
		(start 27.817572 -218.774518)
		(end 27.817572 -200.045066)
		(width 0.127)
		(layer "In5.Cu")
		(net "T3_BLAD1_EN")
	)
	(segment
		(start 22.41423 -237.313724)
		(end 22.41423 -235.504736)
		(width 0.127)
		(layer "In5.Cu")
		(net "T3_BLAD1_EN")
	)
	(segment
		(start 26.613104 -192.943988)
		(end 27.772868 -191.784224)
		(width 0.127)
		(layer "In5.Cu")
		(net "T3_BLAD1_EN")
	)
	(segment
		(start 100.857812 -152.913334)
		(end 100.857812 -107.649772)
		(width 0.127)
		(layer "In5.Cu")
		(net "T3_BLAD1_EN")
	)
	(segment
		(start 8.325104 -243.79428)
		(end 15.933674 -243.79428)
		(width 0.127)
		(layer "In5.Cu")
		(net "T3_BLAD1_EN")
	)
	(segment
		(start 27.08783 -219.50426)
		(end 27.817572 -218.774518)
		(width 0.127)
		(layer "In5.Cu")
		(net "T3_BLAD1_EN")
	)
	(segment
		(start 90.019124 -99.554284)
		(end 88.17991 -97.71507)
		(width 0.127)
		(layer "In5.Cu")
		(net "T3_BLAD1_EN")
	)
	(segment
		(start 95.133668 -101.925628)
		(end 92.762324 -99.554284)
		(width 0.127)
		(layer "In5.Cu")
		(net "T3_BLAD1_EN")
	)
	(segment
		(start 27.772868 -181.751224)
		(end 30.614874 -178.909218)
		(width 0.127)
		(layer "In5.Cu")
		(net "T3_BLAD1_EN")
	)
	(segment
		(start 15.933674 -243.79428)
		(end 22.41423 -237.313724)
		(width 0.127)
		(layer "In5.Cu")
		(net "T3_BLAD1_EN")
	)
	(segment
		(start 6.448806 -245.670578)
		(end 8.325104 -243.79428)
		(width 0.127)
		(layer "In5.Cu")
		(net "T3_BLAD1_EN")
	)
	(segment
		(start 27.817572 -200.045066)
		(end 26.613104 -198.840598)
		(width 0.127)
		(layer "In5.Cu")
		(net "T3_BLAD1_EN")
	)
	(segment
		(start 27.772868 -191.784224)
		(end 27.772868 -181.751224)
		(width 0.127)
		(layer "In5.Cu")
		(net "T3_BLAD1_EN")
	)
	(segment
		(start 62.027054 -178.909218)
		(end 78.997048 -161.939224)
		(width 0.127)
		(layer "In5.Cu")
		(net "T3_BLAD1_EN")
	)
	(segment
		(start 100.857812 -107.649772)
		(end 95.133668 -101.925628)
		(width 0.127)
		(layer "In5.Cu")
		(net "T3_BLAD1_EN")
	)
	(segment
		(start 27.08783 -230.831136)
		(end 27.08783 -219.50426)
		(width 0.127)
		(layer "In5.Cu")
		(net "T3_BLAD1_EN")
	)
	(segment
		(start 26.613104 -198.840598)
		(end 26.613104 -192.943988)
		(width 0.127)
		(layer "In5.Cu")
		(net "T3_BLAD1_EN")
	)
	(via
		(at 82.853784 -105.151428)
		(size 0.508)
		(drill 0.254)
		(layers "F.Cu" "B.Cu")
		(net "T3_BLAD3_TXD")
	)
	(segment
		(start 84.46008 -136.79551)
		(end 84.46008 -115.004088)
		(width 0.127)
		(layer "In2.Cu")
		(net "T3_BLAD3_TXD")
	)
	(segment
		(start 85.640418 -96.458786)
		(end 85.640418 -95.175578)
		(width 0.127)
		(layer "In2.Cu")
		(net "T3_BLAD3_TXD")
	)
	(segment
		(start 21.384768 -196.794628)
		(end 21.384768 -181.918356)
		(width 0.127)
		(layer "In2.Cu")
		(net "T3_BLAD3_TXD")
	)
	(segment
		(start 84.339176 -101.450394)
		(end 84.339176 -97.760028)
		(width 0.127)
		(layer "In2.Cu")
		(net "T3_BLAD3_TXD")
	)
	(segment
		(start 77.840332 -147.645628)
		(end 81.410048 -144.075912)
		(width 0.127)
		(layer "In2.Cu")
		(net "T3_BLAD3_TXD")
	)
	(segment
		(start 19.744182 -229.07371)
		(end 24.881586 -223.936306)
		(width 0.127)
		(layer "In2.Cu")
		(net "T3_BLAD3_TXD")
	)
	(segment
		(start 81.410048 -144.075912)
		(end 81.750408 -144.075912)
		(width 0.127)
		(layer "In2.Cu")
		(net "T3_BLAD3_TXD")
	)
	(segment
		(start 24.881586 -200.291446)
		(end 21.384768 -196.794628)
		(width 0.127)
		(layer "In2.Cu")
		(net "T3_BLAD3_TXD")
	)
	(segment
		(start 19.744182 -230.534464)
		(end 19.744182 -229.07371)
		(width 0.127)
		(layer "In2.Cu")
		(net "T3_BLAD3_TXD")
	)
	(segment
		(start 83.702906 -142.123414)
		(end 83.702906 -137.552684)
		(width 0.127)
		(layer "In2.Cu")
		(net "T3_BLAD3_TXD")
	)
	(segment
		(start 82.853784 -102.935786)
		(end 84.339176 -101.450394)
		(width 0.127)
		(layer "In2.Cu")
		(net "T3_BLAD3_TXD")
	)
	(segment
		(start 24.881586 -223.936306)
		(end 24.881586 -200.291446)
		(width 0.127)
		(layer "In2.Cu")
		(net "T3_BLAD3_TXD")
	)
	(segment
		(start 15.608046 -234.6706)
		(end 19.744182 -230.534464)
		(width 0.127)
		(layer "In2.Cu")
		(net "T3_BLAD3_TXD")
	)
	(segment
		(start 8.448802 -234.6706)
		(end 15.608046 -234.6706)
		(width 0.127)
		(layer "In2.Cu")
		(net "T3_BLAD3_TXD")
	)
	(segment
		(start 58.717434 -176.472596)
		(end 77.840332 -157.349698)
		(width 0.127)
		(layer "In2.Cu")
		(net "T3_BLAD3_TXD")
	)
	(segment
		(start 77.840332 -157.349698)
		(end 77.840332 -147.645628)
		(width 0.127)
		(layer "In2.Cu")
		(net "T3_BLAD3_TXD")
	)
	(segment
		(start 81.750408 -144.075912)
		(end 83.702906 -142.123414)
		(width 0.127)
		(layer "In2.Cu")
		(net "T3_BLAD3_TXD")
	)
	(segment
		(start 85.640418 -95.175578)
		(end 85.63991 -95.17507)
		(width 0.127)
		(layer "In2.Cu")
		(net "T3_BLAD3_TXD")
	)
	(segment
		(start 84.46008 -115.004088)
		(end 82.853784 -113.397792)
		(width 0.127)
		(layer "In2.Cu")
		(net "T3_BLAD3_TXD")
	)
	(segment
		(start 82.853784 -113.397792)
		(end 82.853784 -105.151428)
		(width 0.127)
		(layer "In2.Cu")
		(net "T3_BLAD3_TXD")
	)
	(segment
		(start 21.384768 -181.918356)
		(end 26.830528 -176.472596)
		(width 0.127)
		(layer "In2.Cu")
		(net "T3_BLAD3_TXD")
	)
	(segment
		(start 26.830528 -176.472596)
		(end 58.717434 -176.472596)
		(width 0.127)
		(layer "In2.Cu")
		(net "T3_BLAD3_TXD")
	)
	(segment
		(start 83.702906 -137.552684)
		(end 84.46008 -136.79551)
		(width 0.127)
		(layer "In2.Cu")
		(net "T3_BLAD3_TXD")
	)
	(segment
		(start 82.853784 -105.151428)
		(end 82.853784 -102.935786)
		(width 0.127)
		(layer "In2.Cu")
		(net "T3_BLAD3_TXD")
	)
	(segment
		(start 84.339176 -97.760028)
		(end 85.640418 -96.458786)
		(width 0.127)
		(layer "In2.Cu")
		(net "T3_BLAD3_TXD")
	)
	(via
		(at 96.743012 -102.615746)
		(size 0.508)
		(drill 0.254)
		(layers "F.Cu" "B.Cu")
		(net "T3_BLAD2_EN")
	)
	(segment
		(start 8.451596 -244.667786)
		(end 15.677388 -244.667786)
		(width 0.127)
		(layer "In5.Cu")
		(net "T3_BLAD2_EN")
	)
	(segment
		(start 101.230176 -107.10291)
		(end 96.743012 -102.615746)
		(width 0.127)
		(layer "In5.Cu")
		(net "T3_BLAD2_EN")
	)
	(segment
		(start 90.64117 -99.022154)
		(end 89.44991 -97.830894)
		(width 0.127)
		(layer "In5.Cu")
		(net "T3_BLAD2_EN")
	)
	(segment
		(start 89.44991 -97.830894)
		(end 89.44991 -96.44507)
		(width 0.127)
		(layer "In5.Cu")
		(net "T3_BLAD2_EN")
	)
	(segment
		(start 27.430222 -219.688664)
		(end 28.148534 -218.970352)
		(width 0.127)
		(layer "In5.Cu")
		(net "T3_BLAD2_EN")
	)
	(segment
		(start 22.786594 -237.55858)
		(end 22.786594 -235.645706)
		(width 0.127)
		(layer "In5.Cu")
		(net "T3_BLAD2_EN")
	)
	(segment
		(start 93.14942 -99.022154)
		(end 90.64117 -99.022154)
		(width 0.127)
		(layer "In5.Cu")
		(net "T3_BLAD2_EN")
	)
	(segment
		(start 8.448802 -244.67058)
		(end 8.451596 -244.667786)
		(width 0.127)
		(layer "In5.Cu")
		(net "T3_BLAD2_EN")
	)
	(segment
		(start 30.769306 -179.281582)
		(end 62.181486 -179.281582)
		(width 0.127)
		(layer "In5.Cu")
		(net "T3_BLAD2_EN")
	)
	(segment
		(start 28.148534 -218.970352)
		(end 28.148534 -181.902354)
		(width 0.127)
		(layer "In5.Cu")
		(net "T3_BLAD2_EN")
	)
	(segment
		(start 28.148534 -181.902354)
		(end 30.769306 -179.281582)
		(width 0.127)
		(layer "In5.Cu")
		(net "T3_BLAD2_EN")
	)
	(segment
		(start 91.986354 -162.311588)
		(end 101.230176 -153.067766)
		(width 0.127)
		(layer "In5.Cu")
		(net "T3_BLAD2_EN")
	)
	(segment
		(start 62.181486 -179.281582)
		(end 79.15148 -162.311588)
		(width 0.127)
		(layer "In5.Cu")
		(net "T3_BLAD2_EN")
	)
	(segment
		(start 96.743012 -102.615746)
		(end 93.14942 -99.022154)
		(width 0.127)
		(layer "In5.Cu")
		(net "T3_BLAD2_EN")
	)
	(segment
		(start 101.230176 -153.067766)
		(end 101.230176 -107.10291)
		(width 0.127)
		(layer "In5.Cu")
		(net "T3_BLAD2_EN")
	)
	(segment
		(start 22.786594 -235.645706)
		(end 27.430222 -231.002078)
		(width 0.127)
		(layer "In5.Cu")
		(net "T3_BLAD2_EN")
	)
	(segment
		(start 27.430222 -231.002078)
		(end 27.430222 -219.688664)
		(width 0.127)
		(layer "In5.Cu")
		(net "T3_BLAD2_EN")
	)
	(segment
		(start 79.15148 -162.311588)
		(end 91.986354 -162.311588)
		(width 0.127)
		(layer "In5.Cu")
		(net "T3_BLAD2_EN")
	)
	(segment
		(start 15.677388 -244.667786)
		(end 22.786594 -237.55858)
		(width 0.127)
		(layer "In5.Cu")
		(net "T3_BLAD2_EN")
	)
	(via
		(at 86.892638 -102.027736)
		(size 0.508)
		(drill 0.254)
		(layers "F.Cu" "B.Cu")
		(net "T3_BLAD2_RXD")
	)
	(segment
		(start 84.737194 -142.552166)
		(end 84.737194 -137.981436)
		(width 0.127)
		(layer "In2.Cu")
		(net "T3_BLAD2_RXD")
	)
	(segment
		(start 78.87462 -148.07438)
		(end 81.8388 -145.1102)
		(width 0.127)
		(layer "In2.Cu")
		(net "T3_BLAD2_RXD")
	)
	(segment
		(start 90.350594 -98.56978)
		(end 86.892638 -102.027736)
		(width 0.127)
		(layer "In2.Cu")
		(net "T3_BLAD2_RXD")
	)
	(segment
		(start 84.737194 -137.981436)
		(end 85.494368 -137.224262)
		(width 0.127)
		(layer "In2.Cu")
		(net "T3_BLAD2_RXD")
	)
	(segment
		(start 84.793836 -113.874804)
		(end 84.793836 -104.126538)
		(width 0.127)
		(layer "In2.Cu")
		(net "T3_BLAD2_RXD")
	)
	(segment
		(start 22.708108 -182.534052)
		(end 27.735276 -177.506884)
		(width 0.127)
		(layer "In2.Cu")
		(net "T3_BLAD2_RXD")
	)
	(segment
		(start 85.494368 -137.224262)
		(end 85.494368 -114.575336)
		(width 0.127)
		(layer "In2.Cu")
		(net "T3_BLAD2_RXD")
	)
	(segment
		(start 25.968706 -224.642934)
		(end 25.968706 -199.633078)
		(width 0.127)
		(layer "In2.Cu")
		(net "T3_BLAD2_RXD")
	)
	(segment
		(start 59.146186 -177.506884)
		(end 78.87462 -157.77845)
		(width 0.127)
		(layer "In2.Cu")
		(net "T3_BLAD2_RXD")
	)
	(segment
		(start 81.8388 -145.1102)
		(end 82.17916 -145.1102)
		(width 0.127)
		(layer "In2.Cu")
		(net "T3_BLAD2_RXD")
	)
	(segment
		(start 91.98991 -96.44507)
		(end 91.98991 -97.54743)
		(width 0.127)
		(layer "In2.Cu")
		(net "T3_BLAD2_RXD")
	)
	(segment
		(start 22.708108 -196.37248)
		(end 22.708108 -182.534052)
		(width 0.127)
		(layer "In2.Cu")
		(net "T3_BLAD2_RXD")
	)
	(segment
		(start 78.87462 -157.77845)
		(end 78.87462 -148.07438)
		(width 0.127)
		(layer "In2.Cu")
		(net "T3_BLAD2_RXD")
	)
	(segment
		(start 21.002498 -231.036622)
		(end 21.002498 -229.609142)
		(width 0.127)
		(layer "In2.Cu")
		(net "T3_BLAD2_RXD")
	)
	(segment
		(start 85.494368 -114.575336)
		(end 84.793836 -113.874804)
		(width 0.127)
		(layer "In2.Cu")
		(net "T3_BLAD2_RXD")
	)
	(segment
		(start 25.968706 -199.633078)
		(end 22.708108 -196.37248)
		(width 0.127)
		(layer "In2.Cu")
		(net "T3_BLAD2_RXD")
	)
	(segment
		(start 90.96756 -98.56978)
		(end 90.350594 -98.56978)
		(width 0.127)
		(layer "In2.Cu")
		(net "T3_BLAD2_RXD")
	)
	(segment
		(start 84.793836 -104.126538)
		(end 86.892638 -102.027736)
		(width 0.127)
		(layer "In2.Cu")
		(net "T3_BLAD2_RXD")
	)
	(segment
		(start 27.735276 -177.506884)
		(end 59.146186 -177.506884)
		(width 0.127)
		(layer "In2.Cu")
		(net "T3_BLAD2_RXD")
	)
	(segment
		(start 13.368528 -238.670592)
		(end 21.002498 -231.036622)
		(width 0.127)
		(layer "In2.Cu")
		(net "T3_BLAD2_RXD")
	)
	(segment
		(start 8.448802 -238.670592)
		(end 13.368528 -238.670592)
		(width 0.127)
		(layer "In2.Cu")
		(net "T3_BLAD2_RXD")
	)
	(segment
		(start 21.002498 -229.609142)
		(end 25.968706 -224.642934)
		(width 0.127)
		(layer "In2.Cu")
		(net "T3_BLAD2_RXD")
	)
	(segment
		(start 91.98991 -97.54743)
		(end 90.96756 -98.56978)
		(width 0.127)
		(layer "In2.Cu")
		(net "T3_BLAD2_RXD")
	)
	(segment
		(start 82.17916 -145.1102)
		(end 84.737194 -142.552166)
		(width 0.127)
		(layer "In2.Cu")
		(net "T3_BLAD2_RXD")
	)
	(segment
		(start 7.264908 -252.912372)
		(end 8.065516 -253.71298)
		(width 0.1524)
		(layer "F.Cu")
		(net "I2C_PSU2_SCL")
	)
	(segment
		(start 3.29438 -252.670564)
		(end 3.536188 -252.912372)
		(width 0.1524)
		(layer "F.Cu")
		(net "I2C_PSU2_SCL")
	)
	(segment
		(start 8.065516 -253.71298)
		(end 9.821418 -253.71298)
		(width 0.1524)
		(layer "F.Cu")
		(net "I2C_PSU2_SCL")
	)
	(segment
		(start 9.821418 -253.71298)
		(end 10.489692 -254.381254)
		(width 0.1524)
		(layer "F.Cu")
		(net "I2C_PSU2_SCL")
	)
	(segment
		(start 1.948942 -252.670564)
		(end 3.29438 -252.670564)
		(width 0.1524)
		(layer "F.Cu")
		(net "I2C_PSU2_SCL")
	)
	(segment
		(start 10.489692 -254.381254)
		(end 25.038558 -254.381254)
		(width 0.1524)
		(layer "F.Cu")
		(net "I2C_PSU2_SCL")
	)
	(segment
		(start 3.536188 -252.912372)
		(end 7.264908 -252.912372)
		(width 0.1524)
		(layer "F.Cu")
		(net "I2C_PSU2_SCL")
	)
	(segment
		(start 25.038558 -254.381254)
		(end 25.574498 -253.845314)
		(width 0.1524)
		(layer "F.Cu")
		(net "I2C_PSU2_SCL")
	)
	(via
		(at 25.574498 -253.845314)
		(size 0.508)
		(drill 0.254)
		(layers "F.Cu" "B.Cu")
		(net "I2C_PSU2_SCL")
	)
	(segment
		(start 37.03701 -269.727426)
		(end 25.574498 -258.264914)
		(width 0.1524)
		(layer "B.Cu")
		(net "I2C_PSU2_SCL")
	)
	(segment
		(start 25.03043 -250.18873)
		(end 25.03043 -204.761084)
		(width 0.1524)
		(layer "B.Cu")
		(net "I2C_PSU2_SCL")
	)
	(segment
		(start 25.574498 -250.732798)
		(end 25.03043 -250.18873)
		(width 0.1524)
		(layer "B.Cu")
		(net "I2C_PSU2_SCL")
	)
	(segment
		(start 25.574498 -253.845314)
		(end 25.574498 -250.732798)
		(width 0.1524)
		(layer "B.Cu")
		(net "I2C_PSU2_SCL")
	)
	(segment
		(start 37.03701 -273.37258)
		(end 37.03701 -269.727426)
		(width 0.1524)
		(layer "B.Cu")
		(net "I2C_PSU2_SCL")
	)
	(segment
		(start 25.574498 -258.264914)
		(end 25.574498 -253.845314)
		(width 0.1524)
		(layer "B.Cu")
		(net "I2C_PSU2_SCL")
	)
	(segment
		(start 25.03043 -204.761084)
		(end 29.097478 -200.694036)
		(width 0.1524)
		(layer "B.Cu")
		(net "I2C_PSU2_SCL")
	)
	(segment
		(start 31.87192 -200.694036)
		(end 34.291016 -198.27494)
		(width 0.1524)
		(layer "B.Cu")
		(net "I2C_PSU2_SCL")
	)
	(segment
		(start 35.53968 -274.86991)
		(end 37.03701 -273.37258)
		(width 0.1524)
		(layer "B.Cu")
		(net "I2C_PSU2_SCL")
	)
	(segment
		(start 34.291016 -198.27494)
		(end 34.291016 -187.7187)
		(width 0.1524)
		(layer "B.Cu")
		(net "I2C_PSU2_SCL")
	)
	(segment
		(start 29.097478 -200.694036)
		(end 31.87192 -200.694036)
		(width 0.1524)
		(layer "B.Cu")
		(net "I2C_PSU2_SCL")
	)
	(segment
		(start 34.291016 -187.7187)
		(end 35.53968 -186.470036)
		(width 0.1524)
		(layer "B.Cu")
		(net "I2C_PSU2_SCL")
	)
	(via
		(at 96.677226 -104.168448)
		(size 0.508)
		(drill 0.254)
		(layers "F.Cu" "B.Cu")
		(net "T3_BLAD4_EN")
	)
	(segment
		(start 89.44991 -93.90507)
		(end 89.44991 -95.09125)
		(width 0.127)
		(layer "In5.Cu")
		(net "T3_BLAD4_EN")
	)
	(segment
		(start 91.689682 -161.59607)
		(end 100.514658 -152.771094)
		(width 0.127)
		(layer "In5.Cu")
		(net "T3_BLAD4_EN")
	)
	(segment
		(start 26.160476 -191.403732)
		(end 26.552144 -191.012064)
		(width 0.127)
		(layer "In5.Cu")
		(net "T3_BLAD4_EN")
	)
	(segment
		(start 26.552144 -181.923182)
		(end 29.909262 -178.566064)
		(width 0.127)
		(layer "In5.Cu")
		(net "T3_BLAD4_EN")
	)
	(segment
		(start 87.341202 -98.059494)
		(end 89.261696 -99.979988)
		(width 0.127)
		(layer "In5.Cu")
		(net "T3_BLAD4_EN")
	)
	(segment
		(start 78.854808 -161.59607)
		(end 91.689682 -161.59607)
		(width 0.127)
		(layer "In5.Cu")
		(net "T3_BLAD4_EN")
	)
	(segment
		(start 92.488766 -99.979988)
		(end 96.677226 -104.168448)
		(width 0.127)
		(layer "In5.Cu")
		(net "T3_BLAD4_EN")
	)
	(segment
		(start 22.021292 -235.37926)
		(end 26.732992 -230.66756)
		(width 0.127)
		(layer "In5.Cu")
		(net "T3_BLAD4_EN")
	)
	(segment
		(start 22.021292 -237.221268)
		(end 22.021292 -235.37926)
		(width 0.127)
		(layer "In5.Cu")
		(net "T3_BLAD4_EN")
	)
	(segment
		(start 26.552144 -191.012064)
		(end 26.552144 -181.923182)
		(width 0.127)
		(layer "In5.Cu")
		(net "T3_BLAD4_EN")
	)
	(segment
		(start 87.341202 -97.199958)
		(end 87.341202 -98.059494)
		(width 0.127)
		(layer "In5.Cu")
		(net "T3_BLAD4_EN")
	)
	(segment
		(start 26.160476 -198.995284)
		(end 26.160476 -191.403732)
		(width 0.127)
		(layer "In5.Cu")
		(net "T3_BLAD4_EN")
	)
	(segment
		(start 89.44991 -95.09125)
		(end 87.341202 -97.199958)
		(width 0.127)
		(layer "In5.Cu")
		(net "T3_BLAD4_EN")
	)
	(segment
		(start 8.448802 -242.670584)
		(end 8.451596 -242.66779)
		(width 0.127)
		(layer "In5.Cu")
		(net "T3_BLAD4_EN")
	)
	(segment
		(start 61.884814 -178.566064)
		(end 78.854808 -161.59607)
		(width 0.127)
		(layer "In5.Cu")
		(net "T3_BLAD4_EN")
	)
	(segment
		(start 26.732992 -230.66756)
		(end 26.732992 -219.373704)
		(width 0.127)
		(layer "In5.Cu")
		(net "T3_BLAD4_EN")
	)
	(segment
		(start 27.470862 -200.30567)
		(end 26.160476 -198.995284)
		(width 0.127)
		(layer "In5.Cu")
		(net "T3_BLAD4_EN")
	)
	(segment
		(start 8.451596 -242.66779)
		(end 16.57477 -242.66779)
		(width 0.127)
		(layer "In5.Cu")
		(net "T3_BLAD4_EN")
	)
	(segment
		(start 89.261696 -99.979988)
		(end 92.488766 -99.979988)
		(width 0.127)
		(layer "In5.Cu")
		(net "T3_BLAD4_EN")
	)
	(segment
		(start 27.470862 -218.635834)
		(end 27.470862 -200.30567)
		(width 0.127)
		(layer "In5.Cu")
		(net "T3_BLAD4_EN")
	)
	(segment
		(start 16.57477 -242.66779)
		(end 22.021292 -237.221268)
		(width 0.127)
		(layer "In5.Cu")
		(net "T3_BLAD4_EN")
	)
	(segment
		(start 100.514658 -152.771094)
		(end 100.514658 -108.00588)
		(width 0.127)
		(layer "In5.Cu")
		(net "T3_BLAD4_EN")
	)
	(segment
		(start 100.514658 -108.00588)
		(end 96.677226 -104.168448)
		(width 0.127)
		(layer "In5.Cu")
		(net "T3_BLAD4_EN")
	)
	(segment
		(start 29.909262 -178.566064)
		(end 61.884814 -178.566064)
		(width 0.127)
		(layer "In5.Cu")
		(net "T3_BLAD4_EN")
	)
	(segment
		(start 26.732992 -219.373704)
		(end 27.470862 -218.635834)
		(width 0.127)
		(layer "In5.Cu")
		(net "T3_BLAD4_EN")
	)
	(segment
		(start 10.390632 -324.530212)
		(end 10.910824 -324.01002)
		(width 0.1524)
		(layer "F.Cu")
		(net "FAN5_TACH")
	)
	(segment
		(start 7.25932 -324.669912)
		(end 7.39902 -324.530212)
		(width 0.1524)
		(layer "F.Cu")
		(net "FAN5_TACH")
	)
	(segment
		(start 7.39902 -324.530212)
		(end 10.390632 -324.530212)
		(width 0.1524)
		(layer "F.Cu")
		(net "FAN5_TACH")
	)
	(segment
		(start 10.910824 -324.01002)
		(end 13.063728 -324.01002)
		(width 0.1524)
		(layer "F.Cu")
		(net "FAN5_TACH")
	)
	(segment
		(start 6.449822 -324.669912)
		(end 7.25932 -324.669912)
		(width 0.1524)
		(layer "F.Cu")
		(net "FAN5_TACH")
	)
	(segment
		(start 4.290568 -448.888612)
		(end 8.51408 -444.6651)
		(width 0.1524)
		(layer "B.Cu")
		(net "FAN5_TACH")
	)
	(segment
		(start 8.51408 -444.6651)
		(end 8.51408 -420.557452)
		(width 0.1524)
		(layer "B.Cu")
		(net "FAN5_TACH")
	)
	(segment
		(start 5.944108 -461.694022)
		(end 4.290568 -460.040482)
		(width 0.1524)
		(layer "B.Cu")
		(net "FAN5_TACH")
	)
	(segment
		(start 12.582398 -372.33987)
		(end 12.582398 -345.830144)
		(width 0.1524)
		(layer "B.Cu")
		(net "FAN5_TACH")
	)
	(segment
		(start 8.134858 -326.796654)
		(end 7.576566 -326.238362)
		(width 0.1524)
		(layer "B.Cu")
		(net "FAN5_TACH")
	)
	(segment
		(start 4.290568 -460.040482)
		(end 4.290568 -448.888612)
		(width 0.1524)
		(layer "B.Cu")
		(net "FAN5_TACH")
	)
	(segment
		(start 7.576566 -326.238362)
		(end 7.576566 -325.796656)
		(width 0.1524)
		(layer "B.Cu")
		(net "FAN5_TACH")
	)
	(segment
		(start 8.51408 -420.557452)
		(end 22.592284 -406.479248)
		(width 0.1524)
		(layer "B.Cu")
		(net "FAN5_TACH")
	)
	(segment
		(start 7.576566 -325.796656)
		(end 6.449822 -324.669912)
		(width 0.1524)
		(layer "B.Cu")
		(net "FAN5_TACH")
	)
	(segment
		(start 22.592284 -382.349756)
		(end 12.582398 -372.33987)
		(width 0.1524)
		(layer "B.Cu")
		(net "FAN5_TACH")
	)
	(segment
		(start 22.592284 -406.479248)
		(end 22.592284 -382.349756)
		(width 0.1524)
		(layer "B.Cu")
		(net "FAN5_TACH")
	)
	(segment
		(start 12.582398 -345.830144)
		(end 10.331958 -343.579704)
		(width 0.1524)
		(layer "B.Cu")
		(net "FAN5_TACH")
	)
	(segment
		(start 10.331958 -328.380852)
		(end 8.74776 -326.796654)
		(width 0.1524)
		(layer "B.Cu")
		(net "FAN5_TACH")
	)
	(segment
		(start 10.331958 -343.579704)
		(end 10.331958 -328.380852)
		(width 0.1524)
		(layer "B.Cu")
		(net "FAN5_TACH")
	)
	(segment
		(start 8.74776 -326.796654)
		(end 8.134858 -326.796654)
		(width 0.1524)
		(layer "B.Cu")
		(net "FAN5_TACH")
	)
	(via
		(at 81.52892 -107.49915)
		(size 0.508)
		(drill 0.254)
		(layers "F.Cu" "B.Cu")
		(net "T3_BLAD4_TXD")
	)
	(segment
		(start 81.52892 -113.020094)
		(end 83.790536 -115.28171)
		(width 0.127)
		(layer "In2.Cu")
		(net "T3_BLAD4_TXD")
	)
	(segment
		(start 86.031324 -92.1131)
		(end 91.869768 -92.1131)
		(width 0.127)
		(layer "In2.Cu")
		(net "T3_BLAD4_TXD")
	)
	(segment
		(start 81.472786 -143.406368)
		(end 81.132426 -143.406368)
		(width 0.127)
		(layer "In2.Cu")
		(net "T3_BLAD4_TXD")
	)
	(segment
		(start 19.074638 -228.75113)
		(end 19.074638 -230.101648)
		(width 0.127)
		(layer "In2.Cu")
		(net "T3_BLAD4_TXD")
	)
	(segment
		(start 77.170788 -147.368006)
		(end 77.170788 -157.072076)
		(width 0.127)
		(layer "In2.Cu")
		(net "T3_BLAD4_TXD")
	)
	(segment
		(start 83.312762 -100.645468)
		(end 83.312762 -94.831662)
		(width 0.127)
		(layer "In2.Cu")
		(net "T3_BLAD4_TXD")
	)
	(segment
		(start 83.790536 -136.517888)
		(end 83.033362 -137.275062)
		(width 0.127)
		(layer "In2.Cu")
		(net "T3_BLAD4_TXD")
	)
	(segment
		(start 92.171266 -95.17507)
		(end 90.71991 -95.17507)
		(width 0.127)
		(layer "In2.Cu")
		(net "T3_BLAD4_TXD")
	)
	(segment
		(start 81.52892 -102.42931)
		(end 83.312762 -100.645468)
		(width 0.127)
		(layer "In2.Cu")
		(net "T3_BLAD4_TXD")
	)
	(segment
		(start 83.033362 -137.275062)
		(end 83.033362 -141.845792)
		(width 0.127)
		(layer "In2.Cu")
		(net "T3_BLAD4_TXD")
	)
	(segment
		(start 77.170788 -157.072076)
		(end 58.439812 -175.803052)
		(width 0.127)
		(layer "In2.Cu")
		(net "T3_BLAD4_TXD")
	)
	(segment
		(start 15.506192 -233.670094)
		(end 9.448292 -233.670094)
		(width 0.127)
		(layer "In2.Cu")
		(net "T3_BLAD4_TXD")
	)
	(segment
		(start 24.159464 -223.666304)
		(end 19.074638 -228.75113)
		(width 0.127)
		(layer "In2.Cu")
		(net "T3_BLAD4_TXD")
	)
	(segment
		(start 24.159464 -200.824846)
		(end 24.159464 -223.666304)
		(width 0.127)
		(layer "In2.Cu")
		(net "T3_BLAD4_TXD")
	)
	(segment
		(start 25.823164 -175.803052)
		(end 20.40382 -181.222396)
		(width 0.127)
		(layer "In2.Cu")
		(net "T3_BLAD4_TXD")
	)
	(segment
		(start 58.439812 -175.803052)
		(end 25.823164 -175.803052)
		(width 0.127)
		(layer "In2.Cu")
		(net "T3_BLAD4_TXD")
	)
	(segment
		(start 9.448292 -233.670094)
		(end 8.448802 -232.670604)
		(width 0.127)
		(layer "In2.Cu")
		(net "T3_BLAD4_TXD")
	)
	(segment
		(start 20.40382 -181.222396)
		(end 20.40382 -197.069202)
		(width 0.127)
		(layer "In2.Cu")
		(net "T3_BLAD4_TXD")
	)
	(segment
		(start 93.095318 -93.33865)
		(end 93.095318 -94.251018)
		(width 0.127)
		(layer "In2.Cu")
		(net "T3_BLAD4_TXD")
	)
	(segment
		(start 81.52892 -107.49915)
		(end 81.52892 -113.020094)
		(width 0.127)
		(layer "In2.Cu")
		(net "T3_BLAD4_TXD")
	)
	(segment
		(start 91.869768 -92.1131)
		(end 93.095318 -93.33865)
		(width 0.127)
		(layer "In2.Cu")
		(net "T3_BLAD4_TXD")
	)
	(segment
		(start 81.132426 -143.406368)
		(end 77.170788 -147.368006)
		(width 0.127)
		(layer "In2.Cu")
		(net "T3_BLAD4_TXD")
	)
	(segment
		(start 93.095318 -94.251018)
		(end 92.171266 -95.17507)
		(width 0.127)
		(layer "In2.Cu")
		(net "T3_BLAD4_TXD")
	)
	(segment
		(start 83.033362 -141.845792)
		(end 81.472786 -143.406368)
		(width 0.127)
		(layer "In2.Cu")
		(net "T3_BLAD4_TXD")
	)
	(segment
		(start 81.52892 -107.49915)
		(end 81.52892 -102.42931)
		(width 0.127)
		(layer "In2.Cu")
		(net "T3_BLAD4_TXD")
	)
	(segment
		(start 19.074638 -230.101648)
		(end 15.506192 -233.670094)
		(width 0.127)
		(layer "In2.Cu")
		(net "T3_BLAD4_TXD")
	)
	(segment
		(start 20.40382 -197.069202)
		(end 24.159464 -200.824846)
		(width 0.127)
		(layer "In2.Cu")
		(net "T3_BLAD4_TXD")
	)
	(segment
		(start 83.312762 -94.831662)
		(end 86.031324 -92.1131)
		(width 0.127)
		(layer "In2.Cu")
		(net "T3_BLAD4_TXD")
	)
	(segment
		(start 83.790536 -115.28171)
		(end 83.790536 -136.517888)
		(width 0.127)
		(layer "In2.Cu")
		(net "T3_BLAD4_TXD")
	)
	(segment
		(start 36.539932 -194.090036)
		(end 37.555932 -194.089782)
		(width 0.1524)
		(layer "F.Cu")
		(net "PSU3_AD0")
	)
	(segment
		(start 35.53968 -194.090036)
		(end 36.539932 -194.090036)
		(width 0.1524)
		(layer "F.Cu")
		(net "PSU3_AD0")
	)
	(segment
		(start 37.580824 -194.114674)
		(end 39.50081 -194.114674)
		(width 0.1524)
		(layer "F.Cu")
		(net "PSU3_AD0")
	)
	(segment
		(start 37.555932 -194.089782)
		(end 37.580824 -194.114674)
		(width 0.1524)
		(layer "F.Cu")
		(net "PSU3_AD0")
	)
	(segment
		(start 11.00709 -322.972176)
		(end 10.309352 -323.669914)
		(width 0.1524)
		(layer "F.Cu")
		(net "FAN6_TACH")
	)
	(segment
		(start 13.038074 -322.972176)
		(end 11.00709 -322.972176)
		(width 0.1524)
		(layer "F.Cu")
		(net "FAN6_TACH")
	)
	(segment
		(start 10.309352 -323.669914)
		(end 8.449818 -323.669914)
		(width 0.1524)
		(layer "F.Cu")
		(net "FAN6_TACH")
	)
	(segment
		(start 23.303484 -407.375106)
		(end 23.303484 -382.055116)
		(width 0.1524)
		(layer "B.Cu")
		(net "FAN6_TACH")
	)
	(segment
		(start 12.89304 -445.115696)
		(end 12.89304 -417.78555)
		(width 0.1524)
		(layer "B.Cu")
		(net "FAN6_TACH")
	)
	(segment
		(start 23.303484 -382.055116)
		(end 13.293598 -372.04523)
		(width 0.1524)
		(layer "B.Cu")
		(net "FAN6_TACH")
	)
	(segment
		(start 5.944108 -449.094098)
		(end 8.914638 -449.094098)
		(width 0.1524)
		(layer "B.Cu")
		(net "FAN6_TACH")
	)
	(segment
		(start 11.043158 -326.263254)
		(end 8.449818 -323.669914)
		(width 0.1524)
		(layer "B.Cu")
		(net "FAN6_TACH")
	)
	(segment
		(start 13.293598 -372.04523)
		(end 13.293598 -345.535504)
		(width 0.1524)
		(layer "B.Cu")
		(net "FAN6_TACH")
	)
	(segment
		(start 11.043158 -343.285064)
		(end 11.043158 -326.263254)
		(width 0.1524)
		(layer "B.Cu")
		(net "FAN6_TACH")
	)
	(segment
		(start 8.914638 -449.094098)
		(end 12.89304 -445.115696)
		(width 0.1524)
		(layer "B.Cu")
		(net "FAN6_TACH")
	)
	(segment
		(start 13.293598 -345.535504)
		(end 11.043158 -343.285064)
		(width 0.1524)
		(layer "B.Cu")
		(net "FAN6_TACH")
	)
	(segment
		(start 12.89304 -417.78555)
		(end 23.303484 -407.375106)
		(width 0.1524)
		(layer "B.Cu")
		(net "FAN6_TACH")
	)
	(via
		(at 95.108268 -103.341678)
		(size 0.508)
		(drill 0.254)
		(layers "F.Cu" "B.Cu")
		(net "T3_BLAD1_RXD")
	)
	(segment
		(start 8.451596 -240.667794)
		(end 18.003774 -240.667794)
		(width 0.127)
		(layer "In5.Cu")
		(net "T3_BLAD1_RXD")
	)
	(segment
		(start 27.140408 -218.395296)
		(end 27.140408 -200.495408)
		(width 0.127)
		(layer "In5.Cu")
		(net "T3_BLAD1_RXD")
	)
	(segment
		(start 88.70569 -100.432108)
		(end 86.90991 -98.636328)
		(width 0.127)
		(layer "In5.Cu")
		(net "T3_BLAD1_RXD")
	)
	(segment
		(start 61.717428 -178.162458)
		(end 78.687422 -161.192464)
		(width 0.127)
		(layer "In5.Cu")
		(net "T3_BLAD1_RXD")
	)
	(segment
		(start 26.40203 -230.42753)
		(end 26.40203 -219.133674)
		(width 0.127)
		(layer "In5.Cu")
		(net "T3_BLAD1_RXD")
	)
	(segment
		(start 29.741876 -178.162458)
		(end 61.717428 -178.162458)
		(width 0.127)
		(layer "In5.Cu")
		(net "T3_BLAD1_RXD")
	)
	(segment
		(start 91.522296 -161.192464)
		(end 100.111052 -152.603708)
		(width 0.127)
		(layer "In5.Cu")
		(net "T3_BLAD1_RXD")
	)
	(segment
		(start 26.221944 -181.68239)
		(end 29.741876 -178.162458)
		(width 0.127)
		(layer "In5.Cu")
		(net "T3_BLAD1_RXD")
	)
	(segment
		(start 92.198698 -100.432108)
		(end 88.70569 -100.432108)
		(width 0.127)
		(layer "In5.Cu")
		(net "T3_BLAD1_RXD")
	)
	(segment
		(start 86.90991 -98.636328)
		(end 86.90991 -96.44507)
		(width 0.127)
		(layer "In5.Cu")
		(net "T3_BLAD1_RXD")
	)
	(segment
		(start 18.003774 -240.667794)
		(end 21.617686 -237.053882)
		(width 0.127)
		(layer "In5.Cu")
		(net "T3_BLAD1_RXD")
	)
	(segment
		(start 27.140408 -200.495408)
		(end 25.161494 -198.516494)
		(width 0.127)
		(layer "In5.Cu")
		(net "T3_BLAD1_RXD")
	)
	(segment
		(start 21.617686 -235.211874)
		(end 26.40203 -230.42753)
		(width 0.127)
		(layer "In5.Cu")
		(net "T3_BLAD1_RXD")
	)
	(segment
		(start 21.617686 -237.053882)
		(end 21.617686 -235.211874)
		(width 0.127)
		(layer "In5.Cu")
		(net "T3_BLAD1_RXD")
	)
	(segment
		(start 100.111052 -108.344462)
		(end 95.108268 -103.341678)
		(width 0.127)
		(layer "In5.Cu")
		(net "T3_BLAD1_RXD")
	)
	(segment
		(start 8.448802 -240.670588)
		(end 8.451596 -240.667794)
		(width 0.127)
		(layer "In5.Cu")
		(net "T3_BLAD1_RXD")
	)
	(segment
		(start 25.161494 -198.516494)
		(end 25.161494 -191.826134)
		(width 0.127)
		(layer "In5.Cu")
		(net "T3_BLAD1_RXD")
	)
	(segment
		(start 25.161494 -191.826134)
		(end 26.221944 -190.765684)
		(width 0.127)
		(layer "In5.Cu")
		(net "T3_BLAD1_RXD")
	)
	(segment
		(start 78.687422 -161.192464)
		(end 91.522296 -161.192464)
		(width 0.127)
		(layer "In5.Cu")
		(net "T3_BLAD1_RXD")
	)
	(segment
		(start 26.221944 -190.765684)
		(end 26.221944 -181.68239)
		(width 0.127)
		(layer "In5.Cu")
		(net "T3_BLAD1_RXD")
	)
	(segment
		(start 95.108268 -103.341678)
		(end 92.198698 -100.432108)
		(width 0.127)
		(layer "In5.Cu")
		(net "T3_BLAD1_RXD")
	)
	(segment
		(start 100.111052 -152.603708)
		(end 100.111052 -108.344462)
		(width 0.127)
		(layer "In5.Cu")
		(net "T3_BLAD1_RXD")
	)
	(segment
		(start 26.40203 -219.133674)
		(end 27.140408 -218.395296)
		(width 0.127)
		(layer "In5.Cu")
		(net "T3_BLAD1_RXD")
	)
	(segment
		(start 7.264908 -323.669914)
		(end 1.949958 -323.669914)
		(width 0.1524)
		(layer "F.Cu")
		(net "FAN2_TACH")
	)
	(segment
		(start 9.764522 -322.945506)
		(end 7.989316 -322.945506)
		(width 0.1524)
		(layer "F.Cu")
		(net "FAN2_TACH")
	)
	(segment
		(start 13.055092 -321.89166)
		(end 10.818368 -321.89166)
		(width 0.1524)
		(layer "F.Cu")
		(net "FAN2_TACH")
	)
	(segment
		(start 7.989316 -322.945506)
		(end 7.264908 -323.669914)
		(width 0.1524)
		(layer "F.Cu")
		(net "FAN2_TACH")
	)
	(segment
		(start 10.818368 -321.89166)
		(end 9.764522 -322.945506)
		(width 0.1524)
		(layer "F.Cu")
		(net "FAN2_TACH")
	)
	(segment
		(start 11.398758 -343.137744)
		(end 11.398758 -325.855838)
		(width 0.1524)
		(layer "B.Cu")
		(net "FAN2_TACH")
	)
	(segment
		(start 13.615924 -446.922398)
		(end 13.615924 -418.032438)
		(width 0.1524)
		(layer "B.Cu")
		(net "FAN2_TACH")
	)
	(segment
		(start 6.296152 -321.543172)
		(end 4.16941 -323.669914)
		(width 0.1524)
		(layer "B.Cu")
		(net "FAN2_TACH")
	)
	(segment
		(start 11.398758 -325.855838)
		(end 10.333736 -324.790816)
		(width 0.1524)
		(layer "B.Cu")
		(net "FAN2_TACH")
	)
	(segment
		(start 23.659084 -407.989278)
		(end 23.659084 -381.907796)
		(width 0.1524)
		(layer "B.Cu")
		(net "FAN2_TACH")
	)
	(segment
		(start 10.333736 -324.790816)
		(end 10.333736 -322.031614)
		(width 0.1524)
		(layer "B.Cu")
		(net "FAN2_TACH")
	)
	(segment
		(start 10.333736 -322.031614)
		(end 9.158224 -320.856102)
		(width 0.1524)
		(layer "B.Cu")
		(net "FAN2_TACH")
	)
	(segment
		(start 13.653262 -371.901974)
		(end 13.653262 -345.392248)
		(width 0.1524)
		(layer "B.Cu")
		(net "FAN2_TACH")
	)
	(segment
		(start 9.158224 -320.856102)
		(end 7.787894 -320.856102)
		(width 0.1524)
		(layer "B.Cu")
		(net "FAN2_TACH")
	)
	(segment
		(start 23.659084 -381.907796)
		(end 13.653262 -371.901974)
		(width 0.1524)
		(layer "B.Cu")
		(net "FAN2_TACH")
	)
	(segment
		(start 13.653262 -345.392248)
		(end 11.398758 -343.137744)
		(width 0.1524)
		(layer "B.Cu")
		(net "FAN2_TACH")
	)
	(segment
		(start 7.100824 -321.543172)
		(end 6.296152 -321.543172)
		(width 0.1524)
		(layer "B.Cu")
		(net "FAN2_TACH")
	)
	(segment
		(start 13.615924 -418.032438)
		(end 23.659084 -407.989278)
		(width 0.1524)
		(layer "B.Cu")
		(net "FAN2_TACH")
	)
	(segment
		(start 4.16941 -323.669914)
		(end 1.949958 -323.669914)
		(width 0.1524)
		(layer "B.Cu")
		(net "FAN2_TACH")
	)
	(segment
		(start 11.444224 -449.094098)
		(end 13.615924 -446.922398)
		(width 0.1524)
		(layer "B.Cu")
		(net "FAN2_TACH")
	)
	(segment
		(start 7.787894 -320.856102)
		(end 7.100824 -321.543172)
		(width 0.1524)
		(layer "B.Cu")
		(net "FAN2_TACH")
	)
	(via
		(at 82.121502 -106.251502)
		(size 0.508)
		(drill 0.254)
		(layers "F.Cu" "B.Cu")
		(net "T3_BLAD4_RXD")
	)
	(segment
		(start 15.50289 -234.147614)
		(end 9.162796 -234.147614)
		(width 0.127)
		(layer "In2.Cu")
		(net "T3_BLAD4_RXD")
	)
	(segment
		(start 24.501602 -223.814386)
		(end 19.409918 -228.90607)
		(width 0.127)
		(layer "In2.Cu")
		(net "T3_BLAD4_RXD")
	)
	(segment
		(start 83.766914 -94.851728)
		(end 83.766914 -100.98278)
		(width 0.127)
		(layer "In2.Cu")
		(net "T3_BLAD4_RXD")
	)
	(segment
		(start 86.170262 -92.44838)
		(end 83.766914 -94.851728)
		(width 0.127)
		(layer "In2.Cu")
		(net "T3_BLAD4_RXD")
	)
	(segment
		(start 20.97405 -196.977254)
		(end 24.501602 -200.504806)
		(width 0.127)
		(layer "In2.Cu")
		(net "T3_BLAD4_RXD")
	)
	(segment
		(start 82.121502 -106.251502)
		(end 82.121502 -113.138458)
		(width 0.127)
		(layer "In2.Cu")
		(net "T3_BLAD4_RXD")
	)
	(segment
		(start 77.506068 -147.506944)
		(end 77.506068 -157.211014)
		(width 0.127)
		(layer "In2.Cu")
		(net "T3_BLAD4_RXD")
	)
	(segment
		(start 8.685784 -233.670602)
		(end 6.448806 -233.670602)
		(width 0.127)
		(layer "In2.Cu")
		(net "T3_BLAD4_RXD")
	)
	(segment
		(start 26.468832 -176.138332)
		(end 20.97405 -181.633114)
		(width 0.127)
		(layer "In2.Cu")
		(net "T3_BLAD4_RXD")
	)
	(segment
		(start 84.125816 -115.142772)
		(end 84.125816 -136.656826)
		(width 0.127)
		(layer "In2.Cu")
		(net "T3_BLAD4_RXD")
	)
	(segment
		(start 90.53322 -92.44838)
		(end 86.170262 -92.44838)
		(width 0.127)
		(layer "In2.Cu")
		(net "T3_BLAD4_RXD")
	)
	(segment
		(start 20.97405 -181.633114)
		(end 20.97405 -196.977254)
		(width 0.127)
		(layer "In2.Cu")
		(net "T3_BLAD4_RXD")
	)
	(segment
		(start 82.121502 -113.138458)
		(end 84.125816 -115.142772)
		(width 0.127)
		(layer "In2.Cu")
		(net "T3_BLAD4_RXD")
	)
	(segment
		(start 83.368642 -137.414)
		(end 83.368642 -141.98473)
		(width 0.127)
		(layer "In2.Cu")
		(net "T3_BLAD4_RXD")
	)
	(segment
		(start 84.125816 -136.656826)
		(end 83.368642 -137.414)
		(width 0.127)
		(layer "In2.Cu")
		(net "T3_BLAD4_RXD")
	)
	(segment
		(start 24.501602 -200.504806)
		(end 24.501602 -223.814386)
		(width 0.127)
		(layer "In2.Cu")
		(net "T3_BLAD4_RXD")
	)
	(segment
		(start 83.766914 -100.98278)
		(end 82.121502 -102.628192)
		(width 0.127)
		(layer "In2.Cu")
		(net "T3_BLAD4_RXD")
	)
	(segment
		(start 81.611724 -143.741648)
		(end 81.271364 -143.741648)
		(width 0.127)
		(layer "In2.Cu")
		(net "T3_BLAD4_RXD")
	)
	(segment
		(start 91.98991 -93.90507)
		(end 90.53322 -92.44838)
		(width 0.127)
		(layer "In2.Cu")
		(net "T3_BLAD4_RXD")
	)
	(segment
		(start 19.409918 -230.240586)
		(end 15.50289 -234.147614)
		(width 0.127)
		(layer "In2.Cu")
		(net "T3_BLAD4_RXD")
	)
	(segment
		(start 77.506068 -157.211014)
		(end 58.57875 -176.138332)
		(width 0.127)
		(layer "In2.Cu")
		(net "T3_BLAD4_RXD")
	)
	(segment
		(start 19.409918 -228.90607)
		(end 19.409918 -230.240586)
		(width 0.127)
		(layer "In2.Cu")
		(net "T3_BLAD4_RXD")
	)
	(segment
		(start 9.162796 -234.147614)
		(end 8.685784 -233.670602)
		(width 0.127)
		(layer "In2.Cu")
		(net "T3_BLAD4_RXD")
	)
	(segment
		(start 58.57875 -176.138332)
		(end 26.468832 -176.138332)
		(width 0.127)
		(layer "In2.Cu")
		(net "T3_BLAD4_RXD")
	)
	(segment
		(start 83.368642 -141.98473)
		(end 81.611724 -143.741648)
		(width 0.127)
		(layer "In2.Cu")
		(net "T3_BLAD4_RXD")
	)
	(segment
		(start 81.271364 -143.741648)
		(end 77.506068 -147.506944)
		(width 0.127)
		(layer "In2.Cu")
		(net "T3_BLAD4_RXD")
	)
	(segment
		(start 82.121502 -102.628192)
		(end 82.121502 -106.251502)
		(width 0.127)
		(layer "In2.Cu")
		(net "T3_BLAD4_RXD")
	)
	(via
		(at 85.222588 -102.624382)
		(size 0.508)
		(drill 0.254)
		(layers "F.Cu" "B.Cu")
		(net "T3_BLAD2_TXD")
	)
	(segment
		(start 84.393532 -142.409672)
		(end 84.393532 -137.838942)
		(width 0.127)
		(layer "In2.Cu")
		(net "T3_BLAD2_TXD")
	)
	(segment
		(start 78.530958 -157.635956)
		(end 78.530958 -147.931886)
		(width 0.127)
		(layer "In2.Cu")
		(net "T3_BLAD2_TXD")
	)
	(segment
		(start 85.150706 -114.71783)
		(end 84.273644 -113.840768)
		(width 0.127)
		(layer "In2.Cu")
		(net "T3_BLAD2_TXD")
	)
	(segment
		(start 84.273644 -113.840768)
		(end 84.273644 -103.573326)
		(width 0.127)
		(layer "In2.Cu")
		(net "T3_BLAD2_TXD")
	)
	(segment
		(start 90.1319 -97.71507)
		(end 90.71991 -97.71507)
		(width 0.127)
		(layer "In2.Cu")
		(net "T3_BLAD2_TXD")
	)
	(segment
		(start 59.003692 -177.163222)
		(end 78.530958 -157.635956)
		(width 0.127)
		(layer "In2.Cu")
		(net "T3_BLAD2_TXD")
	)
	(segment
		(start 20.59178 -229.438962)
		(end 25.603708 -224.427034)
		(width 0.127)
		(layer "In2.Cu")
		(net "T3_BLAD2_TXD")
	)
	(segment
		(start 25.603708 -224.427034)
		(end 25.603708 -199.792844)
		(width 0.127)
		(layer "In2.Cu")
		(net "T3_BLAD2_TXD")
	)
	(segment
		(start 6.448806 -237.670594)
		(end 13.787628 -237.670594)
		(width 0.127)
		(layer "In2.Cu")
		(net "T3_BLAD2_TXD")
	)
	(segment
		(start 13.787628 -237.670594)
		(end 20.59178 -230.866442)
		(width 0.127)
		(layer "In2.Cu")
		(net "T3_BLAD2_TXD")
	)
	(segment
		(start 82.036666 -144.766538)
		(end 84.393532 -142.409672)
		(width 0.127)
		(layer "In2.Cu")
		(net "T3_BLAD2_TXD")
	)
	(segment
		(start 27.383232 -177.163222)
		(end 59.003692 -177.163222)
		(width 0.127)
		(layer "In2.Cu")
		(net "T3_BLAD2_TXD")
	)
	(segment
		(start 85.150706 -137.081768)
		(end 85.150706 -114.71783)
		(width 0.127)
		(layer "In2.Cu")
		(net "T3_BLAD2_TXD")
	)
	(segment
		(start 84.393532 -137.838942)
		(end 85.150706 -137.081768)
		(width 0.127)
		(layer "In2.Cu")
		(net "T3_BLAD2_TXD")
	)
	(segment
		(start 20.59178 -230.866442)
		(end 20.59178 -229.438962)
		(width 0.127)
		(layer "In2.Cu")
		(net "T3_BLAD2_TXD")
	)
	(segment
		(start 22.29739 -196.486526)
		(end 22.29739 -182.249064)
		(width 0.127)
		(layer "In2.Cu")
		(net "T3_BLAD2_TXD")
	)
	(segment
		(start 84.273644 -103.573326)
		(end 85.222588 -102.624382)
		(width 0.127)
		(layer "In2.Cu")
		(net "T3_BLAD2_TXD")
	)
	(segment
		(start 22.29739 -182.249064)
		(end 27.383232 -177.163222)
		(width 0.127)
		(layer "In2.Cu")
		(net "T3_BLAD2_TXD")
	)
	(segment
		(start 81.696306 -144.766538)
		(end 82.036666 -144.766538)
		(width 0.127)
		(layer "In2.Cu")
		(net "T3_BLAD2_TXD")
	)
	(segment
		(start 85.222588 -102.624382)
		(end 90.1319 -97.71507)
		(width 0.127)
		(layer "In2.Cu")
		(net "T3_BLAD2_TXD")
	)
	(segment
		(start 25.603708 -199.792844)
		(end 22.29739 -196.486526)
		(width 0.127)
		(layer "In2.Cu")
		(net "T3_BLAD2_TXD")
	)
	(segment
		(start 78.530958 -147.931886)
		(end 81.696306 -144.766538)
		(width 0.127)
		(layer "In2.Cu")
		(net "T3_BLAD2_TXD")
	)
	(segment
		(start 10.495026 -325.064882)
		(end 13.063728 -325.064882)
		(width 0.1524)
		(layer "F.Cu")
		(net "FAN1_TACH")
	)
	(segment
		(start 7.721346 -324.911974)
		(end 10.342118 -324.911974)
		(width 0.1524)
		(layer "F.Cu")
		(net "FAN1_TACH")
	)
	(segment
		(start 7.168134 -325.465186)
		(end 7.721346 -324.911974)
		(width 0.1524)
		(layer "F.Cu")
		(net "FAN1_TACH")
	)
	(segment
		(start 4.745228 -325.465186)
		(end 7.168134 -325.465186)
		(width 0.1524)
		(layer "F.Cu")
		(net "FAN1_TACH")
	)
	(segment
		(start 10.342118 -324.911974)
		(end 10.495026 -325.064882)
		(width 0.1524)
		(layer "F.Cu")
		(net "FAN1_TACH")
	)
	(segment
		(start 3.949954 -324.669912)
		(end 4.745228 -325.465186)
		(width 0.1524)
		(layer "F.Cu")
		(net "FAN1_TACH")
	)
	(segment
		(start 10.906252 -388.696454)
		(end 10.906252 -372.490238)
		(width 0.1524)
		(layer "B.Cu")
		(net "FAN1_TACH")
	)
	(segment
		(start 4.769866 -326.335898)
		(end 3.949954 -325.515986)
		(width 0.1524)
		(layer "B.Cu")
		(net "FAN1_TACH")
	)
	(segment
		(start 8.60552 -330.61021)
		(end 8.12038 -330.61021)
		(width 0.1524)
		(layer "B.Cu")
		(net "FAN1_TACH")
	)
	(segment
		(start 10.03554 -463.102706)
		(end 4.167124 -463.102706)
		(width 0.1524)
		(layer "B.Cu")
		(net "FAN1_TACH")
	)
	(segment
		(start 3.949954 -325.515986)
		(end 3.949954 -324.669912)
		(width 0.1524)
		(layer "B.Cu")
		(net "FAN1_TACH")
	)
	(segment
		(start 10.906252 -372.490238)
		(end 11.871198 -371.525292)
		(width 0.1524)
		(layer "B.Cu")
		(net "FAN1_TACH")
	)
	(segment
		(start 9.520428 -344.400632)
		(end 9.520428 -331.525118)
		(width 0.1524)
		(layer "B.Cu")
		(net "FAN1_TACH")
	)
	(segment
		(start 2.638806 -461.574388)
		(end 2.638806 -448.289934)
		(width 0.1524)
		(layer "B.Cu")
		(net "FAN1_TACH")
	)
	(segment
		(start 11.444224 -461.694022)
		(end 10.03554 -463.102706)
		(width 0.1524)
		(layer "B.Cu")
		(net "FAN1_TACH")
	)
	(segment
		(start 19.09445 -408.082496)
		(end 19.09445 -396.884652)
		(width 0.1524)
		(layer "B.Cu")
		(net "FAN1_TACH")
	)
	(segment
		(start 19.09445 -396.884652)
		(end 10.906252 -388.696454)
		(width 0.1524)
		(layer "B.Cu")
		(net "FAN1_TACH")
	)
	(segment
		(start 2.638806 -448.289934)
		(end 4.338828 -446.589912)
		(width 0.1524)
		(layer "B.Cu")
		(net "FAN1_TACH")
	)
	(segment
		(start 11.871198 -346.751402)
		(end 9.520428 -344.400632)
		(width 0.1524)
		(layer "B.Cu")
		(net "FAN1_TACH")
	)
	(segment
		(start 4.338828 -446.589912)
		(end 4.338828 -422.838118)
		(width 0.1524)
		(layer "B.Cu")
		(net "FAN1_TACH")
	)
	(segment
		(start 7.09168 -329.58151)
		(end 6.121908 -329.58151)
		(width 0.1524)
		(layer "B.Cu")
		(net "FAN1_TACH")
	)
	(segment
		(start 4.338828 -422.838118)
		(end 19.09445 -408.082496)
		(width 0.1524)
		(layer "B.Cu")
		(net "FAN1_TACH")
	)
	(segment
		(start 11.871198 -371.525292)
		(end 11.871198 -346.751402)
		(width 0.1524)
		(layer "B.Cu")
		(net "FAN1_TACH")
	)
	(segment
		(start 8.12038 -330.61021)
		(end 7.09168 -329.58151)
		(width 0.1524)
		(layer "B.Cu")
		(net "FAN1_TACH")
	)
	(segment
		(start 4.167124 -463.102706)
		(end 2.638806 -461.574388)
		(width 0.1524)
		(layer "B.Cu")
		(net "FAN1_TACH")
	)
	(segment
		(start 4.769866 -328.229468)
		(end 4.769866 -326.335898)
		(width 0.1524)
		(layer "B.Cu")
		(net "FAN1_TACH")
	)
	(segment
		(start 6.121908 -329.58151)
		(end 4.769866 -328.229468)
		(width 0.1524)
		(layer "B.Cu")
		(net "FAN1_TACH")
	)
	(segment
		(start 9.520428 -331.525118)
		(end 8.60552 -330.61021)
		(width 0.1524)
		(layer "B.Cu")
		(net "FAN1_TACH")
	)
	(segment
		(start 41.103804 -192.216278)
		(end 40.3733 -192.216278)
		(width 0.508)
		(layer "F.Cu")
		(net "GND")
	)
	(segment
		(start 78.397354 -15.339822)
		(end 78.397354 -16.199612)
		(width 0.508)
		(layer "F.Cu")
		(net "GND")
	)
	(segment
		(start 25.474422 -367.771426)
		(end 24.75611 -367.771426)
		(width 0.4572)
		(layer "F.Cu")
		(net "GND")
	)
	(segment
		(start 79.524606 -15.339822)
		(end 79.524606 -16.199612)
		(width 0.508)
		(layer "F.Cu")
		(net "GND")
	)
	(segment
		(start 72.478392 -150.358348)
		(end 72.478392 -151.26716)
		(width 0.508)
		(layer "F.Cu")
		(net "GND")
	)
	(segment
		(start 25.668224 -181.847998)
		(end 25.035256 -181.847998)
		(width 0.508)
		(layer "F.Cu")
		(net "GND")
	)
	(segment
		(start 40.275002 -461.170274)
		(end 41.4655 -461.1751)
		(width 0.508)
		(layer "F.Cu")
		(net "GND")
	)
	(segment
		(start 73.57745 -396.862554)
		(end 73.57745 -395.785594)
		(width 0.508)
		(layer "F.Cu")
		(net "GND")
	)
	(segment
		(start 82.499962 -504.705874)
		(end 82.499962 -505.529088)
		(width 0.508)
		(layer "F.Cu")
		(net "GND")
	)
	(segment
		(start 68.727066 -353.908614)
		(end 68.727066 -352.965004)
		(width 0.508)
		(layer "F.Cu")
		(net "GND")
	)
	(segment
		(start 67.14109 -206.29118)
		(end 68.592192 -206.29118)
		(width 0.4572)
		(layer "F.Cu")
		(net "GND")
	)
	(segment
		(start 41.245536 -14.412976)
		(end 40.557704 -14.412976)
		(width 0.508)
		(layer "F.Cu")
		(net "GND")
	)
	(segment
		(start 70.678548 -486.89133)
		(end 70.678548 -485.985058)
		(width 0.508)
		(layer "F.Cu")
		(net "GND")
	)
	(segment
		(start 46.808136 -239.669066)
		(end 46.808136 -240.876074)
		(width 0.508)
		(layer "F.Cu")
		(net "GND")
	)
	(segment
		(start 46.785784 -244.518434)
		(end 46.785784 -245.712234)
		(width 0.508)
		(layer "F.Cu")
		(net "GND")
	)
	(segment
		(start 26.88463 -5.10032)
		(end 26.88463 -5.61086)
		(width 0.4572)
		(layer "F.Cu")
		(net "GND")
	)
	(segment
		(start 40.334692 -374.14708)
		(end 40.792908 -374.14708)
		(width 0.508)
		(layer "F.Cu")
		(net "GND")
	)
	(segment
		(start 13.820902 -318.358012)
		(end 14.594332 -318.358012)
		(width 0.4572)
		(layer "F.Cu")
		(net "GND")
	)
	(segment
		(start 25.703784 -189.265306)
		(end 24.923496 -189.265306)
		(width 0.4572)
		(layer "F.Cu")
		(net "GND")
	)
	(segment
		(start 73.532746 -442.44641)
		(end 73.532746 -441.63869)
		(width 0.508)
		(layer "F.Cu")
		(net "GND")
	)
	(segment
		(start 71.390764 -460.977234)
		(end 71.390764 -462.170526)
		(width 0.508)
		(layer "F.Cu")
		(net "GND")
	)
	(segment
		(start 40.959278 -106.221276)
		(end 40.959024 -106.22153)
		(width 0.508)
		(layer "F.Cu")
		(net "GND")
	)
	(segment
		(start 25.702006 -276.12213)
		(end 24.625046 -276.12213)
		(width 0.508)
		(layer "F.Cu")
		(net "GND")
	)
	(segment
		(start 72.81291 -105.15981)
		(end 72.81291 -106.132376)
		(width 0.508)
		(layer "F.Cu")
		(net "GND")
	)
	(segment
		(start 72.185276 -307.419756)
		(end 72.185276 -306.521358)
		(width 0.508)
		(layer "F.Cu")
		(net "GND")
	)
	(segment
		(start 75.059286 -149.513798)
		(end 75.059286 -150.42261)
		(width 0.508)
		(layer "F.Cu")
		(net "GND")
	)
	(segment
		(start 72.559164 -262.860028)
		(end 72.559164 -261.915148)
		(width 0.508)
		(layer "F.Cu")
		(net "GND")
	)
	(segment
		(start 25.457658 -360.550968)
		(end 24.84755 -360.550968)
		(width 0.508)
		(layer "F.Cu")
		(net "GND")
	)
	(segment
		(start 40.221408 -18.414238)
		(end 41.082468 -18.414238)
		(width 0.508)
		(layer "F.Cu")
		(net "GND")
	)
	(segment
		(start 40.249602 -17.30502)
		(end 41.296844 -17.30502)
		(width 0.508)
		(layer "F.Cu")
		(net "GND")
	)
	(segment
		(start 25.702006 -277.377144)
		(end 24.624792 -277.377144)
		(width 0.508)
		(layer "F.Cu")
		(net "GND")
	)
	(segment
		(start 26.78557 -373.44858)
		(end 26.76906 -373.43207)
		(width 0.508)
		(layer "F.Cu")
		(net "GND")
	)
	(segment
		(start 72.284082 -442.44641)
		(end 72.284082 -441.57011)
		(width 0.508)
		(layer "F.Cu")
		(net "GND")
	)
	(segment
		(start 70.85457 -175.545496)
		(end 70.85457 -174.546768)
		(width 0.508)
		(layer "F.Cu")
		(net "GND")
	)
	(segment
		(start 74.0537 -460.132684)
		(end 74.0537 -460.970884)
		(width 0.508)
		(layer "F.Cu")
		(net "GND")
	)
	(segment
		(start 26.547572 -108.230416)
		(end 25.90546 -108.230416)
		(width 0.4572)
		(layer "F.Cu")
		(net "GND")
	)
	(segment
		(start 69.726556 -175.545496)
		(end 69.726556 -174.546768)
		(width 0.508)
		(layer "F.Cu")
		(net "GND")
	)
	(segment
		(start 72.403716 -396.862554)
		(end 72.403716 -395.785594)
		(width 0.508)
		(layer "F.Cu")
		(net "GND")
	)
	(segment
		(start 46.825662 -253.125732)
		(end 46.825662 -254.395224)
		(width 0.508)
		(layer "F.Cu")
		(net "GND")
	)
	(segment
		(start 25.668224 -187.950348)
		(end 24.750522 -187.950348)
		(width 0.508)
		(layer "F.Cu")
		(net "GND")
	)
	(segment
		(start 73.63333 -86.745318)
		(end 73.63333 -85.772752)
		(width 0.508)
		(layer "F.Cu")
		(net "GND")
	)
	(segment
		(start 72.157844 -416.723322)
		(end 72.157844 -417.800282)
		(width 0.508)
		(layer "F.Cu")
		(net "GND")
	)
	(segment
		(start 27.452828 -10.617962)
		(end 27.452828 -9.880346)
		(width 0.4572)
		(layer "F.Cu")
		(net "GND")
	)
	(segment
		(start 71.871332 -283.400754)
		(end 71.871332 -284.345634)
		(width 0.508)
		(layer "F.Cu")
		(net "GND")
	)
	(segment
		(start 74.626978 -307.419756)
		(end 74.626978 -306.521358)
		(width 0.508)
		(layer "F.Cu")
		(net "GND")
	)
	(segment
		(start 79.898748 -505.309378)
		(end 79.898748 -506.498098)
		(width 0.508)
		(layer "F.Cu")
		(net "GND")
	)
	(segment
		(start 70.997572 -353.908614)
		(end 70.997572 -352.943922)
		(width 0.508)
		(layer "F.Cu")
		(net "GND")
	)
	(segment
		(start 40.989758 -103.52405)
		(end 40.25646 -103.52405)
		(width 0.508)
		(layer "F.Cu")
		(net "GND")
	)
	(segment
		(start 71.423276 -238.108744)
		(end 71.423276 -239.126268)
		(width 0.508)
		(layer "F.Cu")
		(net "GND")
	)
	(segment
		(start 26.450798 -19.859244)
		(end 26.445464 -19.864578)
		(width 0.508)
		(layer "F.Cu")
		(net "GND")
	)
	(segment
		(start 70.278244 -220.025722)
		(end 70.278244 -219.071952)
		(width 0.508)
		(layer "F.Cu")
		(net "GND")
	)
	(segment
		(start 41.427146 -370.095526)
		(end 40.704008 -370.099336)
		(width 0.508)
		(layer "F.Cu")
		(net "GND")
	)
	(segment
		(start 25.531572 -99.36988)
		(end 24.88819 -99.36988)
		(width 0.508)
		(layer "F.Cu")
		(net "GND")
	)
	(segment
		(start 74.804524 -86.745318)
		(end 74.804524 -85.772752)
		(width 0.508)
		(layer "F.Cu")
		(net "GND")
	)
	(segment
		(start 68.457064 -131.043426)
		(end 68.457064 -130.134614)
		(width 0.508)
		(layer "F.Cu")
		(net "GND")
	)
	(segment
		(start 72.611996 -238.108744)
		(end 72.611996 -239.126268)
		(width 0.508)
		(layer "F.Cu")
		(net "GND")
	)
	(segment
		(start 71.392796 -86.745318)
		(end 71.392796 -85.772752)
		(width 0.508)
		(layer "F.Cu")
		(net "GND")
	)
	(segment
		(start 73.199752 -282.556204)
		(end 73.199752 -283.501084)
		(width 0.508)
		(layer "F.Cu")
		(net "GND")
	)
	(segment
		(start 71.96836 -175.545496)
		(end 71.96836 -174.546768)
		(width 0.508)
		(layer "F.Cu")
		(net "GND")
	)
	(segment
		(start 26.445464 -19.864578)
		(end 26.445464 -20.969478)
		(width 0.508)
		(layer "F.Cu")
		(net "GND")
	)
	(segment
		(start 40.959278 -106.900726)
		(end 40.959278 -106.221276)
		(width 0.508)
		(layer "F.Cu")
		(net "GND")
	)
	(segment
		(start 71.518526 -106.00436)
		(end 71.518526 -106.976926)
		(width 0.508)
		(layer "F.Cu")
		(net "GND")
	)
	(segment
		(start 71.810118 -486.89133)
		(end 71.810118 -485.985058)
		(width 0.508)
		(layer "F.Cu")
		(net "GND")
	)
	(segment
		(start 25.457658 -361.78236)
		(end 24.740362 -361.78236)
		(width 0.508)
		(layer "F.Cu")
		(net "GND")
	)
	(segment
		(start 16.21028 -146.578828)
		(end 16.21028 -147.232116)
		(width 0.508)
		(layer "F.Cu")
		(net "GND")
	)
	(segment
		(start 40.198802 -197.274942)
		(end 40.471344 -197.274942)
		(width 0.508)
		(layer "F.Cu")
		(net "GND")
	)
	(segment
		(start 46.311566 -260.355588)
		(end 46.779942 -260.355588)
		(width 0.508)
		(layer "F.Cu")
		(net "GND")
	)
	(segment
		(start 74.709782 -326.922638)
		(end 74.709782 -327.821036)
		(width 0.508)
		(layer "F.Cu")
		(net "GND")
	)
	(segment
		(start 72.19696 -353.908868)
		(end 72.19696 -352.944176)
		(width 0.508)
		(layer "F.Cu")
		(net "GND")
	)
	(segment
		(start 70.260718 -60.563506)
		(end 70.260718 -61.3156)
		(width 0.508)
		(layer "F.Cu")
		(net "GND")
	)
	(segment
		(start 16.017494 -330.097384)
		(end 16.017494 -329.263248)
		(width 0.4572)
		(layer "F.Cu")
		(net "GND")
	)
	(segment
		(start 25.597612 -8.344662)
		(end 24.743918 -8.344662)
		(width 0.508)
		(layer "F.Cu")
		(net "GND")
	)
	(segment
		(start 25.531572 -95.65132)
		(end 24.774144 -95.65132)
		(width 0.508)
		(layer "F.Cu")
		(net "GND")
	)
	(segment
		(start 26.843736 -285.030164)
		(end 26.843736 -285.983426)
		(width 0.508)
		(layer "F.Cu")
		(net "GND")
	)
	(segment
		(start 73.687178 -262.860028)
		(end 73.687178 -261.915148)
		(width 0.508)
		(layer "F.Cu")
		(net "GND")
	)
	(segment
		(start 2.965958 -146.294348)
		(end 2.965958 -147.006564)
		(width 0.508)
		(layer "F.Cu")
		(net "GND")
	)
	(segment
		(start 25.725628 -278.486362)
		(end 25.057608 -278.486362)
		(width 0.4572)
		(layer "F.Cu")
		(net "GND")
	)
	(segment
		(start 70.658736 -193.982594)
		(end 70.658736 -194.981322)
		(width 0.508)
		(layer "F.Cu")
		(net "GND")
	)
	(segment
		(start 69.133974 -220.025722)
		(end 69.133974 -219.037916)
		(width 0.508)
		(layer "F.Cu")
		(net "GND")
	)
	(segment
		(start 73.512934 -415.878772)
		(end 73.512934 -416.955732)
		(width 0.508)
		(layer "F.Cu")
		(net "GND")
	)
	(segment
		(start 25.825958 -447.250058)
		(end 25.163272 -447.250058)
		(width 0.508)
		(layer "F.Cu")
		(net "GND")
	)
	(segment
		(start 71.405496 -262.860028)
		(end 71.405496 -261.915148)
		(width 0.508)
		(layer "F.Cu")
		(net "GND")
	)
	(segment
		(start 46.896528 -248.705116)
		(end 46.896528 -249.789442)
		(width 0.508)
		(layer "F.Cu")
		(net "GND")
	)
	(segment
		(start 26.528268 -196.6214)
		(end 25.715976 -196.6214)
		(width 0.4572)
		(layer "F.Cu")
		(net "GND")
	)
	(segment
		(start 25.457658 -366.710722)
		(end 24.636222 -366.710722)
		(width 0.508)
		(layer "F.Cu")
		(net "GND")
	)
	(segment
		(start 69.774816 -442.44641)
		(end 69.774816 -441.501784)
		(width 0.508)
		(layer "F.Cu")
		(net "GND")
	)
	(segment
		(start 69.549518 -486.89133)
		(end 69.549518 -485.985058)
		(width 0.508)
		(layer "F.Cu")
		(net "GND")
	)
	(segment
		(start 73.914508 -105.15981)
		(end 73.914508 -106.132376)
		(width 0.508)
		(layer "F.Cu")
		(net "GND")
	)
	(segment
		(start 14.9225 -146.562064)
		(end 14.9225 -147.231862)
		(width 0.508)
		(layer "F.Cu")
		(net "GND")
	)
	(segment
		(start 73.353676 -472.101672)
		(end 74.575924 -472.101672)
		(width 0.508)
		(layer "F.Cu")
		(net "GND")
	)
	(segment
		(start 70.095364 -238.953294)
		(end 70.095364 -239.970818)
		(width 0.508)
		(layer "F.Cu")
		(net "GND")
	)
	(segment
		(start 69.116194 -117.627146)
		(end 69.847714 -117.627146)
		(width 0.4572)
		(layer "F.Cu")
		(net "GND")
	)
	(segment
		(start 71.044562 -442.44641)
		(end 71.044562 -441.553092)
		(width 0.508)
		(layer "F.Cu")
		(net "GND")
	)
	(segment
		(start 72.590152 -220.025722)
		(end 72.590152 -219.008198)
		(width 0.508)
		(layer "F.Cu")
		(net "GND")
	)
	(segment
		(start 26.65476 -11.75639)
		(end 26.65476 -11.980418)
		(width 0.4572)
		(layer "F.Cu")
		(net "GND")
	)
	(segment
		(start 71.815198 -193.982594)
		(end 71.815198 -194.981322)
		(width 0.508)
		(layer "F.Cu")
		(net "GND")
	)
	(segment
		(start 40.51427 -371.513354)
		(end 41.281096 -371.513354)
		(width 0.508)
		(layer "F.Cu")
		(net "GND")
	)
	(segment
		(start 40.30091 -194.114674)
		(end 41.057576 -194.114674)
		(width 0.508)
		(layer "F.Cu")
		(net "GND")
	)
	(segment
		(start 14.76502 -396.021052)
		(end 13.743432 -396.021052)
		(width 0.508)
		(layer "F.Cu")
		(net "GND")
	)
	(segment
		(start 46.765972 -257.889502)
		(end 46.765972 -258.89712)
		(width 0.508)
		(layer "F.Cu")
		(net "GND")
	)
	(segment
		(start 18.253964 -334.086962)
		(end 19.17065 -334.086962)
		(width 0.508)
		(layer "F.Cu")
		(net "GND")
	)
	(segment
		(start 73.00468 -42.231056)
		(end 73.00468 -41.28516)
		(width 0.508)
		(layer "F.Cu")
		(net "GND")
	)
	(segment
		(start 73.45934 -326.922638)
		(end 73.45934 -327.821036)
		(width 0.508)
		(layer "F.Cu")
		(net "GND")
	)
	(segment
		(start 80.662018 -15.339822)
		(end 80.662018 -16.199612)
		(width 0.508)
		(layer "F.Cu")
		(net "GND")
	)
	(segment
		(start 69.982334 -371.001798)
		(end 69.982334 -371.96649)
		(width 0.508)
		(layer "F.Cu")
		(net "GND")
	)
	(segment
		(start 2.81559 -395.043914)
		(end 2.81559 -394.357606)
		(width 0.508)
		(layer "F.Cu")
		(net "GND")
	)
	(segment
		(start 74.798682 -16.184372)
		(end 74.798682 -17.203928)
		(width 0.508)
		(layer "F.Cu")
		(net "GND")
	)
	(segment
		(start 46.779942 -260.355588)
		(end 47.84979 -259.28574)
		(width 0.508)
		(layer "F.Cu")
		(net "GND")
	)
	(segment
		(start 41.792906 -283.49829)
		(end 40.86098 -283.49829)
		(width 0.508)
		(layer "F.Cu")
		(net "GND")
	)
	(segment
		(start 67.291966 -29.351986)
		(end 67.977258 -29.351986)
		(width 0.4572)
		(layer "F.Cu")
		(net "GND")
	)
	(segment
		(start 25.825958 -453.535034)
		(end 25.157938 -453.535034)
		(width 0.508)
		(layer "F.Cu")
		(net "GND")
	)
	(segment
		(start 71.45147 -220.025722)
		(end 71.45147 -219.008198)
		(width 0.508)
		(layer "F.Cu")
		(net "GND")
	)
	(segment
		(start 72.928734 -486.89133)
		(end 72.928734 -485.985058)
		(width 0.508)
		(layer "F.Cu")
		(net "GND")
	)
	(segment
		(start 26.65476 -11.980418)
		(end 26.072084 -12.563094)
		(width 0.4572)
		(layer "F.Cu")
		(net "GND")
	)
	(segment
		(start 72.087232 -327.767188)
		(end 72.087232 -328.665586)
		(width 0.508)
		(layer "F.Cu")
		(net "GND")
	)
	(segment
		(start 40.471344 -197.274942)
		(end 40.927274 -196.819012)
		(width 0.508)
		(layer "F.Cu")
		(net "GND")
	)
	(segment
		(start 41.427146 -370.099336)
		(end 41.427146 -370.095526)
		(width 0.508)
		(layer "F.Cu")
		(net "GND")
	)
	(segment
		(start 74.345292 -282.556204)
		(end 74.345292 -283.501084)
		(width 0.508)
		(layer "F.Cu")
		(net "GND")
	)
	(segment
		(start 77.254354 -15.339822)
		(end 77.254354 -16.199612)
		(width 0.508)
		(layer "F.Cu")
		(net "GND")
	)
	(segment
		(start 25.702006 -271.14881)
		(end 24.613616 -271.14881)
		(width 0.508)
		(layer "F.Cu")
		(net "GND")
	)
	(segment
		(start 75.91298 -396.862554)
		(end 75.91298 -395.785594)
		(width 0.508)
		(layer "F.Cu")
		(net "GND")
	)
	(segment
		(start 68.592192 -206.29118)
		(end 68.59778 -206.296768)
		(width 0.4572)
		(layer "F.Cu")
		(net "GND")
	)
	(segment
		(start 74.153522 -42.231056)
		(end 74.153522 -41.30802)
		(width 0.508)
		(layer "F.Cu")
		(net "GND")
	)
	(segment
		(start 76.120498 -15.339822)
		(end 76.120498 -16.199612)
		(width 0.508)
		(layer "F.Cu")
		(net "GND")
	)
	(segment
		(start 74.69886 -415.878772)
		(end 74.69886 -416.955732)
		(width 0.508)
		(layer "F.Cu")
		(net "GND")
	)
	(segment
		(start 25.702006 -272.345404)
		(end 24.580596 -272.345404)
		(width 0.508)
		(layer "F.Cu")
		(net "GND")
	)
	(segment
		(start 74.775568 -396.862554)
		(end 74.775568 -395.785594)
		(width 0.508)
		(layer "F.Cu")
		(net "GND")
	)
	(segment
		(start 73.426828 -307.419756)
		(end 73.426828 -306.521358)
		(width 0.508)
		(layer "F.Cu")
		(net "GND")
	)
	(segment
		(start 69.370956 -194.827144)
		(end 69.370956 -195.825872)
		(width 0.508)
		(layer "F.Cu")
		(net "GND")
	)
	(segment
		(start 25.825958 -452.257668)
		(end 25.113742 -452.257668)
		(width 0.508)
		(layer "F.Cu")
		(net "GND")
	)
	(segment
		(start 4.186936 -395.010386)
		(end 4.186936 -394.248386)
		(width 0.508)
		(layer "F.Cu")
		(net "GND")
	)
	(segment
		(start 25.825958 -448.493388)
		(end 25.172162 -448.493388)
		(width 0.508)
		(layer "F.Cu")
		(net "GND")
	)
	(segment
		(start 70.71487 -131.043426)
		(end 70.71487 -130.134614)
		(width 0.508)
		(layer "F.Cu")
		(net "GND")
	)
	(segment
		(start 81.332832 -295.215564)
		(end 82.752184 -295.215564)
		(width 0.508)
		(layer "F.Cu")
		(net "GND")
	)
	(segment
		(start 25.597612 -9.509252)
		(end 24.743918 -9.509252)
		(width 0.508)
		(layer "F.Cu")
		(net "GND")
	)
	(segment
		(start 69.863208 -353.908614)
		(end 69.863208 -352.98761)
		(width 0.508)
		(layer "F.Cu")
		(net "GND")
	)
	(segment
		(start 40.456612 -281.140662)
		(end 41.18356 -281.140662)
		(width 0.508)
		(layer "F.Cu")
		(net "GND")
	)
	(segment
		(start 71.903844 -42.231056)
		(end 71.903844 -41.31945)
		(width 0.508)
		(layer "F.Cu")
		(net "GND")
	)
	(segment
		(start 17.162272 -330.055474)
		(end 17.162272 -329.350116)
		(width 0.4572)
		(layer "F.Cu")
		(net "GND")
	)
	(segment
		(start 26.88463 -4.025138)
		(end 26.88463 -5.10032)
		(width 0.4572)
		(layer "F.Cu")
		(net "GND")
	)
	(segment
		(start 41.4655 -461.1751)
		(end 41.4655 -461.170274)
		(width 0.508)
		(layer "F.Cu")
		(net "GND")
	)
	(segment
		(start 73.909936 -149.513798)
		(end 73.909936 -150.42261)
		(width 0.508)
		(layer "F.Cu")
		(net "GND")
	)
	(segment
		(start 72.520302 -86.745318)
		(end 72.520302 -85.772752)
		(width 0.508)
		(layer "F.Cu")
		(net "GND")
	)
	(segment
		(start 25.457658 -365.50092)
		(end 24.636984 -365.50092)
		(width 0.508)
		(layer "F.Cu")
		(net "GND")
	)
	(segment
		(start 41.18356 -459.16596)
		(end 40.34536 -459.16596)
		(width 0.508)
		(layer "F.Cu")
		(net "GND")
	)
	(segment
		(start 71.11746 -371.001798)
		(end 71.11746 -371.96649)
		(width 0.508)
		(layer "F.Cu")
		(net "GND")
	)
	(segment
		(start 78.393544 -384.526282)
		(end 79.729076 -384.526282)
		(width 0.508)
		(layer "F.Cu")
		(net "GND")
	)
	(segment
		(start 25.531572 -100.590096)
		(end 24.801322 -100.590096)
		(width 0.508)
		(layer "F.Cu")
		(net "GND")
	)
	(segment
		(start 25.668224 -183.06923)
		(end 25.042114 -183.06923)
		(width 0.508)
		(layer "F.Cu")
		(net "GND")
	)
	(segment
		(start 26.839926 -461.829912)
		(end 26.839926 -461.067658)
		(width 0.4572)
		(layer "F.Cu")
		(net "GND")
	)
	(segment
		(start 40.792908 -374.14708)
		(end 41.209468 -373.73052)
		(width 0.508)
		(layer "F.Cu")
		(net "GND")
	)
	(segment
		(start 68.607686 -175.545496)
		(end 68.607686 -174.546768)
		(width 0.508)
		(layer "F.Cu")
		(net "GND")
	)
	(segment
		(start 26.88463 -5.61086)
		(end 27.00909 -5.73532)
		(width 0.4572)
		(layer "F.Cu")
		(net "GND")
	)
	(segment
		(start 74.832718 -262.860028)
		(end 74.832718 -261.915148)
		(width 0.508)
		(layer "F.Cu")
		(net "GND")
	)
	(segment
		(start 26.78557 -374.115076)
		(end 26.78557 -373.44858)
		(width 0.508)
		(layer "F.Cu")
		(net "GND")
	)
	(segment
		(start 69.580252 -131.043426)
		(end 69.580252 -130.134614)
		(width 0.508)
		(layer "F.Cu")
		(net "GND")
	)
	(segment
		(start 81.78927 -15.339822)
		(end 81.78927 -16.199612)
		(width 0.508)
		(layer "F.Cu")
		(net "GND")
	)
	(segment
		(start 13.853922 -330.080874)
		(end 13.853922 -329.314302)
		(width 0.4572)
		(layer "F.Cu")
		(net "GND")
	)
	(segment
		(start 25.531572 -94.464886)
		(end 24.754078 -94.464886)
		(width 0.508)
		(layer "F.Cu")
		(net "GND")
	)
	(segment
		(start 71.423022 -60.563506)
		(end 71.423022 -61.372496)
		(width 0.508)
		(layer "F.Cu")
		(net "GND")
	)
	(segment
		(start 25.85212 -454.646538)
		(end 25.220676 -454.646538)
		(width 0.4572)
		(layer "F.Cu")
		(net "GND")
	)
	(segment
		(start 72.802242 -460.132684)
		(end 72.802242 -460.8576)
		(width 0.508)
		(layer "F.Cu")
		(net "GND")
	)
	(segment
		(start 71.825104 -131.043426)
		(end 71.825104 -130.134614)
		(width 0.508)
		(layer "F.Cu")
		(net "GND")
	)
	(segment
		(start 25.668224 -186.752992)
		(end 24.773636 -186.752992)
		(width 0.508)
		(layer "F.Cu")
		(net "GND")
	)
	(segment
		(start 68.972938 -61.408056)
		(end 68.972938 -62.319662)
		(width 0.508)
		(layer "F.Cu")
		(net "GND")
	)
	(segment
		(start 75.316842 -42.231056)
		(end 75.316842 -41.29659)
		(width 0.508)
		(layer "F.Cu")
		(net "GND")
	)
	(segment
		(start 81.29143 -504.705874)
		(end 81.29143 -505.51461)
		(width 0.508)
		(layer "F.Cu")
		(net "GND")
	)
	(segment
		(start 71.007986 -307.419756)
		(end 71.007986 -306.521358)
		(width 0.508)
		(layer "F.Cu")
		(net "GND")
	)
	(segment
		(start 68.639436 -371.846348)
		(end 68.639436 -372.81104)
		(width 0.508)
		(layer "F.Cu")
		(net "GND")
	)
	(via
		(at 42.291 -28.297378)
		(size 1.016)
		(drill 0.508)
		(layers "F.Cu" "B.Cu")
		(net "GND")
	)
	(via
		(at 72.284082 -441.57011)
		(size 0.508)
		(drill 0.254)
		(layers "F.Cu" "B.Cu")
		(net "GND")
	)
	(via
		(at 61.159136 -21.955506)
		(size 1.016)
		(drill 0.508)
		(layers "F.Cu" "B.Cu")
		(net "GND")
	)
	(via
		(at 60.080398 -65.804796)
		(size 1.016)
		(drill 0.508)
		(layers "F.Cu" "B.Cu")
		(net "GND")
	)
	(via
		(at 39.689786 -128.627886)
		(size 1.016)
		(drill 0.508)
		(layers "F.Cu" "B.Cu")
		(net "GND")
	)
	(via
		(at 42.715434 -481.385626)
		(size 1.016)
		(drill 0.508)
		(layers "F.Cu" "B.Cu")
		(net "GND")
	)
	(via
		(at 41.281096 -371.513354)
		(size 0.508)
		(drill 0.254)
		(layers "F.Cu" "B.Cu")
		(net "GND")
	)
	(via
		(at 74.832718 -261.915148)
		(size 0.508)
		(drill 0.254)
		(layers "F.Cu" "B.Cu")
		(net "GND")
	)
	(via
		(at 61.159136 -23.99665)
		(size 1.016)
		(drill 0.508)
		(layers "F.Cu" "B.Cu")
		(net "GND")
	)
	(via
		(at 42.758868 -477.699324)
		(size 1.016)
		(drill 0.508)
		(layers "F.Cu" "B.Cu")
		(net "GND")
	)
	(via
		(at 0.762254 -25.408636)
		(size 0.508)
		(drill 0.254)
		(layers "F.Cu" "B.Cu")
		(net "GND")
	)
	(via
		(at 63.215012 -424.278044)
		(size 1.016)
		(drill 0.508)
		(layers "F.Cu" "B.Cu")
		(net "GND")
	)
	(via
		(at 59.067192 -122.524774)
		(size 1.016)
		(drill 0.508)
		(layers "F.Cu" "B.Cu")
		(net "GND")
	)
	(via
		(at 45.47108 -220.40088)
		(size 1.016)
		(drill 0.508)
		(layers "F.Cu" "B.Cu")
		(net "GND")
	)
	(via
		(at 26.072084 -12.563094)
		(size 0.508)
		(drill 0.254)
		(layers "F.Cu" "B.Cu")
		(net "GND")
	)
	(via
		(at 64.74841 -255.185672)
		(size 1.016)
		(drill 0.508)
		(layers "F.Cu" "B.Cu")
		(net "GND")
	)
	(via
		(at 43.02125 -302.34509)
		(size 1.016)
		(drill 0.508)
		(layers "F.Cu" "B.Cu")
		(net "GND")
	)
	(via
		(at 73.532746 -441.63869)
		(size 0.508)
		(drill 0.254)
		(layers "F.Cu" "B.Cu")
		(net "GND")
	)
	(via
		(at 0.762254 -482.608636)
		(size 0.508)
		(drill 0.254)
		(layers "F.Cu" "B.Cu")
		(net "GND")
	)
	(via
		(at 40.517826 -473.964762)
		(size 1.016)
		(drill 0.508)
		(layers "F.Cu" "B.Cu")
		(net "GND")
	)
	(via
		(at 57.13984 -431.755804)
		(size 1.016)
		(drill 0.508)
		(layers "F.Cu" "B.Cu")
		(net "GND")
	)
	(via
		(at 71.392796 -85.772752)
		(size 0.508)
		(drill 0.254)
		(layers "F.Cu" "B.Cu")
		(net "GND")
	)
	(via
		(at 0.762254 -304.808636)
		(size 0.508)
		(drill 0.254)
		(layers "F.Cu" "B.Cu")
		(net "GND")
	)
	(via
		(at 24.743918 -8.344662)
		(size 0.508)
		(drill 0.254)
		(layers "F.Cu" "B.Cu")
		(net "GND")
	)
	(via
		(at 39.482776 -212.548216)
		(size 1.016)
		(drill 0.508)
		(layers "F.Cu" "B.Cu")
		(net "GND")
	)
	(via
		(at 44.619418 -485.317292)
		(size 1.016)
		(drill 0.508)
		(layers "F.Cu" "B.Cu")
		(net "GND")
	)
	(via
		(at 60.551314 -152.784302)
		(size 1.016)
		(drill 0.508)
		(layers "F.Cu" "B.Cu")
		(net "GND")
	)
	(via
		(at 102.238048 -182.145432)
		(size 0.508)
		(drill 0.254)
		(layers "F.Cu" "B.Cu")
		(net "GND")
	)
	(via
		(at 43.567096 -220.40088)
		(size 1.016)
		(drill 0.508)
		(layers "F.Cu" "B.Cu")
		(net "GND")
	)
	(via
		(at 62.860428 -308.685184)
		(size 1.016)
		(drill 0.508)
		(layers "F.Cu" "B.Cu")
		(net "GND")
	)
	(via
		(at 41.030398 -384.536696)
		(size 1.016)
		(drill 0.508)
		(layers "F.Cu" "B.Cu")
		(net "GND")
	)
	(via
		(at 62.792356 -154.459432)
		(size 1.016)
		(drill 0.508)
		(layers "F.Cu" "B.Cu")
		(net "GND")
	)
	(via
		(at 39.689786 -126.586742)
		(size 1.016)
		(drill 0.508)
		(layers "F.Cu" "B.Cu")
		(net "GND")
	)
	(via
		(at 70.71487 -130.134614)
		(size 0.508)
		(drill 0.254)
		(layers "F.Cu" "B.Cu")
		(net "GND")
	)
	(via
		(at 58.716672 -249.34418)
		(size 1.016)
		(drill 0.508)
		(layers "F.Cu" "B.Cu")
		(net "GND")
	)
	(via
		(at 69.982334 -371.96649)
		(size 0.508)
		(drill 0.254)
		(layers "F.Cu" "B.Cu")
		(net "GND")
	)
	(via
		(at 24.613616 -271.14881)
		(size 0.508)
		(drill 0.254)
		(layers "F.Cu" "B.Cu")
		(net "GND")
	)
	(via
		(at 40.474392 -483.276148)
		(size 1.016)
		(drill 0.508)
		(layers "F.Cu" "B.Cu")
		(net "GND")
	)
	(via
		(at 74.626978 -306.521358)
		(size 0.508)
		(drill 0.254)
		(layers "F.Cu" "B.Cu")
		(net "GND")
	)
	(via
		(at 19.515582 -525.237964)
		(size 0.508)
		(drill 0.254)
		(layers "F.Cu" "B.Cu")
		(net "GND")
	)
	(via
		(at 71.423022 -61.372496)
		(size 0.508)
		(drill 0.254)
		(layers "F.Cu" "B.Cu")
		(net "GND")
	)
	(via
		(at 0.762254 -228.608636)
		(size 0.508)
		(drill 0.254)
		(layers "F.Cu" "B.Cu")
		(net "GND")
	)
	(via
		(at 0.762254 -241.308636)
		(size 0.508)
		(drill 0.254)
		(layers "F.Cu" "B.Cu")
		(net "GND")
	)
	(via
		(at 59.069986 -422.444418)
		(size 1.016)
		(drill 0.508)
		(layers "F.Cu" "B.Cu")
		(net "GND")
	)
	(via
		(at 64.791844 -247.333008)
		(size 1.016)
		(drill 0.508)
		(layers "F.Cu" "B.Cu")
		(net "GND")
	)
	(via
		(at 39.143686 -382.63576)
		(size 1.016)
		(drill 0.508)
		(layers "F.Cu" "B.Cu")
		(net "GND")
	)
	(via
		(at 43.61053 -208.97215)
		(size 1.016)
		(drill 0.508)
		(layers "F.Cu" "B.Cu")
		(net "GND")
	)
	(via
		(at 62.88786 -245.657878)
		(size 1.016)
		(drill 0.508)
		(layers "F.Cu" "B.Cu")
		(net "GND")
	)
	(via
		(at 102.238048 -29.745432)
		(size 0.508)
		(drill 0.254)
		(layers "F.Cu" "B.Cu")
		(net "GND")
	)
	(via
		(at 39.439342 -220.40088)
		(size 1.016)
		(drill 0.508)
		(layers "F.Cu" "B.Cu")
		(net "GND")
	)
	(via
		(at 68.972938 -62.319662)
		(size 0.508)
		(drill 0.254)
		(layers "F.Cu" "B.Cu")
		(net "GND")
	)
	(via
		(at 58.760106 -245.657878)
		(size 1.016)
		(drill 0.508)
		(layers "F.Cu" "B.Cu")
		(net "GND")
	)
	(via
		(at 40.780208 -298.769024)
		(size 1.016)
		(drill 0.508)
		(layers "F.Cu" "B.Cu")
		(net "GND")
	)
	(via
		(at 63.106554 -14.477746)
		(size 1.016)
		(drill 0.508)
		(layers "F.Cu" "B.Cu")
		(net "GND")
	)
	(via
		(at 41.369488 -210.873086)
		(size 1.016)
		(drill 0.508)
		(layers "F.Cu" "B.Cu")
		(net "GND")
	)
	(via
		(at 40.780208 -296.935398)
		(size 1.016)
		(drill 0.508)
		(layers "F.Cu" "B.Cu")
		(net "GND")
	)
	(via
		(at 62.844426 -249.34418)
		(size 1.016)
		(drill 0.508)
		(layers "F.Cu" "B.Cu")
		(net "GND")
	)
	(via
		(at 74.0537 -460.970884)
		(size 0.508)
		(drill 0.254)
		(layers "F.Cu" "B.Cu")
		(net "GND")
	)
	(via
		(at 71.11746 -371.96649)
		(size 0.508)
		(drill 0.254)
		(layers "F.Cu" "B.Cu")
		(net "GND")
	)
	(via
		(at 57.839356 -60.395104)
		(size 1.016)
		(drill 0.508)
		(layers "F.Cu" "B.Cu")
		(net "GND")
	)
	(via
		(at 102.238048 -131.345432)
		(size 0.508)
		(drill 0.254)
		(layers "F.Cu" "B.Cu")
		(net "GND")
	)
	(via
		(at 72.087232 -328.665586)
		(size 0.508)
		(drill 0.254)
		(layers "F.Cu" "B.Cu")
		(net "GND")
	)
	(via
		(at 74.345292 -283.501084)
		(size 0.508)
		(drill 0.254)
		(layers "F.Cu" "B.Cu")
		(net "GND")
	)
	(via
		(at 39.143686 -386.211826)
		(size 1.016)
		(drill 0.508)
		(layers "F.Cu" "B.Cu")
		(net "GND")
	)
	(via
		(at 102.238048 -385.345432)
		(size 0.508)
		(drill 0.254)
		(layers "F.Cu" "B.Cu")
		(net "GND")
	)
	(via
		(at 58.732674 -304.734214)
		(size 1.016)
		(drill 0.508)
		(layers "F.Cu" "B.Cu")
		(net "GND")
	)
	(via
		(at 62.792356 -152.784302)
		(size 1.016)
		(drill 0.508)
		(layers "F.Cu" "B.Cu")
		(net "GND")
	)
	(via
		(at 24.88819 -99.36988)
		(size 0.508)
		(drill 0.254)
		(layers "F.Cu" "B.Cu")
		(net "GND")
	)
	(via
		(at 71.518526 -106.976926)
		(size 0.508)
		(drill 0.254)
		(layers "F.Cu" "B.Cu")
		(net "GND")
	)
	(via
		(at 43.61053 -212.548216)
		(size 1.016)
		(drill 0.508)
		(layers "F.Cu" "B.Cu")
		(net "GND")
	)
	(via
		(at 43.567096 -214.559388)
		(size 1.016)
		(drill 0.508)
		(layers "F.Cu" "B.Cu")
		(net "GND")
	)
	(via
		(at 39.73322 -117.275356)
		(size 1.016)
		(drill 0.508)
		(layers "F.Cu" "B.Cu")
		(net "GND")
	)
	(via
		(at 0.762254 -317.508636)
		(size 0.508)
		(drill 0.254)
		(layers "F.Cu" "B.Cu")
		(net "GND")
	)
	(via
		(at 57.839356 -62.22873)
		(size 1.016)
		(drill 0.508)
		(layers "F.Cu" "B.Cu")
		(net "GND")
	)
	(via
		(at 73.199752 -283.501084)
		(size 0.508)
		(drill 0.254)
		(layers "F.Cu" "B.Cu")
		(net "GND")
	)
	(via
		(at 0.762254 -431.808636)
		(size 0.508)
		(drill 0.254)
		(layers "F.Cu" "B.Cu")
		(net "GND")
	)
	(via
		(at 72.559164 -261.915148)
		(size 0.508)
		(drill 0.254)
		(layers "F.Cu" "B.Cu")
		(net "GND")
	)
	(via
		(at 57.183274 -427.85411)
		(size 1.016)
		(drill 0.508)
		(layers "F.Cu" "B.Cu")
		(net "GND")
	)
	(via
		(at 102.238048 -93.245432)
		(size 0.508)
		(drill 0.254)
		(layers "F.Cu" "B.Cu")
		(net "GND")
	)
	(via
		(at 58.760106 -241.923316)
		(size 1.016)
		(drill 0.508)
		(layers "F.Cu" "B.Cu")
		(net "GND")
	)
	(via
		(at 60.036964 -71.747634)
		(size 1.016)
		(drill 0.508)
		(layers "F.Cu" "B.Cu")
		(net "GND")
	)
	(via
		(at 102.238048 -194.845432)
		(size 0.508)
		(drill 0.254)
		(layers "F.Cu" "B.Cu")
		(net "GND")
	)
	(via
		(at 62.88786 -243.756942)
		(size 1.016)
		(drill 0.508)
		(layers "F.Cu" "B.Cu")
		(net "GND")
	)
	(via
		(at 25.90546 -108.230416)
		(size 0.508)
		(drill 0.254)
		(layers "F.Cu" "B.Cu")
		(net "GND")
	)
	(via
		(at 102.238048 -321.845432)
		(size 0.508)
		(drill 0.254)
		(layers "F.Cu" "B.Cu")
		(net "GND")
	)
	(via
		(at 62.748922 -160.40227)
		(size 1.016)
		(drill 0.508)
		(layers "F.Cu" "B.Cu")
		(net "GND")
	)
	(via
		(at 70.278244 -219.071952)
		(size 0.508)
		(drill 0.254)
		(layers "F.Cu" "B.Cu")
		(net "GND")
	)
	(via
		(at 82.752184 -295.215564)
		(size 0.508)
		(drill 0.254)
		(layers "F.Cu" "B.Cu")
		(net "GND")
	)
	(via
		(at 57.795922 -67.815968)
		(size 1.016)
		(drill 0.508)
		(layers "F.Cu" "B.Cu")
		(net "GND")
	)
	(via
		(at 59.026552 -433.796948)
		(size 1.016)
		(drill 0.508)
		(layers "F.Cu" "B.Cu")
		(net "GND")
	)
	(via
		(at 72.403716 -395.785594)
		(size 0.508)
		(drill 0.254)
		(layers "F.Cu" "B.Cu")
		(net "GND")
	)
	(via
		(at 69.726556 -174.546768)
		(size 0.508)
		(drill 0.254)
		(layers "F.Cu" "B.Cu")
		(net "GND")
	)
	(via
		(at 41.209468 -373.73052)
		(size 0.508)
		(drill 0.254)
		(layers "F.Cu" "B.Cu")
		(net "GND")
	)
	(via
		(at 60.646818 -247.333008)
		(size 1.016)
		(drill 0.508)
		(layers "F.Cu" "B.Cu")
		(net "GND")
	)
	(via
		(at 63.06312 -23.99665)
		(size 1.016)
		(drill 0.508)
		(layers "F.Cu" "B.Cu")
		(net "GND")
	)
	(via
		(at 39.73322 -122.685048)
		(size 1.016)
		(drill 0.508)
		(layers "F.Cu" "B.Cu")
		(net "GND")
	)
	(via
		(at 61.940948 -69.70649)
		(size 1.016)
		(drill 0.508)
		(layers "F.Cu" "B.Cu")
		(net "GND")
	)
	(via
		(at 70.85457 -174.546768)
		(size 0.508)
		(drill 0.254)
		(layers "F.Cu" "B.Cu")
		(net "GND")
	)
	(via
		(at 41.18356 -459.16596)
		(size 0.508)
		(drill 0.254)
		(layers "F.Cu" "B.Cu")
		(net "GND")
	)
	(via
		(at 44.662852 -477.699324)
		(size 1.016)
		(drill 0.508)
		(layers "F.Cu" "B.Cu")
		(net "GND")
	)
	(via
		(at 27.00909 -5.73532)
		(size 0.508)
		(drill 0.254)
		(layers "F.Cu" "B.Cu")
		(net "GND")
	)
	(via
		(at 61.940948 -73.65746)
		(size 1.016)
		(drill 0.508)
		(layers "F.Cu" "B.Cu")
		(net "GND")
	)
	(via
		(at 61.267594 -435.706774)
		(size 1.016)
		(drill 0.508)
		(layers "F.Cu" "B.Cu")
		(net "GND")
	)
	(via
		(at 61.20257 -18.053812)
		(size 1.016)
		(drill 0.508)
		(layers "F.Cu" "B.Cu")
		(net "GND")
	)
	(via
		(at 76.120498 -16.199612)
		(size 0.508)
		(drill 0.254)
		(layers "F.Cu" "B.Cu")
		(net "GND")
	)
	(via
		(at 39.439342 -216.44991)
		(size 1.016)
		(drill 0.508)
		(layers "F.Cu" "B.Cu")
		(net "GND")
	)
	(via
		(at 102.238048 -398.045432)
		(size 0.508)
		(drill 0.254)
		(layers "F.Cu" "B.Cu")
		(net "GND")
	)
	(via
		(at 70.658736 -194.981322)
		(size 0.508)
		(drill 0.254)
		(layers "F.Cu" "B.Cu")
		(net "GND")
	)
	(via
		(at 73.687178 -261.915148)
		(size 0.508)
		(drill 0.254)
		(layers "F.Cu" "B.Cu")
		(net "GND")
	)
	(via
		(at 0.762254 -101.608636)
		(size 0.508)
		(drill 0.254)
		(layers "F.Cu" "B.Cu")
		(net "GND")
	)
	(via
		(at 60.080398 -62.22873)
		(size 1.016)
		(drill 0.508)
		(layers "F.Cu" "B.Cu")
		(net "GND")
	)
	(via
		(at 61.984382 -65.804796)
		(size 1.016)
		(drill 0.508)
		(layers "F.Cu" "B.Cu")
		(net "GND")
	)
	(via
		(at 24.754078 -94.464886)
		(size 0.508)
		(drill 0.254)
		(layers "F.Cu" "B.Cu")
		(net "GND")
	)
	(via
		(at 0.763524 -405.028908)
		(size 0.508)
		(drill 0.254)
		(layers "F.Cu" "B.Cu")
		(net "GND")
	)
	(via
		(at 44.414948 -77.797406)
		(size 1.016)
		(drill 0.508)
		(layers "F.Cu" "B.Cu")
		(net "GND")
	)
	(via
		(at 71.815198 -194.981322)
		(size 0.508)
		(drill 0.254)
		(layers "F.Cu" "B.Cu")
		(net "GND")
	)
	(via
		(at 0.762254 -203.208636)
		(size 0.508)
		(drill 0.254)
		(layers "F.Cu" "B.Cu")
		(net "GND")
	)
	(via
		(at 64.764412 -306.775358)
		(size 1.016)
		(drill 0.508)
		(layers "F.Cu" "B.Cu")
		(net "GND")
	)
	(via
		(at 72.185276 -306.521358)
		(size 0.508)
		(drill 0.254)
		(layers "F.Cu" "B.Cu")
		(net "GND")
	)
	(via
		(at 46.785784 -245.712234)
		(size 0.508)
		(drill 0.254)
		(layers "F.Cu" "B.Cu")
		(net "GND")
	)
	(via
		(at 42.715434 -483.276148)
		(size 1.016)
		(drill 0.508)
		(layers "F.Cu" "B.Cu")
		(net "GND")
	)
	(via
		(at 14.9225 -147.231862)
		(size 0.508)
		(drill 0.254)
		(layers "F.Cu" "B.Cu")
		(net "GND")
	)
	(via
		(at 45.13199 -394.06449)
		(size 1.016)
		(drill 0.508)
		(layers "F.Cu" "B.Cu")
		(net "GND")
	)
	(via
		(at 74.709782 -327.821036)
		(size 0.508)
		(drill 0.254)
		(layers "F.Cu" "B.Cu")
		(net "GND")
	)
	(via
		(at 43.228006 -394.06449)
		(size 1.016)
		(drill 0.508)
		(layers "F.Cu" "B.Cu")
		(net "GND")
	)
	(via
		(at 45.13199 -388.222998)
		(size 1.016)
		(drill 0.508)
		(layers "F.Cu" "B.Cu")
		(net "GND")
	)
	(via
		(at 73.45934 -327.821036)
		(size 0.508)
		(drill 0.254)
		(layers "F.Cu" "B.Cu")
		(net "GND")
	)
	(via
		(at 63.168784 -124.535946)
		(size 1.016)
		(drill 0.508)
		(layers "F.Cu" "B.Cu")
		(net "GND")
	)
	(via
		(at 0.762254 -63.508636)
		(size 0.508)
		(drill 0.254)
		(layers "F.Cu" "B.Cu")
		(net "GND")
	)
	(via
		(at 25.172162 -448.493388)
		(size 0.508)
		(drill 0.254)
		(layers "F.Cu" "B.Cu")
		(net "GND")
	)
	(via
		(at 42.247566 -41.559734)
		(size 1.016)
		(drill 0.508)
		(layers "F.Cu" "B.Cu")
		(net "GND")
	)
	(via
		(at 0.762254 -127.008636)
		(size 0.508)
		(drill 0.254)
		(layers "F.Cu" "B.Cu")
		(net "GND")
	)
	(via
		(at 43.228006 -388.222998)
		(size 1.016)
		(drill 0.508)
		(layers "F.Cu" "B.Cu")
		(net "GND")
	)
	(via
		(at 42.291 -30.131004)
		(size 1.016)
		(drill 0.508)
		(layers "F.Cu" "B.Cu")
		(net "GND")
	)
	(via
		(at 61.308234 -120.849644)
		(size 1.016)
		(drill 0.508)
		(layers "F.Cu" "B.Cu")
		(net "GND")
	)
	(via
		(at 102.238048 -67.845432)
		(size 0.508)
		(drill 0.254)
		(layers "F.Cu" "B.Cu")
		(net "GND")
	)
	(via
		(at 42.715434 -485.317292)
		(size 1.016)
		(drill 0.508)
		(layers "F.Cu" "B.Cu")
		(net "GND")
	)
	(via
		(at 44.505626 -0.762508)
		(size 0.508)
		(drill 0.254)
		(layers "F.Cu" "B.Cu")
		(net "GND")
	)
	(via
		(at 90.015314 -349.55734)
		(size 1.016)
		(drill 0.508)
		(layers "F.Cu" "B.Cu")
		(net "GND")
	)
	(via
		(at 43.02125 -298.769024)
		(size 1.016)
		(drill 0.508)
		(layers "F.Cu" "B.Cu")
		(net "GND")
	)
	(via
		(at 38.631114 -479.374454)
		(size 1.016)
		(drill 0.508)
		(layers "F.Cu" "B.Cu")
		(net "GND")
	)
	(via
		(at 64.652906 -160.40227)
		(size 1.016)
		(drill 0.508)
		(layers "F.Cu" "B.Cu")
		(net "GND")
	)
	(via
		(at 45.13199 -392.154664)
		(size 1.016)
		(drill 0.508)
		(layers "F.Cu" "B.Cu")
		(net "GND")
	)
	(via
		(at 44.662852 -475.798388)
		(size 1.016)
		(drill 0.508)
		(layers "F.Cu" "B.Cu")
		(net "GND")
	)
	(via
		(at 44.925234 -300.66996)
		(size 1.016)
		(drill 0.508)
		(layers "F.Cu" "B.Cu")
		(net "GND")
	)
	(via
		(at 45.13199 -390.11352)
		(size 1.016)
		(drill 0.508)
		(layers "F.Cu" "B.Cu")
		(net "GND")
	)
	(via
		(at 58.664602 -152.784302)
		(size 1.016)
		(drill 0.508)
		(layers "F.Cu" "B.Cu")
		(net "GND")
	)
	(via
		(at 44.134278 -35.718242)
		(size 1.016)
		(drill 0.508)
		(layers "F.Cu" "B.Cu")
		(net "GND")
	)
	(via
		(at 39.143686 -380.802134)
		(size 1.016)
		(drill 0.508)
		(layers "F.Cu" "B.Cu")
		(net "GND")
	)
	(via
		(at 77.254354 -16.199612)
		(size 0.508)
		(drill 0.254)
		(layers "F.Cu" "B.Cu")
		(net "GND")
	)
	(via
		(at 41.030398 -382.63576)
		(size 1.016)
		(drill 0.508)
		(layers "F.Cu" "B.Cu")
		(net "GND")
	)
	(via
		(at 45.175424 -386.211826)
		(size 1.016)
		(drill 0.508)
		(layers "F.Cu" "B.Cu")
		(net "GND")
	)
	(via
		(at 42.758868 -475.798388)
		(size 1.016)
		(drill 0.508)
		(layers "F.Cu" "B.Cu")
		(net "GND")
	)
	(via
		(at 58.760106 -243.756942)
		(size 1.016)
		(drill 0.508)
		(layers "F.Cu" "B.Cu")
		(net "GND")
	)
	(via
		(at 93.006926 -337.740244)
		(size 1.016)
		(drill 0.508)
		(layers "F.Cu" "B.Cu")
		(net "GND")
	)
	(via
		(at 60.50788 -162.312096)
		(size 1.016)
		(drill 0.508)
		(layers "F.Cu" "B.Cu")
		(net "GND")
	)
	(via
		(at 102.238048 -512.345432)
		(size 0.508)
		(drill 0.254)
		(layers "F.Cu" "B.Cu")
		(net "GND")
	)
	(via
		(at 43.567096 -218.491054)
		(size 1.016)
		(drill 0.508)
		(layers "F.Cu" "B.Cu")
		(net "GND")
	)
	(via
		(at 72.478392 -151.26716)
		(size 0.508)
		(drill 0.254)
		(layers "F.Cu" "B.Cu")
		(net "GND")
	)
	(via
		(at 44.134278 -37.608764)
		(size 1.016)
		(drill 0.508)
		(layers "F.Cu" "B.Cu")
		(net "GND")
	)
	(via
		(at 60.619386 -304.734214)
		(size 1.016)
		(drill 0.508)
		(layers "F.Cu" "B.Cu")
		(net "GND")
	)
	(via
		(at 62.860428 -304.734214)
		(size 1.016)
		(drill 0.508)
		(layers "F.Cu" "B.Cu")
		(net "GND")
	)
	(via
		(at 43.27144 -384.536696)
		(size 1.016)
		(drill 0.508)
		(layers "F.Cu" "B.Cu")
		(net "GND")
	)
	(via
		(at 75.059286 -150.42261)
		(size 0.508)
		(drill 0.254)
		(layers "F.Cu" "B.Cu")
		(net "GND")
	)
	(via
		(at 63.06312 -20.064984)
		(size 1.016)
		(drill 0.508)
		(layers "F.Cu" "B.Cu")
		(net "GND")
	)
	(via
		(at 42.977816 -304.356262)
		(size 1.016)
		(drill 0.508)
		(layers "F.Cu" "B.Cu")
		(net "GND")
	)
	(via
		(at 102.238048 -207.545432)
		(size 0.508)
		(drill 0.254)
		(layers "F.Cu" "B.Cu")
		(net "GND")
	)
	(via
		(at 16.017494 -329.263248)
		(size 0.508)
		(drill 0.254)
		(layers "F.Cu" "B.Cu")
		(net "GND")
	)
	(via
		(at 69.774816 -441.501784)
		(size 0.508)
		(drill 0.254)
		(layers "F.Cu" "B.Cu")
		(net "GND")
	)
	(via
		(at 60.646818 -241.923316)
		(size 1.016)
		(drill 0.508)
		(layers "F.Cu" "B.Cu")
		(net "GND")
	)
	(via
		(at 102.238048 -105.945432)
		(size 0.508)
		(drill 0.254)
		(layers "F.Cu" "B.Cu")
		(net "GND")
	)
	(via
		(at 41.792906 -283.49829)
		(size 0.508)
		(drill 0.254)
		(layers "F.Cu" "B.Cu")
		(net "GND")
	)
	(via
		(at 71.007986 -306.521358)
		(size 0.508)
		(drill 0.254)
		(layers "F.Cu" "B.Cu")
		(net "GND")
	)
	(via
		(at 72.611996 -239.126268)
		(size 0.508)
		(drill 0.254)
		(layers "F.Cu" "B.Cu")
		(net "GND")
	)
	(via
		(at 102.238048 -359.945432)
		(size 0.508)
		(drill 0.254)
		(layers "F.Cu" "B.Cu")
		(net "GND")
	)
	(via
		(at 71.45147 -219.008198)
		(size 0.508)
		(drill 0.254)
		(layers "F.Cu" "B.Cu")
		(net "GND")
	)
	(via
		(at 38.58768 -483.276148)
		(size 1.016)
		(drill 0.508)
		(layers "F.Cu" "B.Cu")
		(net "GND")
	)
	(via
		(at 57.205626 -0.762508)
		(size 0.508)
		(drill 0.254)
		(layers "F.Cu" "B.Cu")
		(net "GND")
	)
	(via
		(at 0.762254 -444.508636)
		(size 0.508)
		(drill 0.254)
		(layers "F.Cu" "B.Cu")
		(net "GND")
	)
	(via
		(at 63.212218 -122.524774)
		(size 1.016)
		(drill 0.508)
		(layers "F.Cu" "B.Cu")
		(net "GND")
	)
	(via
		(at 59.069986 -426.17898)
		(size 1.016)
		(drill 0.508)
		(layers "F.Cu" "B.Cu")
		(net "GND")
	)
	(via
		(at 68.639436 -372.81104)
		(size 0.508)
		(drill 0.254)
		(layers "F.Cu" "B.Cu")
		(net "GND")
	)
	(via
		(at 44.414948 -79.707232)
		(size 1.016)
		(drill 0.508)
		(layers "F.Cu" "B.Cu")
		(net "GND")
	)
	(via
		(at 59.067192 -118.948708)
		(size 1.016)
		(drill 0.508)
		(layers "F.Cu" "B.Cu")
		(net "GND")
	)
	(via
		(at 66.037714 -529.236178)
		(size 0.508)
		(drill 0.254)
		(layers "F.Cu" "B.Cu")
		(net "GND")
	)
	(via
		(at 61.267594 -431.755804)
		(size 1.016)
		(drill 0.508)
		(layers "F.Cu" "B.Cu")
		(net "GND")
	)
	(via
		(at 26.78557 -374.115076)
		(size 0.508)
		(drill 0.254)
		(layers "F.Cu" "B.Cu")
		(net "GND")
	)
	(via
		(at 0.762254 -38.108636)
		(size 0.508)
		(drill 0.254)
		(layers "F.Cu" "B.Cu")
		(net "GND")
	)
	(via
		(at 57.13984 -429.865282)
		(size 1.016)
		(drill 0.508)
		(layers "F.Cu" "B.Cu")
		(net "GND")
	)
	(via
		(at 102.238048 -258.345432)
		(size 0.508)
		(drill 0.254)
		(layers "F.Cu" "B.Cu")
		(net "GND")
	)
	(via
		(at 59.026552 -435.706774)
		(size 1.016)
		(drill 0.508)
		(layers "F.Cu" "B.Cu")
		(net "GND")
	)
	(via
		(at 44.177712 -33.70707)
		(size 1.016)
		(drill 0.508)
		(layers "F.Cu" "B.Cu")
		(net "GND")
	)
	(via
		(at 57.13984 -433.796948)
		(size 1.016)
		(drill 0.508)
		(layers "F.Cu" "B.Cu")
		(net "GND")
	)
	(via
		(at 61.2648 -128.467612)
		(size 1.016)
		(drill 0.508)
		(layers "F.Cu" "B.Cu")
		(net "GND")
	)
	(via
		(at 102.238048 -156.745432)
		(size 0.508)
		(drill 0.254)
		(layers "F.Cu" "B.Cu")
		(net "GND")
	)
	(via
		(at 61.159136 -20.064984)
		(size 1.016)
		(drill 0.508)
		(layers "F.Cu" "B.Cu")
		(net "GND")
	)
	(via
		(at 71.871332 -284.345634)
		(size 0.508)
		(drill 0.254)
		(layers "F.Cu" "B.Cu")
		(net "GND")
	)
	(via
		(at 0.762254 -508.008636)
		(size 0.508)
		(drill 0.254)
		(layers "F.Cu" "B.Cu")
		(net "GND")
	)
	(via
		(at 45.47108 -214.559388)
		(size 1.016)
		(drill 0.508)
		(layers "F.Cu" "B.Cu")
		(net "GND")
	)
	(via
		(at 58.716672 -253.275846)
		(size 1.016)
		(drill 0.508)
		(layers "F.Cu" "B.Cu")
		(net "GND")
	)
	(via
		(at 0.762254 -215.908636)
		(size 0.508)
		(drill 0.254)
		(layers "F.Cu" "B.Cu")
		(net "GND")
	)
	(via
		(at 102.238048 -220.245432)
		(size 0.508)
		(drill 0.254)
		(layers "F.Cu" "B.Cu")
		(net "GND")
	)
	(via
		(at 40.517826 -475.798388)
		(size 1.016)
		(drill 0.508)
		(layers "F.Cu" "B.Cu")
		(net "GND")
	)
	(via
		(at 59.023758 -126.426468)
		(size 1.016)
		(drill 0.508)
		(layers "F.Cu" "B.Cu")
		(net "GND")
	)
	(via
		(at 40.959278 -106.900726)
		(size 0.508)
		(drill 0.254)
		(layers "F.Cu" "B.Cu")
		(net "GND")
	)
	(via
		(at 81.29143 -505.51461)
		(size 0.508)
		(drill 0.254)
		(layers "F.Cu" "B.Cu")
		(net "GND")
	)
	(via
		(at 43.228006 -392.154664)
		(size 1.016)
		(drill 0.508)
		(layers "F.Cu" "B.Cu")
		(net "GND")
	)
	(via
		(at 70.260718 -61.3156)
		(size 0.508)
		(drill 0.254)
		(layers "F.Cu" "B.Cu")
		(net "GND")
	)
	(via
		(at 58.716672 -251.234702)
		(size 1.016)
		(drill 0.508)
		(layers "F.Cu" "B.Cu")
		(net "GND")
	)
	(via
		(at 40.637714 -529.236178)
		(size 0.508)
		(drill 0.254)
		(layers "F.Cu" "B.Cu")
		(net "GND")
	)
	(via
		(at 78.397354 -16.199612)
		(size 0.508)
		(drill 0.254)
		(layers "F.Cu" "B.Cu")
		(net "GND")
	)
	(via
		(at 60.080398 -64.129666)
		(size 1.016)
		(drill 0.508)
		(layers "F.Cu" "B.Cu")
		(net "GND")
	)
	(via
		(at 24.774144 -95.65132)
		(size 0.508)
		(drill 0.254)
		(layers "F.Cu" "B.Cu")
		(net "GND")
	)
	(via
		(at 14.594332 -318.358012)
		(size 0.508)
		(drill 0.254)
		(layers "F.Cu" "B.Cu")
		(net "GND")
	)
	(via
		(at 44.925234 -298.769024)
		(size 1.016)
		(drill 0.508)
		(layers "F.Cu" "B.Cu")
		(net "GND")
	)
	(via
		(at 71.423276 -239.126268)
		(size 0.508)
		(drill 0.254)
		(layers "F.Cu" "B.Cu")
		(net "GND")
	)
	(via
		(at 69.905626 -0.762508)
		(size 0.508)
		(drill 0.254)
		(layers "F.Cu" "B.Cu")
		(net "GND")
	)
	(via
		(at 38.58768 -485.317292)
		(size 1.016)
		(drill 0.508)
		(layers "F.Cu" "B.Cu")
		(net "GND")
	)
	(via
		(at 61.984382 -62.22873)
		(size 1.016)
		(drill 0.508)
		(layers "F.Cu" "B.Cu")
		(net "GND")
	)
	(via
		(at 0.762254 -381.008636)
		(size 0.508)
		(drill 0.254)
		(layers "F.Cu" "B.Cu")
		(net "GND")
	)
	(via
		(at 0.762254 -139.708636)
		(size 0.508)
		(drill 0.254)
		(layers "F.Cu" "B.Cu")
		(net "GND")
	)
	(via
		(at 42.715434 -487.227118)
		(size 1.016)
		(drill 0.508)
		(layers "F.Cu" "B.Cu")
		(net "GND")
	)
	(via
		(at 57.795922 -71.747634)
		(size 1.016)
		(drill 0.508)
		(layers "F.Cu" "B.Cu")
		(net "GND")
	)
	(via
		(at 60.551314 -150.883366)
		(size 1.016)
		(drill 0.508)
		(layers "F.Cu" "B.Cu")
		(net "GND")
	)
	(via
		(at 6.405626 -4.763008)
		(size 0.508)
		(drill 0.254)
		(layers "F.Cu" "B.Cu")
		(net "GND")
	)
	(via
		(at 59.023758 -124.535946)
		(size 1.016)
		(drill 0.508)
		(layers "F.Cu" "B.Cu")
		(net "GND")
	)
	(via
		(at 45.175424 -382.63576)
		(size 1.016)
		(drill 0.508)
		(layers "F.Cu" "B.Cu")
		(net "GND")
	)
	(via
		(at 24.801322 -100.590096)
		(size 0.508)
		(drill 0.254)
		(layers "F.Cu" "B.Cu")
		(net "GND")
	)
	(via
		(at 39.439342 -218.491054)
		(size 1.016)
		(drill 0.508)
		(layers "F.Cu" "B.Cu")
		(net "GND")
	)
	(via
		(at 102.238048 -448.845432)
		(size 0.508)
		(drill 0.254)
		(layers "F.Cu" "B.Cu")
		(net "GND")
	)
	(via
		(at 13.743432 -396.021052)
		(size 0.508)
		(drill 0.254)
		(layers "F.Cu" "B.Cu")
		(net "GND")
	)
	(via
		(at 60.603384 -251.234702)
		(size 1.016)
		(drill 0.508)
		(layers "F.Cu" "B.Cu")
		(net "GND")
	)
	(via
		(at 63.215012 -427.85411)
		(size 1.016)
		(drill 0.508)
		(layers "F.Cu" "B.Cu")
		(net "GND")
	)
	(via
		(at 60.603384 -249.34418)
		(size 1.016)
		(drill 0.508)
		(layers "F.Cu" "B.Cu")
		(net "GND")
	)
	(via
		(at 0.762254 -342.908636)
		(size 0.508)
		(drill 0.254)
		(layers "F.Cu" "B.Cu")
		(net "GND")
	)
	(via
		(at 41.369488 -212.548216)
		(size 1.016)
		(drill 0.508)
		(layers "F.Cu" "B.Cu")
		(net "GND")
	)
	(via
		(at 24.773636 -186.752992)
		(size 0.508)
		(drill 0.254)
		(layers "F.Cu" "B.Cu")
		(net "GND")
	)
	(via
		(at 102.238048 -144.045432)
		(size 0.508)
		(drill 0.254)
		(layers "F.Cu" "B.Cu")
		(net "GND")
	)
	(via
		(at 24.624792 -277.377144)
		(size 0.508)
		(drill 0.254)
		(layers "F.Cu" "B.Cu")
		(net "GND")
	)
	(via
		(at 44.458382 -70.179438)
		(size 1.016)
		(drill 0.508)
		(layers "F.Cu" "B.Cu")
		(net "GND")
	)
	(via
		(at 25.035256 -181.847998)
		(size 0.508)
		(drill 0.254)
		(layers "F.Cu" "B.Cu")
		(net "GND")
	)
	(via
		(at 93.006926 -345.450922)
		(size 1.016)
		(drill 0.508)
		(layers "F.Cu" "B.Cu")
		(net "GND")
	)
	(via
		(at 60.50788 -156.470604)
		(size 1.016)
		(drill 0.508)
		(layers "F.Cu" "B.Cu")
		(net "GND")
	)
	(via
		(at 41.245536 -14.412976)
		(size 0.508)
		(drill 0.254)
		(layers "F.Cu" "B.Cu")
		(net "GND")
	)
	(via
		(at 61.308234 -118.948708)
		(size 1.016)
		(drill 0.508)
		(layers "F.Cu" "B.Cu")
		(net "GND")
	)
	(via
		(at 40.474392 -481.385626)
		(size 1.016)
		(drill 0.508)
		(layers "F.Cu" "B.Cu")
		(net "GND")
	)
	(via
		(at 59.069986 -427.85411)
		(size 1.016)
		(drill 0.508)
		(layers "F.Cu" "B.Cu")
		(net "GND")
	)
	(via
		(at 71.825104 -130.134614)
		(size 0.508)
		(drill 0.254)
		(layers "F.Cu" "B.Cu")
		(net "GND")
	)
	(via
		(at 73.512934 -416.955732)
		(size 0.508)
		(drill 0.254)
		(layers "F.Cu" "B.Cu")
		(net "GND")
	)
	(via
		(at 38.58768 -481.385626)
		(size 1.016)
		(drill 0.508)
		(layers "F.Cu" "B.Cu")
		(net "GND")
	)
	(via
		(at 102.238048 -486.945432)
		(size 0.508)
		(drill 0.254)
		(layers "F.Cu" "B.Cu")
		(net "GND")
	)
	(via
		(at 72.590152 -219.008198)
		(size 0.508)
		(drill 0.254)
		(layers "F.Cu" "B.Cu")
		(net "GND")
	)
	(via
		(at 60.50788 -158.361126)
		(size 1.016)
		(drill 0.508)
		(layers "F.Cu" "B.Cu")
		(net "GND")
	)
	(via
		(at 62.844426 -251.234702)
		(size 1.016)
		(drill 0.508)
		(layers "F.Cu" "B.Cu")
		(net "GND")
	)
	(via
		(at 38.850062 -304.356262)
		(size 1.016)
		(drill 0.508)
		(layers "F.Cu" "B.Cu")
		(net "GND")
	)
	(via
		(at 58.621168 -156.470604)
		(size 1.016)
		(drill 0.508)
		(layers "F.Cu" "B.Cu")
		(net "GND")
	)
	(via
		(at 102.238048 -232.945432)
		(size 0.508)
		(drill 0.254)
		(layers "F.Cu" "B.Cu")
		(net "GND")
	)
	(via
		(at 102.238048 -410.745432)
		(size 0.508)
		(drill 0.254)
		(layers "F.Cu" "B.Cu")
		(net "GND")
	)
	(via
		(at 64.69634 -152.784302)
		(size 1.016)
		(drill 0.508)
		(layers "F.Cu" "B.Cu")
		(net "GND")
	)
	(via
		(at 24.636984 -365.50092)
		(size 0.508)
		(drill 0.254)
		(layers "F.Cu" "B.Cu")
		(net "GND")
	)
	(via
		(at 102.238048 -80.545432)
		(size 0.508)
		(drill 0.254)
		(layers "F.Cu" "B.Cu")
		(net "GND")
	)
	(via
		(at 26.445464 -20.969478)
		(size 0.508)
		(drill 0.254)
		(layers "F.Cu" "B.Cu")
		(net "GND")
	)
	(via
		(at 41.030398 -380.802134)
		(size 1.016)
		(drill 0.508)
		(layers "F.Cu" "B.Cu")
		(net "GND")
	)
	(via
		(at 24.84755 -360.550968)
		(size 0.508)
		(drill 0.254)
		(layers "F.Cu" "B.Cu")
		(net "GND")
	)
	(via
		(at 102.238048 -474.245432)
		(size 0.508)
		(drill 0.254)
		(layers "F.Cu" "B.Cu")
		(net "GND")
	)
	(via
		(at 73.00468 -41.28516)
		(size 0.508)
		(drill 0.254)
		(layers "F.Cu" "B.Cu")
		(net "GND")
	)
	(via
		(at 24.580596 -272.345404)
		(size 0.508)
		(drill 0.254)
		(layers "F.Cu" "B.Cu")
		(net "GND")
	)
	(via
		(at 79.524606 -16.199612)
		(size 0.508)
		(drill 0.254)
		(layers "F.Cu" "B.Cu")
		(net "GND")
	)
	(via
		(at 70.678548 -485.985058)
		(size 0.508)
		(drill 0.254)
		(layers "F.Cu" "B.Cu")
		(net "GND")
	)
	(via
		(at 60.619386 -306.775358)
		(size 1.016)
		(drill 0.508)
		(layers "F.Cu" "B.Cu")
		(net "GND")
	)
	(via
		(at 63.171578 -431.755804)
		(size 1.016)
		(drill 0.508)
		(layers "F.Cu" "B.Cu")
		(net "GND")
	)
	(via
		(at 44.925234 -302.34509)
		(size 1.016)
		(drill 0.508)
		(layers "F.Cu" "B.Cu")
		(net "GND")
	)
	(via
		(at 63.212218 -118.948708)
		(size 1.016)
		(drill 0.508)
		(layers "F.Cu" "B.Cu")
		(net "GND")
	)
	(via
		(at 64.764412 -308.685184)
		(size 1.016)
		(drill 0.508)
		(layers "F.Cu" "B.Cu")
		(net "GND")
	)
	(via
		(at 102.238048 -525.045432)
		(size 0.508)
		(drill 0.254)
		(layers "F.Cu" "B.Cu")
		(net "GND")
	)
	(via
		(at 61.984382 -64.129666)
		(size 1.016)
		(drill 0.508)
		(layers "F.Cu" "B.Cu")
		(net "GND")
	)
	(via
		(at 25.057608 -278.486362)
		(size 0.508)
		(drill 0.254)
		(layers "F.Cu" "B.Cu")
		(net "GND")
	)
	(via
		(at 90.015314 -345.450922)
		(size 1.016)
		(drill 0.508)
		(layers "F.Cu" "B.Cu")
		(net "GND")
	)
	(via
		(at 0.762254 -13.216636)
		(size 0.508)
		(drill 0.254)
		(layers "F.Cu" "B.Cu")
		(net "GND")
	)
	(via
		(at 72.928734 -485.985058)
		(size 0.508)
		(drill 0.254)
		(layers "F.Cu" "B.Cu")
		(net "GND")
	)
	(via
		(at 102.238048 -17.045432)
		(size 0.508)
		(drill 0.254)
		(layers "F.Cu" "B.Cu")
		(net "GND")
	)
	(via
		(at 71.903844 -41.31945)
		(size 0.508)
		(drill 0.254)
		(layers "F.Cu" "B.Cu")
		(net "GND")
	)
	(via
		(at 44.177712 -32.03194)
		(size 1.016)
		(drill 0.508)
		(layers "F.Cu" "B.Cu")
		(net "GND")
	)
	(via
		(at 40.986964 -388.222998)
		(size 1.016)
		(drill 0.508)
		(layers "F.Cu" "B.Cu")
		(net "GND")
	)
	(via
		(at 60.036964 -67.815968)
		(size 1.016)
		(drill 0.508)
		(layers "F.Cu" "B.Cu")
		(net "GND")
	)
	(via
		(at 0.762254 -50.808636)
		(size 0.508)
		(drill 0.254)
		(layers "F.Cu" "B.Cu")
		(net "GND")
	)
	(via
		(at 38.58768 -487.227118)
		(size 1.016)
		(drill 0.508)
		(layers "F.Cu" "B.Cu")
		(net "GND")
	)
	(via
		(at 57.183274 -426.17898)
		(size 1.016)
		(drill 0.508)
		(layers "F.Cu" "B.Cu")
		(net "GND")
	)
	(via
		(at 39.100252 -394.06449)
		(size 1.016)
		(drill 0.508)
		(layers "F.Cu" "B.Cu")
		(net "GND")
	)
	(via
		(at 61.267594 -429.865282)
		(size 1.016)
		(drill 0.508)
		(layers "F.Cu" "B.Cu")
		(net "GND")
	)
	(via
		(at 91.437714 -529.236178)
		(size 0.508)
		(drill 0.254)
		(layers "F.Cu" "B.Cu")
		(net "GND")
	)
	(via
		(at 0.762254 -292.108636)
		(size 0.508)
		(drill 0.254)
		(layers "F.Cu" "B.Cu")
		(net "GND")
	)
	(via
		(at 102.238048 -436.145432)
		(size 0.508)
		(drill 0.254)
		(layers "F.Cu" "B.Cu")
		(net "GND")
	)
	(via
		(at 39.439342 -214.559388)
		(size 1.016)
		(drill 0.508)
		(layers "F.Cu" "B.Cu")
		(net "GND")
	)
	(via
		(at 78.737714 -529.236178)
		(size 0.508)
		(drill 0.254)
		(layers "F.Cu" "B.Cu")
		(net "GND")
	)
	(via
		(at 72.802242 -460.8576)
		(size 0.508)
		(drill 0.254)
		(layers "F.Cu" "B.Cu")
		(net "GND")
	)
	(via
		(at 63.171578 -429.865282)
		(size 1.016)
		(drill 0.508)
		(layers "F.Cu" "B.Cu")
		(net "GND")
	)
	(via
		(at 42.247566 -35.718242)
		(size 1.016)
		(drill 0.508)
		(layers "F.Cu" "B.Cu")
		(net "GND")
	)
	(via
		(at 0.762254 -190.508636)
		(size 0.508)
		(drill 0.254)
		(layers "F.Cu" "B.Cu")
		(net "GND")
	)
	(via
		(at 59.067192 -117.115082)
		(size 1.016)
		(drill 0.508)
		(layers "F.Cu" "B.Cu")
		(net "GND")
	)
	(via
		(at 93.006926 -347.413834)
		(size 1.016)
		(drill 0.508)
		(layers "F.Cu" "B.Cu")
		(net "GND")
	)
	(via
		(at 41.326054 -216.44991)
		(size 1.016)
		(drill 0.508)
		(layers "F.Cu" "B.Cu")
		(net "GND")
	)
	(via
		(at 38.631114 -473.964762)
		(size 1.016)
		(drill 0.508)
		(layers "F.Cu" "B.Cu")
		(net "GND")
	)
	(via
		(at 41.082468 -18.414238)
		(size 0.508)
		(drill 0.254)
		(layers "F.Cu" "B.Cu")
		(net "GND")
	)
	(via
		(at 61.308234 -122.524774)
		(size 1.016)
		(drill 0.508)
		(layers "F.Cu" "B.Cu")
		(net "GND")
	)
	(via
		(at 43.61053 -210.873086)
		(size 1.016)
		(drill 0.508)
		(layers "F.Cu" "B.Cu")
		(net "GND")
	)
	(via
		(at 4.186936 -394.248386)
		(size 0.508)
		(drill 0.254)
		(layers "F.Cu" "B.Cu")
		(net "GND")
	)
	(via
		(at 39.482776 -210.873086)
		(size 1.016)
		(drill 0.508)
		(layers "F.Cu" "B.Cu")
		(net "GND")
	)
	(via
		(at 73.63333 -85.772752)
		(size 0.508)
		(drill 0.254)
		(layers "F.Cu" "B.Cu")
		(net "GND")
	)
	(via
		(at 0.762254 -419.108636)
		(size 0.508)
		(drill 0.254)
		(layers "F.Cu" "B.Cu")
		(net "GND")
	)
	(via
		(at 25.157938 -453.535034)
		(size 0.508)
		(drill 0.254)
		(layers "F.Cu" "B.Cu")
		(net "GND")
	)
	(via
		(at 61.311028 -427.85411)
		(size 1.016)
		(drill 0.508)
		(layers "F.Cu" "B.Cu")
		(net "GND")
	)
	(via
		(at 0.762254 -266.708636)
		(size 0.508)
		(drill 0.254)
		(layers "F.Cu" "B.Cu")
		(net "GND")
	)
	(via
		(at 41.057576 -194.114674)
		(size 0.508)
		(drill 0.254)
		(layers "F.Cu" "B.Cu")
		(net "GND")
	)
	(via
		(at 64.652906 -156.470604)
		(size 1.016)
		(drill 0.508)
		(layers "F.Cu" "B.Cu")
		(net "GND")
	)
	(via
		(at 44.414948 -73.86574)
		(size 1.016)
		(drill 0.508)
		(layers "F.Cu" "B.Cu")
		(net "GND")
	)
	(via
		(at 82.499962 -505.529088)
		(size 0.508)
		(drill 0.254)
		(layers "F.Cu" "B.Cu")
		(net "GND")
	)
	(via
		(at 46.825662 -254.395224)
		(size 0.508)
		(drill 0.254)
		(layers "F.Cu" "B.Cu")
		(net "GND")
	)
	(via
		(at 44.177712 -28.297378)
		(size 1.016)
		(drill 0.508)
		(layers "F.Cu" "B.Cu")
		(net "GND")
	)
	(via
		(at 38.893496 -300.66996)
		(size 1.016)
		(drill 0.508)
		(layers "F.Cu" "B.Cu")
		(net "GND")
	)
	(via
		(at 59.023758 -130.377438)
		(size 1.016)
		(drill 0.508)
		(layers "F.Cu" "B.Cu")
		(net "GND")
	)
	(via
		(at 61.2648 -126.426468)
		(size 1.016)
		(drill 0.508)
		(layers "F.Cu" "B.Cu")
		(net "GND")
	)
	(via
		(at 44.619418 -487.227118)
		(size 1.016)
		(drill 0.508)
		(layers "F.Cu" "B.Cu")
		(net "GND")
	)
	(via
		(at 60.50788 -160.40227)
		(size 1.016)
		(drill 0.508)
		(layers "F.Cu" "B.Cu")
		(net "GND")
	)
	(via
		(at 0.762254 -520.708636)
		(size 0.508)
		(drill 0.254)
		(layers "F.Cu" "B.Cu")
		(net "GND")
	)
	(via
		(at 63.06312 -21.955506)
		(size 1.016)
		(drill 0.508)
		(layers "F.Cu" "B.Cu")
		(net "GND")
	)
	(via
		(at 102.238048 -245.645432)
		(size 0.508)
		(drill 0.254)
		(layers "F.Cu" "B.Cu")
		(net "GND")
	)
	(via
		(at 44.8818 -304.356262)
		(size 1.016)
		(drill 0.508)
		(layers "F.Cu" "B.Cu")
		(net "GND")
	)
	(via
		(at 40.989758 -103.52405)
		(size 0.508)
		(drill 0.254)
		(layers "F.Cu" "B.Cu")
		(net "GND")
	)
	(via
		(at 102.238048 -461.545432)
		(size 0.508)
		(drill 0.254)
		(layers "F.Cu" "B.Cu")
		(net "GND")
	)
	(via
		(at 47.84979 -259.28574)
		(size 0.508)
		(drill 0.254)
		(layers "F.Cu" "B.Cu")
		(net "GND")
	)
	(via
		(at 70.877176 -158.655258)
		(size 1.016)
		(drill 0.508)
		(layers "F.Cu" "B.Cu")
		(net "GND")
	)
	(via
		(at 43.27144 -382.63576)
		(size 1.016)
		(drill 0.508)
		(layers "F.Cu" "B.Cu")
		(net "GND")
	)
	(via
		(at 102.238048 -499.645432)
		(size 0.508)
		(drill 0.254)
		(layers "F.Cu" "B.Cu")
		(net "GND")
	)
	(via
		(at 61.2648 -130.377438)
		(size 1.016)
		(drill 0.508)
		(layers "F.Cu" "B.Cu")
		(net "GND")
	)
	(via
		(at 17.162272 -329.350116)
		(size 0.508)
		(drill 0.254)
		(layers "F.Cu" "B.Cu")
		(net "GND")
	)
	(via
		(at 60.551314 -154.459432)
		(size 1.016)
		(drill 0.508)
		(layers "F.Cu" "B.Cu")
		(net "GND")
	)
	(via
		(at 24.750522 -187.950348)
		(size 0.508)
		(drill 0.254)
		(layers "F.Cu" "B.Cu")
		(net "GND")
	)
	(via
		(at 24.743918 -9.509252)
		(size 0.508)
		(drill 0.254)
		(layers "F.Cu" "B.Cu")
		(net "GND")
	)
	(via
		(at 69.580252 -130.134614)
		(size 0.508)
		(drill 0.254)
		(layers "F.Cu" "B.Cu")
		(net "GND")
	)
	(via
		(at 62.844426 -255.185672)
		(size 1.016)
		(drill 0.508)
		(layers "F.Cu" "B.Cu")
		(net "GND")
	)
	(via
		(at 61.267594 -433.796948)
		(size 1.016)
		(drill 0.508)
		(layers "F.Cu" "B.Cu")
		(net "GND")
	)
	(via
		(at 79.729076 -384.526282)
		(size 0.508)
		(drill 0.254)
		(layers "F.Cu" "B.Cu")
		(net "GND")
	)
	(via
		(at 60.646818 -245.657878)
		(size 1.016)
		(drill 0.508)
		(layers "F.Cu" "B.Cu")
		(net "GND")
	)
	(via
		(at 44.619418 -483.276148)
		(size 1.016)
		(drill 0.508)
		(layers "F.Cu" "B.Cu")
		(net "GND")
	)
	(via
		(at 31.805626 -0.762508)
		(size 0.508)
		(drill 0.254)
		(layers "F.Cu" "B.Cu")
		(net "GND")
	)
	(via
		(at 73.57745 -395.785594)
		(size 0.508)
		(drill 0.254)
		(layers "F.Cu" "B.Cu")
		(net "GND")
	)
	(via
		(at 63.168784 -126.426468)
		(size 1.016)
		(drill 0.508)
		(layers "F.Cu" "B.Cu")
		(net "GND")
	)
	(via
		(at 61.2648 -124.535946)
		(size 1.016)
		(drill 0.508)
		(layers "F.Cu" "B.Cu")
		(net "GND")
	)
	(via
		(at 41.427146 -370.099336)
		(size 0.508)
		(drill 0.254)
		(layers "F.Cu" "B.Cu")
		(net "GND")
	)
	(via
		(at 90.015314 -347.413834)
		(size 1.016)
		(drill 0.508)
		(layers "F.Cu" "B.Cu")
		(net "GND")
	)
	(via
		(at 25.163272 -447.250058)
		(size 0.508)
		(drill 0.254)
		(layers "F.Cu" "B.Cu")
		(net "GND")
	)
	(via
		(at 62.844426 -253.275846)
		(size 1.016)
		(drill 0.508)
		(layers "F.Cu" "B.Cu")
		(net "GND")
	)
	(via
		(at 73.426828 -306.521358)
		(size 0.508)
		(drill 0.254)
		(layers "F.Cu" "B.Cu")
		(net "GND")
	)
	(via
		(at 60.619386 -308.685184)
		(size 1.016)
		(drill 0.508)
		(layers "F.Cu" "B.Cu")
		(net "GND")
	)
	(via
		(at 19.17065 -334.086962)
		(size 0.508)
		(drill 0.254)
		(layers "F.Cu" "B.Cu")
		(net "GND")
	)
	(via
		(at 90.015314 -340.411054)
		(size 1.016)
		(drill 0.508)
		(layers "F.Cu" "B.Cu")
		(net "GND")
	)
	(via
		(at 41.296844 -17.30502)
		(size 0.508)
		(drill 0.254)
		(layers "F.Cu" "B.Cu")
		(net "GND")
	)
	(via
		(at 72.520302 -85.772752)
		(size 0.508)
		(drill 0.254)
		(layers "F.Cu" "B.Cu")
		(net "GND")
	)
	(via
		(at 38.631114 -477.699324)
		(size 1.016)
		(drill 0.508)
		(layers "F.Cu" "B.Cu")
		(net "GND")
	)
	(via
		(at 46.765972 -258.89712)
		(size 0.508)
		(drill 0.254)
		(layers "F.Cu" "B.Cu")
		(net "GND")
	)
	(via
		(at 71.96836 -174.546768)
		(size 0.508)
		(drill 0.254)
		(layers "F.Cu" "B.Cu")
		(net "GND")
	)
	(via
		(at 80.662018 -16.199612)
		(size 0.508)
		(drill 0.254)
		(layers "F.Cu" "B.Cu")
		(net "GND")
	)
	(via
		(at 63.171578 -435.706774)
		(size 1.016)
		(drill 0.508)
		(layers "F.Cu" "B.Cu")
		(net "GND")
	)
	(via
		(at 25.113742 -452.257668)
		(size 0.508)
		(drill 0.254)
		(layers "F.Cu" "B.Cu")
		(net "GND")
	)
	(via
		(at 59.069986 -424.278044)
		(size 1.016)
		(drill 0.508)
		(layers "F.Cu" "B.Cu")
		(net "GND")
	)
	(via
		(at 57.839356 -65.804796)
		(size 1.016)
		(drill 0.508)
		(layers "F.Cu" "B.Cu")
		(net "GND")
	)
	(via
		(at 64.74841 -251.234702)
		(size 1.016)
		(drill 0.508)
		(layers "F.Cu" "B.Cu")
		(net "GND")
	)
	(via
		(at 39.143686 -384.536696)
		(size 1.016)
		(drill 0.508)
		(layers "F.Cu" "B.Cu")
		(net "GND")
	)
	(via
		(at 59.026552 -429.865282)
		(size 1.016)
		(drill 0.508)
		(layers "F.Cu" "B.Cu")
		(net "GND")
	)
	(via
		(at 57.795922 -69.70649)
		(size 1.016)
		(drill 0.508)
		(layers "F.Cu" "B.Cu")
		(net "GND")
	)
	(via
		(at 40.986964 -394.06449)
		(size 1.016)
		(drill 0.508)
		(layers "F.Cu" "B.Cu")
		(net "GND")
	)
	(via
		(at 58.732674 -306.775358)
		(size 1.016)
		(drill 0.508)
		(layers "F.Cu" "B.Cu")
		(net "GND")
	)
	(via
		(at 90.015314 -343.079324)
		(size 1.016)
		(drill 0.508)
		(layers "F.Cu" "B.Cu")
		(net "GND")
	)
	(via
		(at 39.100252 -392.154664)
		(size 1.016)
		(drill 0.508)
		(layers "F.Cu" "B.Cu")
		(net "GND")
	)
	(via
		(at 59.067192 -120.849644)
		(size 1.016)
		(drill 0.508)
		(layers "F.Cu" "B.Cu")
		(net "GND")
	)
	(via
		(at 102.238048 -296.445432)
		(size 0.508)
		(drill 0.254)
		(layers "F.Cu" "B.Cu")
		(net "GND")
	)
	(via
		(at 0.762254 -152.408636)
		(size 0.508)
		(drill 0.254)
		(layers "F.Cu" "B.Cu")
		(net "GND")
	)
	(via
		(at 45.47108 -216.44991)
		(size 1.016)
		(drill 0.508)
		(layers "F.Cu" "B.Cu")
		(net "GND")
	)
	(via
		(at 62.748922 -158.361126)
		(size 1.016)
		(drill 0.508)
		(layers "F.Cu" "B.Cu")
		(net "GND")
	)
	(via
		(at 42.247566 -39.649908)
		(size 1.016)
		(drill 0.508)
		(layers "F.Cu" "B.Cu")
		(net "GND")
	)
	(via
		(at 43.02125 -300.66996)
		(size 1.016)
		(drill 0.508)
		(layers "F.Cu" "B.Cu")
		(net "GND")
	)
	(via
		(at 64.74841 -249.34418)
		(size 1.016)
		(drill 0.508)
		(layers "F.Cu" "B.Cu")
		(net "GND")
	)
	(via
		(at 43.567096 -216.44991)
		(size 1.016)
		(drill 0.508)
		(layers "F.Cu" "B.Cu")
		(net "GND")
	)
	(via
		(at 62.748922 -162.312096)
		(size 1.016)
		(drill 0.508)
		(layers "F.Cu" "B.Cu")
		(net "GND")
	)
	(via
		(at 40.780208 -300.66996)
		(size 1.016)
		(drill 0.508)
		(layers "F.Cu" "B.Cu")
		(net "GND")
	)
	(via
		(at 102.238048 -55.145432)
		(size 0.508)
		(drill 0.254)
		(layers "F.Cu" "B.Cu")
		(net "GND")
	)
	(via
		(at 68.607686 -174.546768)
		(size 0.508)
		(drill 0.254)
		(layers "F.Cu" "B.Cu")
		(net "GND")
	)
	(via
		(at 58.760106 -247.333008)
		(size 1.016)
		(drill 0.508)
		(layers "F.Cu" "B.Cu")
		(net "GND")
	)
	(via
		(at 69.847714 -117.627146)
		(size 0.508)
		(drill 0.254)
		(layers "F.Cu" "B.Cu")
		(net "GND")
	)
	(via
		(at 74.69886 -416.955732)
		(size 0.508)
		(drill 0.254)
		(layers "F.Cu" "B.Cu")
		(net "GND")
	)
	(via
		(at 46.896528 -249.789442)
		(size 0.508)
		(drill 0.254)
		(layers "F.Cu" "B.Cu")
		(net "GND")
	)
	(via
		(at 68.59778 -206.296768)
		(size 0.508)
		(drill 0.254)
		(layers "F.Cu" "B.Cu")
		(net "GND")
	)
	(via
		(at 0.762254 -368.308636)
		(size 0.508)
		(drill 0.254)
		(layers "F.Cu" "B.Cu")
		(net "GND")
	)
	(via
		(at 44.619418 -481.385626)
		(size 1.016)
		(drill 0.508)
		(layers "F.Cu" "B.Cu")
		(net "GND")
	)
	(via
		(at 44.458382 -68.278502)
		(size 1.016)
		(drill 0.508)
		(layers "F.Cu" "B.Cu")
		(net "GND")
	)
	(via
		(at 40.986964 -392.154664)
		(size 1.016)
		(drill 0.508)
		(layers "F.Cu" "B.Cu")
		(net "GND")
	)
	(via
		(at 25.715976 -196.6214)
		(size 0.508)
		(drill 0.254)
		(layers "F.Cu" "B.Cu")
		(net "GND")
	)
	(via
		(at 53.337714 -529.236178)
		(size 0.508)
		(drill 0.254)
		(layers "F.Cu" "B.Cu")
		(net "GND")
	)
	(via
		(at 95.305626 -0.762508)
		(size 0.508)
		(drill 0.254)
		(layers "F.Cu" "B.Cu")
		(net "GND")
	)
	(via
		(at 71.810118 -485.985058)
		(size 0.508)
		(drill 0.254)
		(layers "F.Cu" "B.Cu")
		(net "GND")
	)
	(via
		(at 81.78927 -16.199612)
		(size 0.508)
		(drill 0.254)
		(layers "F.Cu" "B.Cu")
		(net "GND")
	)
	(via
		(at 71.044562 -441.553092)
		(size 0.508)
		(drill 0.254)
		(layers "F.Cu" "B.Cu")
		(net "GND")
	)
	(via
		(at 61.311028 -426.17898)
		(size 1.016)
		(drill 0.508)
		(layers "F.Cu" "B.Cu")
		(net "GND")
	)
	(via
		(at 68.457064 -130.134614)
		(size 0.508)
		(drill 0.254)
		(layers "F.Cu" "B.Cu")
		(net "GND")
	)
	(via
		(at 93.006926 -340.411054)
		(size 1.016)
		(drill 0.508)
		(layers "F.Cu" "B.Cu")
		(net "GND")
	)
	(via
		(at 74.153522 -41.30802)
		(size 0.508)
		(drill 0.254)
		(layers "F.Cu" "B.Cu")
		(net "GND")
	)
	(via
		(at 45.514514 -212.548216)
		(size 1.016)
		(drill 0.508)
		(layers "F.Cu" "B.Cu")
		(net "GND")
	)
	(via
		(at 0.762254 -88.908636)
		(size 0.508)
		(drill 0.254)
		(layers "F.Cu" "B.Cu")
		(net "GND")
	)
	(via
		(at 40.986964 -390.11352)
		(size 1.016)
		(drill 0.508)
		(layers "F.Cu" "B.Cu")
		(net "GND")
	)
	(via
		(at 40.517826 -479.374454)
		(size 1.016)
		(drill 0.508)
		(layers "F.Cu" "B.Cu")
		(net "GND")
	)
	(via
		(at 0.762254 -165.108636)
		(size 0.508)
		(drill 0.254)
		(layers "F.Cu" "B.Cu")
		(net "GND")
	)
	(via
		(at 60.603384 -255.185672)
		(size 1.016)
		(drill 0.508)
		(layers "F.Cu" "B.Cu")
		(net "GND")
	)
	(via
		(at 0.762254 -254.008636)
		(size 0.508)
		(drill 0.254)
		(layers "F.Cu" "B.Cu")
		(net "GND")
	)
	(via
		(at 40.517826 -477.699324)
		(size 1.016)
		(drill 0.508)
		(layers "F.Cu" "B.Cu")
		(net "GND")
	)
	(via
		(at 102.238048 -42.445432)
		(size 0.508)
		(drill 0.254)
		(layers "F.Cu" "B.Cu")
		(net "GND")
	)
	(via
		(at 40.927274 -196.819012)
		(size 0.508)
		(drill 0.254)
		(layers "F.Cu" "B.Cu")
		(net "GND")
	)
	(via
		(at 79.898748 -506.498098)
		(size 0.508)
		(drill 0.254)
		(layers "F.Cu" "B.Cu")
		(net "GND")
	)
	(via
		(at 70.095364 -239.970818)
		(size 0.508)
		(drill 0.254)
		(layers "F.Cu" "B.Cu")
		(net "GND")
	)
	(via
		(at 0.762254 -279.408636)
		(size 0.508)
		(drill 0.254)
		(layers "F.Cu" "B.Cu")
		(net "GND")
	)
	(via
		(at 63.106554 -16.378682)
		(size 1.016)
		(drill 0.508)
		(layers "F.Cu" "B.Cu")
		(net "GND")
	)
	(via
		(at 63.171578 -433.796948)
		(size 1.016)
		(drill 0.508)
		(layers "F.Cu" "B.Cu")
		(net "GND")
	)
	(via
		(at 24.636222 -366.710722)
		(size 0.508)
		(drill 0.254)
		(layers "F.Cu" "B.Cu")
		(net "GND")
	)
	(via
		(at 41.326054 -220.40088)
		(size 1.016)
		(drill 0.508)
		(layers "F.Cu" "B.Cu")
		(net "GND")
	)
	(via
		(at 39.482776 -208.97215)
		(size 1.016)
		(drill 0.508)
		(layers "F.Cu" "B.Cu")
		(net "GND")
	)
	(via
		(at 64.791844 -245.657878)
		(size 1.016)
		(drill 0.508)
		(layers "F.Cu" "B.Cu")
		(net "GND")
	)
	(via
		(at 60.646818 -243.756942)
		(size 1.016)
		(drill 0.508)
		(layers "F.Cu" "B.Cu")
		(net "GND")
	)
	(via
		(at 42.247566 -37.608764)
		(size 1.016)
		(drill 0.508)
		(layers "F.Cu" "B.Cu")
		(net "GND")
	)
	(via
		(at 102.238048 -309.145432)
		(size 0.508)
		(drill 0.254)
		(layers "F.Cu" "B.Cu")
		(net "GND")
	)
	(via
		(at 44.662852 -479.374454)
		(size 1.016)
		(drill 0.508)
		(layers "F.Cu" "B.Cu")
		(net "GND")
	)
	(via
		(at 39.689786 -124.69622)
		(size 1.016)
		(drill 0.508)
		(layers "F.Cu" "B.Cu")
		(net "GND")
	)
	(via
		(at 60.036964 -69.70649)
		(size 1.016)
		(drill 0.508)
		(layers "F.Cu" "B.Cu")
		(net "GND")
	)
	(via
		(at 72.157844 -417.800282)
		(size 0.508)
		(drill 0.254)
		(layers "F.Cu" "B.Cu")
		(net "GND")
	)
	(via
		(at 42.291 -32.03194)
		(size 1.016)
		(drill 0.508)
		(layers "F.Cu" "B.Cu")
		(net "GND")
	)
	(via
		(at 69.863208 -352.98761)
		(size 0.508)
		(drill 0.254)
		(layers "F.Cu" "B.Cu")
		(net "GND")
	)
	(via
		(at 102.238048 -4.345432)
		(size 0.508)
		(drill 0.254)
		(layers "F.Cu" "B.Cu")
		(net "GND")
	)
	(via
		(at 63.06312 -25.906476)
		(size 1.016)
		(drill 0.508)
		(layers "F.Cu" "B.Cu")
		(net "GND")
	)
	(via
		(at 0.762254 -469.908636)
		(size 0.508)
		(drill 0.254)
		(layers "F.Cu" "B.Cu")
		(net "GND")
	)
	(via
		(at 82.605626 -0.762508)
		(size 0.508)
		(drill 0.254)
		(layers "F.Cu" "B.Cu")
		(net "GND")
	)
	(via
		(at 59.026552 -431.755804)
		(size 1.016)
		(drill 0.508)
		(layers "F.Cu" "B.Cu")
		(net "GND")
	)
	(via
		(at 64.652906 -158.361126)
		(size 1.016)
		(drill 0.508)
		(layers "F.Cu" "B.Cu")
		(net "GND")
	)
	(via
		(at 6.815582 -525.237964)
		(size 0.508)
		(drill 0.254)
		(layers "F.Cu" "B.Cu")
		(net "GND")
	)
	(via
		(at 63.106554 -18.053812)
		(size 1.016)
		(drill 0.508)
		(layers "F.Cu" "B.Cu")
		(net "GND")
	)
	(via
		(at 61.940948 -67.815968)
		(size 1.016)
		(drill 0.508)
		(layers "F.Cu" "B.Cu")
		(net "GND")
	)
	(via
		(at 2.965958 -147.006564)
		(size 0.508)
		(drill 0.254)
		(layers "F.Cu" "B.Cu")
		(net "GND")
	)
	(via
		(at 45.175424 -384.536696)
		(size 1.016)
		(drill 0.508)
		(layers "F.Cu" "B.Cu")
		(net "GND")
	)
	(via
		(at 2.81559 -394.357606)
		(size 0.508)
		(drill 0.254)
		(layers "F.Cu" "B.Cu")
		(net "GND")
	)
	(via
		(at 44.177712 -30.131004)
		(size 1.016)
		(drill 0.508)
		(layers "F.Cu" "B.Cu")
		(net "GND")
	)
	(via
		(at 38.631114 -475.798388)
		(size 1.016)
		(drill 0.508)
		(layers "F.Cu" "B.Cu")
		(net "GND")
	)
	(via
		(at 58.621168 -160.40227)
		(size 1.016)
		(drill 0.508)
		(layers "F.Cu" "B.Cu")
		(net "GND")
	)
	(via
		(at 44.458382 -66.444876)
		(size 1.016)
		(drill 0.508)
		(layers "F.Cu" "B.Cu")
		(net "GND")
	)
	(via
		(at 44.134278 -41.559734)
		(size 1.016)
		(drill 0.508)
		(layers "F.Cu" "B.Cu")
		(net "GND")
	)
	(via
		(at 26.839926 -461.067658)
		(size 0.508)
		(drill 0.254)
		(layers "F.Cu" "B.Cu")
		(net "GND")
	)
	(via
		(at 45.47108 -218.491054)
		(size 1.016)
		(drill 0.508)
		(layers "F.Cu" "B.Cu")
		(net "GND")
	)
	(via
		(at 93.006926 -343.079324)
		(size 1.016)
		(drill 0.508)
		(layers "F.Cu" "B.Cu")
		(net "GND")
	)
	(via
		(at 27.937714 -529.236178)
		(size 0.508)
		(drill 0.254)
		(layers "F.Cu" "B.Cu")
		(net "GND")
	)
	(via
		(at 25.042114 -183.06923)
		(size 0.508)
		(drill 0.254)
		(layers "F.Cu" "B.Cu")
		(net "GND")
	)
	(via
		(at 69.133974 -219.037916)
		(size 0.508)
		(drill 0.254)
		(layers "F.Cu" "B.Cu")
		(net "GND")
	)
	(via
		(at 64.74841 -253.275846)
		(size 1.016)
		(drill 0.508)
		(layers "F.Cu" "B.Cu")
		(net "GND")
	)
	(via
		(at 71.405496 -261.915148)
		(size 0.508)
		(drill 0.254)
		(layers "F.Cu" "B.Cu")
		(net "GND")
	)
	(via
		(at 39.100252 -390.11352)
		(size 1.016)
		(drill 0.508)
		(layers "F.Cu" "B.Cu")
		(net "GND")
	)
	(via
		(at 0.762254 -457.208636)
		(size 0.508)
		(drill 0.254)
		(layers "F.Cu" "B.Cu")
		(net "GND")
	)
	(via
		(at 74.775568 -395.785594)
		(size 0.508)
		(drill 0.254)
		(layers "F.Cu" "B.Cu")
		(net "GND")
	)
	(via
		(at 19.105626 -4.763008)
		(size 0.508)
		(drill 0.254)
		(layers "F.Cu" "B.Cu")
		(net "GND")
	)
	(via
		(at 59.023758 -128.467612)
		(size 1.016)
		(drill 0.508)
		(layers "F.Cu" "B.Cu")
		(net "GND")
	)
	(via
		(at 61.159136 -25.906476)
		(size 1.016)
		(drill 0.508)
		(layers "F.Cu" "B.Cu")
		(net "GND")
	)
	(via
		(at 16.21028 -147.232116)
		(size 0.508)
		(drill 0.254)
		(layers "F.Cu" "B.Cu")
		(net "GND")
	)
	(via
		(at 38.893496 -296.935398)
		(size 1.016)
		(drill 0.508)
		(layers "F.Cu" "B.Cu")
		(net "GND")
	)
	(via
		(at 102.238048 -283.745432)
		(size 0.508)
		(drill 0.254)
		(layers "F.Cu" "B.Cu")
		(net "GND")
	)
	(via
		(at 58.732674 -308.685184)
		(size 1.016)
		(drill 0.508)
		(layers "F.Cu" "B.Cu")
		(net "GND")
	)
	(via
		(at 42.291 -33.70707)
		(size 1.016)
		(drill 0.508)
		(layers "F.Cu" "B.Cu")
		(net "GND")
	)
	(via
		(at 58.664602 -154.459432)
		(size 1.016)
		(drill 0.508)
		(layers "F.Cu" "B.Cu")
		(net "GND")
	)
	(via
		(at 39.73322 -119.108982)
		(size 1.016)
		(drill 0.508)
		(layers "F.Cu" "B.Cu")
		(net "GND")
	)
	(via
		(at 69.549518 -485.985058)
		(size 0.508)
		(drill 0.254)
		(layers "F.Cu" "B.Cu")
		(net "GND")
	)
	(via
		(at 57.839356 -64.129666)
		(size 1.016)
		(drill 0.508)
		(layers "F.Cu" "B.Cu")
		(net "GND")
	)
	(via
		(at 38.893496 -302.34509)
		(size 1.016)
		(drill 0.508)
		(layers "F.Cu" "B.Cu")
		(net "GND")
	)
	(via
		(at 74.575924 -472.101672)
		(size 0.508)
		(drill 0.254)
		(layers "F.Cu" "B.Cu")
		(net "GND")
	)
	(via
		(at 70.997572 -352.943922)
		(size 0.508)
		(drill 0.254)
		(layers "F.Cu" "B.Cu")
		(net "GND")
	)
	(via
		(at 58.621168 -158.361126)
		(size 1.016)
		(drill 0.508)
		(layers "F.Cu" "B.Cu")
		(net "GND")
	)
	(via
		(at 63.215012 -426.17898)
		(size 1.016)
		(drill 0.508)
		(layers "F.Cu" "B.Cu")
		(net "GND")
	)
	(via
		(at 58.716672 -255.185672)
		(size 1.016)
		(drill 0.508)
		(layers "F.Cu" "B.Cu")
		(net "GND")
	)
	(via
		(at 39.689786 -130.537712)
		(size 1.016)
		(drill 0.508)
		(layers "F.Cu" "B.Cu")
		(net "GND")
	)
	(via
		(at 69.370956 -195.825872)
		(size 0.508)
		(drill 0.254)
		(layers "F.Cu" "B.Cu")
		(net "GND")
	)
	(via
		(at 24.740362 -361.78236)
		(size 0.508)
		(drill 0.254)
		(layers "F.Cu" "B.Cu")
		(net "GND")
	)
	(via
		(at 40.474392 -487.227118)
		(size 1.016)
		(drill 0.508)
		(layers "F.Cu" "B.Cu")
		(net "GND")
	)
	(via
		(at 39.73322 -121.009918)
		(size 1.016)
		(drill 0.508)
		(layers "F.Cu" "B.Cu")
		(net "GND")
	)
	(via
		(at 61.20257 -16.378682)
		(size 1.016)
		(drill 0.508)
		(layers "F.Cu" "B.Cu")
		(net "GND")
	)
	(via
		(at 0.765048 -408.98191)
		(size 0.508)
		(drill 0.254)
		(layers "F.Cu" "B.Cu")
		(net "GND")
	)
	(via
		(at 25.220676 -454.646538)
		(size 0.508)
		(drill 0.254)
		(layers "F.Cu" "B.Cu")
		(net "GND")
	)
	(via
		(at 75.316842 -41.29659)
		(size 0.508)
		(drill 0.254)
		(layers "F.Cu" "B.Cu")
		(net "GND")
	)
	(via
		(at 24.75611 -367.771426)
		(size 0.508)
		(drill 0.254)
		(layers "F.Cu" "B.Cu")
		(net "GND")
	)
	(via
		(at 58.621168 -162.312096)
		(size 1.016)
		(drill 0.508)
		(layers "F.Cu" "B.Cu")
		(net "GND")
	)
	(via
		(at 61.20257 -14.477746)
		(size 1.016)
		(drill 0.508)
		(layers "F.Cu" "B.Cu")
		(net "GND")
	)
	(via
		(at 61.940948 -71.747634)
		(size 1.016)
		(drill 0.508)
		(layers "F.Cu" "B.Cu")
		(net "GND")
	)
	(via
		(at 90.015314 -337.740244)
		(size 1.016)
		(drill 0.508)
		(layers "F.Cu" "B.Cu")
		(net "GND")
	)
	(via
		(at 71.390764 -462.170526)
		(size 0.508)
		(drill 0.254)
		(layers "F.Cu" "B.Cu")
		(net "GND")
	)
	(via
		(at 44.414948 -75.756262)
		(size 1.016)
		(drill 0.508)
		(layers "F.Cu" "B.Cu")
		(net "GND")
	)
	(via
		(at 40.780208 -302.34509)
		(size 1.016)
		(drill 0.508)
		(layers "F.Cu" "B.Cu")
		(net "GND")
	)
	(via
		(at 102.238048 -118.645432)
		(size 0.508)
		(drill 0.254)
		(layers "F.Cu" "B.Cu")
		(net "GND")
	)
	(via
		(at 72.19696 -352.944176)
		(size 0.508)
		(drill 0.254)
		(layers "F.Cu" "B.Cu")
		(net "GND")
	)
	(via
		(at 0.762254 -76.208636)
		(size 0.508)
		(drill 0.254)
		(layers "F.Cu" "B.Cu")
		(net "GND")
	)
	(via
		(at 42.758868 -479.374454)
		(size 1.016)
		(drill 0.508)
		(layers "F.Cu" "B.Cu")
		(net "GND")
	)
	(via
		(at 0.762254 -393.708636)
		(size 0.508)
		(drill 0.254)
		(layers "F.Cu" "B.Cu")
		(net "GND")
	)
	(via
		(at 57.13984 -435.706774)
		(size 1.016)
		(drill 0.508)
		(layers "F.Cu" "B.Cu")
		(net "GND")
	)
	(via
		(at 68.727066 -352.965004)
		(size 0.508)
		(drill 0.254)
		(layers "F.Cu" "B.Cu")
		(net "GND")
	)
	(via
		(at 57.183274 -424.278044)
		(size 1.016)
		(drill 0.508)
		(layers "F.Cu" "B.Cu")
		(net "GND")
	)
	(via
		(at 41.18356 -281.140662)
		(size 0.508)
		(drill 0.254)
		(layers "F.Cu" "B.Cu")
		(net "GND")
	)
	(via
		(at 60.036964 -73.65746)
		(size 1.016)
		(drill 0.508)
		(layers "F.Cu" "B.Cu")
		(net "GND")
	)
	(via
		(at 44.134278 -39.649908)
		(size 1.016)
		(drill 0.508)
		(layers "F.Cu" "B.Cu")
		(net "GND")
	)
	(via
		(at 44.458382 -71.854568)
		(size 1.016)
		(drill 0.508)
		(layers "F.Cu" "B.Cu")
		(net "GND")
	)
	(via
		(at 62.748922 -156.470604)
		(size 1.016)
		(drill 0.508)
		(layers "F.Cu" "B.Cu")
		(net "GND")
	)
	(via
		(at 102.238048 -423.445432)
		(size 0.508)
		(drill 0.254)
		(layers "F.Cu" "B.Cu")
		(net "GND")
	)
	(via
		(at 15.719552 -169.167048)
		(size 0.508)
		(drill 0.254)
		(layers "F.Cu" "B.Cu")
		(net "GND")
	)
	(via
		(at 72.81291 -106.132376)
		(size 0.508)
		(drill 0.254)
		(layers "F.Cu" "B.Cu")
		(net "GND")
	)
	(via
		(at 64.652906 -162.312096)
		(size 1.016)
		(drill 0.508)
		(layers "F.Cu" "B.Cu")
		(net "GND")
	)
	(via
		(at 43.228006 -390.11352)
		(size 1.016)
		(drill 0.508)
		(layers "F.Cu" "B.Cu")
		(net "GND")
	)
	(via
		(at 57.183274 -422.444418)
		(size 1.016)
		(drill 0.508)
		(layers "F.Cu" "B.Cu")
		(net "GND")
	)
	(via
		(at 41.030398 -386.211826)
		(size 1.016)
		(drill 0.508)
		(layers "F.Cu" "B.Cu")
		(net "GND")
	)
	(via
		(at 63.168784 -130.377438)
		(size 1.016)
		(drill 0.508)
		(layers "F.Cu" "B.Cu")
		(net "GND")
	)
	(via
		(at 61.311028 -424.278044)
		(size 1.016)
		(drill 0.508)
		(layers "F.Cu" "B.Cu")
		(net "GND")
	)
	(via
		(at 46.808136 -240.876074)
		(size 0.508)
		(drill 0.254)
		(layers "F.Cu" "B.Cu")
		(net "GND")
	)
	(via
		(at 74.798682 -17.203928)
		(size 0.508)
		(drill 0.254)
		(layers "F.Cu" "B.Cu")
		(net "GND")
	)
	(via
		(at 13.853922 -329.314302)
		(size 0.508)
		(drill 0.254)
		(layers "F.Cu" "B.Cu")
		(net "GND")
	)
	(via
		(at 74.804524 -85.772752)
		(size 0.508)
		(drill 0.254)
		(layers "F.Cu" "B.Cu")
		(net "GND")
	)
	(via
		(at 41.4655 -461.170274)
		(size 0.508)
		(drill 0.254)
		(layers "F.Cu" "B.Cu")
		(net "GND")
	)
	(via
		(at 41.326054 -214.559388)
		(size 1.016)
		(drill 0.508)
		(layers "F.Cu" "B.Cu")
		(net "GND")
	)
	(via
		(at 40.474392 -485.317292)
		(size 1.016)
		(drill 0.508)
		(layers "F.Cu" "B.Cu")
		(net "GND")
	)
	(via
		(at 41.369488 -208.97215)
		(size 1.016)
		(drill 0.508)
		(layers "F.Cu" "B.Cu")
		(net "GND")
	)
	(via
		(at 24.923496 -189.265306)
		(size 0.508)
		(drill 0.254)
		(layers "F.Cu" "B.Cu")
		(net "GND")
	)
	(via
		(at 64.69634 -154.459432)
		(size 1.016)
		(drill 0.508)
		(layers "F.Cu" "B.Cu")
		(net "GND")
	)
	(via
		(at 63.212218 -120.849644)
		(size 1.016)
		(drill 0.508)
		(layers "F.Cu" "B.Cu")
		(net "GND")
	)
	(via
		(at 67.977258 -29.351986)
		(size 0.508)
		(drill 0.254)
		(layers "F.Cu" "B.Cu")
		(net "GND")
	)
	(via
		(at 62.88786 -247.333008)
		(size 1.016)
		(drill 0.508)
		(layers "F.Cu" "B.Cu")
		(net "GND")
	)
	(via
		(at 40.736774 -304.356262)
		(size 1.016)
		(drill 0.508)
		(layers "F.Cu" "B.Cu")
		(net "GND")
	)
	(via
		(at 39.100252 -388.222998)
		(size 1.016)
		(drill 0.508)
		(layers "F.Cu" "B.Cu")
		(net "GND")
	)
	(via
		(at 0.762254 -114.308636)
		(size 0.508)
		(drill 0.254)
		(layers "F.Cu" "B.Cu")
		(net "GND")
	)
	(via
		(at 102.238048 -334.545432)
		(size 0.508)
		(drill 0.254)
		(layers "F.Cu" "B.Cu")
		(net "GND")
	)
	(via
		(at 93.006926 -349.55734)
		(size 1.016)
		(drill 0.508)
		(layers "F.Cu" "B.Cu")
		(net "GND")
	)
	(via
		(at 102.238048 -347.245432)
		(size 0.508)
		(drill 0.254)
		(layers "F.Cu" "B.Cu")
		(net "GND")
	)
	(via
		(at 45.514514 -210.873086)
		(size 1.016)
		(drill 0.508)
		(layers "F.Cu" "B.Cu")
		(net "GND")
	)
	(via
		(at 102.238048 -271.045432)
		(size 0.508)
		(drill 0.254)
		(layers "F.Cu" "B.Cu")
		(net "GND")
	)
	(via
		(at 41.103804 -192.216278)
		(size 0.508)
		(drill 0.254)
		(layers "F.Cu" "B.Cu")
		(net "GND")
	)
	(via
		(at 57.795922 -73.65746)
		(size 1.016)
		(drill 0.508)
		(layers "F.Cu" "B.Cu")
		(net "GND")
	)
	(via
		(at 102.238048 -169.445432)
		(size 0.508)
		(drill 0.254)
		(layers "F.Cu" "B.Cu")
		(net "GND")
	)
	(via
		(at 45.514514 -208.97215)
		(size 1.016)
		(drill 0.508)
		(layers "F.Cu" "B.Cu")
		(net "GND")
	)
	(via
		(at 62.860428 -306.775358)
		(size 1.016)
		(drill 0.508)
		(layers "F.Cu" "B.Cu")
		(net "GND")
	)
	(via
		(at 60.603384 -253.275846)
		(size 1.016)
		(drill 0.508)
		(layers "F.Cu" "B.Cu")
		(net "GND")
	)
	(via
		(at 38.893496 -298.769024)
		(size 1.016)
		(drill 0.508)
		(layers "F.Cu" "B.Cu")
		(net "GND")
	)
	(via
		(at 64.764412 -304.734214)
		(size 1.016)
		(drill 0.508)
		(layers "F.Cu" "B.Cu")
		(net "GND")
	)
	(via
		(at 58.664602 -150.883366)
		(size 1.016)
		(drill 0.508)
		(layers "F.Cu" "B.Cu")
		(net "GND")
	)
	(via
		(at 0.762254 -330.208636)
		(size 0.508)
		(drill 0.254)
		(layers "F.Cu" "B.Cu")
		(net "GND")
	)
	(via
		(at 0.762254 -355.608636)
		(size 0.508)
		(drill 0.254)
		(layers "F.Cu" "B.Cu")
		(net "GND")
	)
	(via
		(at 73.909936 -150.42261)
		(size 0.508)
		(drill 0.254)
		(layers "F.Cu" "B.Cu")
		(net "GND")
	)
	(via
		(at 41.326054 -218.491054)
		(size 1.016)
		(drill 0.508)
		(layers "F.Cu" "B.Cu")
		(net "GND")
	)
	(via
		(at 67.927982 -158.577534)
		(size 1.016)
		(drill 0.508)
		(layers "F.Cu" "B.Cu")
		(net "GND")
	)
	(via
		(at 62.792356 -150.883366)
		(size 1.016)
		(drill 0.508)
		(layers "F.Cu" "B.Cu")
		(net "GND")
	)
	(via
		(at 64.69634 -150.883366)
		(size 1.016)
		(drill 0.508)
		(layers "F.Cu" "B.Cu")
		(net "GND")
	)
	(via
		(at 73.914508 -106.132376)
		(size 0.508)
		(drill 0.254)
		(layers "F.Cu" "B.Cu")
		(net "GND")
	)
	(via
		(at 26.843736 -285.983426)
		(size 0.508)
		(drill 0.254)
		(layers "F.Cu" "B.Cu")
		(net "GND")
	)
	(via
		(at 63.168784 -128.467612)
		(size 1.016)
		(drill 0.508)
		(layers "F.Cu" "B.Cu")
		(net "GND")
	)
	(via
		(at 75.91298 -395.785594)
		(size 0.508)
		(drill 0.254)
		(layers "F.Cu" "B.Cu")
		(net "GND")
	)
	(via
		(at 102.238048 -372.645432)
		(size 0.508)
		(drill 0.254)
		(layers "F.Cu" "B.Cu")
		(net "GND")
	)
	(via
		(at 27.452828 -9.880346)
		(size 0.508)
		(drill 0.254)
		(layers "F.Cu" "B.Cu")
		(net "GND")
	)
	(via
		(at 64.791844 -243.756942)
		(size 1.016)
		(drill 0.508)
		(layers "F.Cu" "B.Cu")
		(net "GND")
	)
	(via
		(at 43.27144 -386.211826)
		(size 1.016)
		(drill 0.508)
		(layers "F.Cu" "B.Cu")
		(net "GND")
	)
	(via
		(at 24.625046 -276.12213)
		(size 0.508)
		(drill 0.254)
		(layers "F.Cu" "B.Cu")
		(net "GND")
	)
	(via
		(at 0.762254 -177.808636)
		(size 0.508)
		(drill 0.254)
		(layers "F.Cu" "B.Cu")
		(net "GND")
	)
	(via
		(at 0.762254 -495.308636)
		(size 0.508)
		(drill 0.254)
		(layers "F.Cu" "B.Cu")
		(net "GND")
	)
	(segment
		(start 38.871144 -375.989596)
		(end 39.577264 -375.989596)
		(width 0.1524)
		(layer "F.Cu")
		(net "PSU5_REMOTE_P")
	)
	(segment
		(start 37.784532 -376.198638)
		(end 38.662102 -376.198638)
		(width 0.1524)
		(layer "F.Cu")
		(net "PSU5_REMOTE_P")
	)
	(segment
		(start 37.555932 -375.970038)
		(end 37.784532 -376.198638)
		(width 0.1524)
		(layer "F.Cu")
		(net "PSU5_REMOTE_P")
	)
	(segment
		(start 38.662102 -376.198638)
		(end 38.871144 -375.989596)
		(width 0.1524)
		(layer "F.Cu")
		(net "PSU5_REMOTE_P")
	)
	(segment
		(start 35.53968 -375.970038)
		(end 37.555932 -375.970038)
		(width 0.1524)
		(layer "F.Cu")
		(net "PSU5_REMOTE_P")
	)
	(segment
		(start 35.53968 -287.56991)
		(end 39.454836 -287.56991)
		(width 0.508)
		(layer "F.Cu")
		(net "PSU4_REMOTE_P")
	)
	(segment
		(start 39.454836 -287.56991)
		(end 39.458138 -287.573212)
		(width 0.508)
		(layer "F.Cu")
		(net "PSU4_REMOTE_P")
	)
	(segment
		(start 39.903908 -369.11153)
		(end 40.434768 -368.58067)
		(width 0.1524)
		(layer "F.Cu")
		(net "PSU5_RETURN")
	)
	(segment
		(start 37.664136 -365.810038)
		(end 40.434768 -368.58067)
		(width 0.1524)
		(layer "F.Cu")
		(net "PSU5_RETURN")
	)
	(segment
		(start 35.53968 -365.810038)
		(end 37.664136 -365.810038)
		(width 0.1524)
		(layer "F.Cu")
		(net "PSU5_RETURN")
	)
	(segment
		(start 39.903908 -370.099336)
		(end 39.903908 -369.11153)
		(width 0.1524)
		(layer "F.Cu")
		(net "PSU5_RETURN")
	)
	(via
		(at 40.434768 -368.58067)
		(size 0.508)
		(drill 0.254)
		(layers "F.Cu" "B.Cu")
		(net "PSU5_RETURN")
	)
	(segment
		(start 39.459916 -199.170036)
		(end 39.460424 -199.169528)
		(width 0.508)
		(layer "F.Cu")
		(net "PSU3_REMOTE_P")
	)
	(segment
		(start 35.53968 -199.170036)
		(end 39.459916 -199.170036)
		(width 0.508)
		(layer "F.Cu")
		(net "PSU3_REMOTE_P")
	)
	(via
		(at 79.988156 -60.493148)
		(size 0.508)
		(drill 0.254)
		(layers "F.Cu" "B.Cu")
		(net "T2_BLAD3_TXD")
	)
	(segment
		(start 10.129774 -203.450698)
		(end 15.786354 -197.794118)
		(width 0.127)
		(layer "In5.Cu")
		(net "T2_BLAD3_TXD")
	)
	(segment
		(start 4.64058 -222.442278)
		(end 7.07644 -222.442278)
		(width 0.127)
		(layer "In5.Cu")
		(net "T2_BLAD3_TXD")
	)
	(segment
		(start 19.832574 -93.280738)
		(end 25.294082 -87.81923)
		(width 0.127)
		(layer "In5.Cu")
		(net "T2_BLAD3_TXD")
	)
	(segment
		(start 25.442164 -115.976908)
		(end 19.832574 -110.367318)
		(width 0.127)
		(layer "In5.Cu")
		(net "T2_BLAD3_TXD")
	)
	(segment
		(start 25.294082 -87.81923)
		(end 51.852068 -87.81923)
		(width 0.127)
		(layer "In5.Cu")
		(net "T2_BLAD3_TXD")
	)
	(segment
		(start 1.951736 -222.66783)
		(end 4.415028 -222.66783)
		(width 0.127)
		(layer "In5.Cu")
		(net "T2_BLAD3_TXD")
	)
	(segment
		(start 84.758276 -55.723028)
		(end 84.758276 -51.606704)
		(width 0.127)
		(layer "In5.Cu")
		(net "T2_BLAD3_TXD")
	)
	(segment
		(start 79.988156 -60.493148)
		(end 84.758276 -55.723028)
		(width 0.127)
		(layer "In5.Cu")
		(net "T2_BLAD3_TXD")
	)
	(segment
		(start 7.07644 -222.442278)
		(end 8.099552 -221.419166)
		(width 0.127)
		(layer "In5.Cu")
		(net "T2_BLAD3_TXD")
	)
	(segment
		(start 19.832574 -110.367318)
		(end 19.832574 -93.280738)
		(width 0.127)
		(layer "In5.Cu")
		(net "T2_BLAD3_TXD")
	)
	(segment
		(start 15.786354 -197.794118)
		(end 15.786354 -177.39868)
		(width 0.127)
		(layer "In5.Cu")
		(net "T2_BLAD3_TXD")
	)
	(segment
		(start 9.750806 -221.419166)
		(end 10.129774 -221.040198)
		(width 0.127)
		(layer "In5.Cu")
		(net "T2_BLAD3_TXD")
	)
	(segment
		(start 1.948942 -222.670624)
		(end 1.951736 -222.66783)
		(width 0.127)
		(layer "In5.Cu")
		(net "T2_BLAD3_TXD")
	)
	(segment
		(start 15.786354 -177.39868)
		(end 25.442164 -167.74287)
		(width 0.127)
		(layer "In5.Cu")
		(net "T2_BLAD3_TXD")
	)
	(segment
		(start 10.129774 -221.040198)
		(end 10.129774 -203.450698)
		(width 0.127)
		(layer "In5.Cu")
		(net "T2_BLAD3_TXD")
	)
	(segment
		(start 51.852068 -87.81923)
		(end 77.406754 -62.264544)
		(width 0.127)
		(layer "In5.Cu")
		(net "T2_BLAD3_TXD")
	)
	(segment
		(start 78.21676 -62.264544)
		(end 79.988156 -60.493148)
		(width 0.127)
		(layer "In5.Cu")
		(net "T2_BLAD3_TXD")
	)
	(segment
		(start 25.442164 -167.74287)
		(end 25.442164 -115.976908)
		(width 0.127)
		(layer "In5.Cu")
		(net "T2_BLAD3_TXD")
	)
	(segment
		(start 84.758276 -51.606704)
		(end 85.63991 -50.72507)
		(width 0.127)
		(layer "In5.Cu")
		(net "T2_BLAD3_TXD")
	)
	(segment
		(start 77.406754 -62.264544)
		(end 78.21676 -62.264544)
		(width 0.127)
		(layer "In5.Cu")
		(net "T2_BLAD3_TXD")
	)
	(segment
		(start 8.099552 -221.419166)
		(end 9.750806 -221.419166)
		(width 0.127)
		(layer "In5.Cu")
		(net "T2_BLAD3_TXD")
	)
	(segment
		(start 4.415028 -222.66783)
		(end 4.64058 -222.442278)
		(width 0.127)
		(layer "In5.Cu")
		(net "T2_BLAD3_TXD")
	)
	(segment
		(start 39.454074 -110.769908)
		(end 39.458392 -110.774226)
		(width 0.4572)
		(layer "F.Cu")
		(net "PSU2_REMOTE_P")
	)
	(segment
		(start 35.53968 -110.769908)
		(end 39.454074 -110.769908)
		(width 0.4572)
		(layer "F.Cu")
		(net "PSU2_REMOTE_P")
	)
	(via
		(at 82.476086 -58.82132)
		(size 0.508)
		(drill 0.254)
		(layers "F.Cu" "B.Cu")
		(net "T2_BLAD3_RXD")
	)
	(segment
		(start 16.219932 -198.01078)
		(end 16.219932 -177.718212)
		(width 0.127)
		(layer "In5.Cu")
		(net "T2_BLAD3_RXD")
	)
	(segment
		(start 25.783794 -168.15435)
		(end 25.783794 -115.634008)
		(width 0.127)
		(layer "In5.Cu")
		(net "T2_BLAD3_RXD")
	)
	(segment
		(start 16.219932 -177.718212)
		(end 25.783794 -168.15435)
		(width 0.127)
		(layer "In5.Cu")
		(net "T2_BLAD3_RXD")
	)
	(segment
		(start 78.048358 -62.692534)
		(end 78.604872 -62.692534)
		(width 0.127)
		(layer "In5.Cu")
		(net "T2_BLAD3_RXD")
	)
	(segment
		(start 77.150214 -63.590678)
		(end 78.048358 -62.692534)
		(width 0.127)
		(layer "In5.Cu")
		(net "T2_BLAD3_RXD")
	)
	(segment
		(start 25.5651 -88.161622)
		(end 53.135784 -88.161622)
		(width 0.127)
		(layer "In5.Cu")
		(net "T2_BLAD3_RXD")
	)
	(segment
		(start 3.948938 -223.670622)
		(end 4.823968 -222.795592)
		(width 0.127)
		(layer "In5.Cu")
		(net "T2_BLAD3_RXD")
	)
	(segment
		(start 86.538816 -52.836572)
		(end 86.083394 -52.38115)
		(width 0.127)
		(layer "In5.Cu")
		(net "T2_BLAD3_RXD")
	)
	(segment
		(start 86.538816 -54.75859)
		(end 86.538816 -52.836572)
		(width 0.127)
		(layer "In5.Cu")
		(net "T2_BLAD3_RXD")
	)
	(segment
		(start 7.222998 -222.795592)
		(end 8.24611 -221.77248)
		(width 0.127)
		(layer "In5.Cu")
		(net "T2_BLAD3_RXD")
	)
	(segment
		(start 8.24611 -221.77248)
		(end 9.897364 -221.77248)
		(width 0.127)
		(layer "In5.Cu")
		(net "T2_BLAD3_RXD")
	)
	(segment
		(start 86.083394 -52.38115)
		(end 86.083394 -51.504596)
		(width 0.127)
		(layer "In5.Cu")
		(net "T2_BLAD3_RXD")
	)
	(segment
		(start 9.897364 -221.77248)
		(end 10.483342 -221.186502)
		(width 0.127)
		(layer "In5.Cu")
		(net "T2_BLAD3_RXD")
	)
	(segment
		(start 78.604872 -62.692534)
		(end 82.476086 -58.82132)
		(width 0.127)
		(layer "In5.Cu")
		(net "T2_BLAD3_RXD")
	)
	(segment
		(start 25.783794 -115.634008)
		(end 20.220432 -110.070646)
		(width 0.127)
		(layer "In5.Cu")
		(net "T2_BLAD3_RXD")
	)
	(segment
		(start 4.823968 -222.795592)
		(end 7.222998 -222.795592)
		(width 0.127)
		(layer "In5.Cu")
		(net "T2_BLAD3_RXD")
	)
	(segment
		(start 10.483342 -221.186502)
		(end 10.483342 -203.74737)
		(width 0.127)
		(layer "In5.Cu")
		(net "T2_BLAD3_RXD")
	)
	(segment
		(start 77.150214 -64.147192)
		(end 77.150214 -63.590678)
		(width 0.127)
		(layer "In5.Cu")
		(net "T2_BLAD3_RXD")
	)
	(segment
		(start 86.083394 -51.504596)
		(end 86.90991 -50.67808)
		(width 0.127)
		(layer "In5.Cu")
		(net "T2_BLAD3_RXD")
	)
	(segment
		(start 20.220432 -110.070646)
		(end 20.220432 -93.50629)
		(width 0.127)
		(layer "In5.Cu")
		(net "T2_BLAD3_RXD")
	)
	(segment
		(start 53.135784 -88.161622)
		(end 77.150214 -64.147192)
		(width 0.127)
		(layer "In5.Cu")
		(net "T2_BLAD3_RXD")
	)
	(segment
		(start 86.90991 -50.67808)
		(end 86.90991 -49.45507)
		(width 0.127)
		(layer "In5.Cu")
		(net "T2_BLAD3_RXD")
	)
	(segment
		(start 82.476086 -58.82132)
		(end 86.538816 -54.75859)
		(width 0.127)
		(layer "In5.Cu")
		(net "T2_BLAD3_RXD")
	)
	(segment
		(start 20.220432 -93.50629)
		(end 25.5651 -88.161622)
		(width 0.127)
		(layer "In5.Cu")
		(net "T2_BLAD3_RXD")
	)
	(segment
		(start 10.483342 -203.74737)
		(end 16.219932 -198.01078)
		(width 0.127)
		(layer "In5.Cu")
		(net "T2_BLAD3_RXD")
	)
	(via
		(at 77.690218 -65.681606)
		(size 0.508)
		(drill 0.254)
		(layers "F.Cu" "B.Cu")
		(net "T2_BLAD4_EN")
	)
	(segment
		(start 27.255216 -106.979212)
		(end 27.778202 -107.502198)
		(width 0.127)
		(layer "In2.Cu")
		(net "T2_BLAD4_EN")
	)
	(segment
		(start 87.190072 -54.096666)
		(end 86.983316 -54.303422)
		(width 0.127)
		(layer "In2.Cu")
		(net "T2_BLAD4_EN")
	)
	(segment
		(start 87.27948 -51.091338)
		(end 87.721186 -51.533044)
		(width 0.127)
		(layer "In2.Cu")
		(net "T2_BLAD4_EN")
	)
	(segment
		(start 89.44991 -49.45507)
		(end 89.143078 -49.761902)
		(width 0.127)
		(layer "In2.Cu")
		(net "T2_BLAD4_EN")
	)
	(segment
		(start 26.072592 -100.84054)
		(end 27.255216 -102.023164)
		(width 0.127)
		(layer "In2.Cu")
		(net "T2_BLAD4_EN")
	)
	(segment
		(start 87.190072 -52.978812)
		(end 87.190072 -54.096666)
		(width 0.127)
		(layer "In2.Cu")
		(net "T2_BLAD4_EN")
	)
	(segment
		(start 86.983316 -54.303422)
		(end 86.983316 -55.361586)
		(width 0.127)
		(layer "In2.Cu")
		(net "T2_BLAD4_EN")
	)
	(segment
		(start 30.007306 -89.712038)
		(end 26.072592 -93.646752)
		(width 0.127)
		(layer "In2.Cu")
		(net "T2_BLAD4_EN")
	)
	(segment
		(start 22.380448 -218.867482)
		(end 11.680698 -229.567232)
		(width 0.127)
		(layer "In2.Cu")
		(net "T2_BLAD4_EN")
	)
	(segment
		(start 87.721186 -51.533044)
		(end 87.721186 -52.447698)
		(width 0.127)
		(layer "In2.Cu")
		(net "T2_BLAD4_EN")
	)
	(segment
		(start 18.55851 -179.607464)
		(end 18.55851 -197.878446)
		(width 0.127)
		(layer "In2.Cu")
		(net "T2_BLAD4_EN")
	)
	(segment
		(start 22.34565 -213.722712)
		(end 22.380448 -213.75751)
		(width 0.127)
		(layer "In2.Cu")
		(net "T2_BLAD4_EN")
	)
	(segment
		(start 82.893154 -59.451748)
		(end 82.893154 -60.47867)
		(width 0.127)
		(layer "In2.Cu")
		(net "T2_BLAD4_EN")
	)
	(segment
		(start 27.255216 -102.023164)
		(end 27.255216 -106.979212)
		(width 0.127)
		(layer "In2.Cu")
		(net "T2_BLAD4_EN")
	)
	(segment
		(start 6.878066 -230.482394)
		(end 3.321304 -230.482394)
		(width 0.127)
		(layer "In2.Cu")
		(net "T2_BLAD4_EN")
	)
	(segment
		(start 3.13309 -230.670608)
		(end 1.948942 -230.670608)
		(width 0.127)
		(layer "In2.Cu")
		(net "T2_BLAD4_EN")
	)
	(segment
		(start 88.017096 -49.761902)
		(end 87.27948 -50.499518)
		(width 0.127)
		(layer "In2.Cu")
		(net "T2_BLAD4_EN")
	)
	(segment
		(start 26.995628 -171.170346)
		(end 18.55851 -179.607464)
		(width 0.127)
		(layer "In2.Cu")
		(net "T2_BLAD4_EN")
	)
	(segment
		(start 87.721186 -52.447698)
		(end 87.190072 -52.978812)
		(width 0.127)
		(layer "In2.Cu")
		(net "T2_BLAD4_EN")
	)
	(segment
		(start 26.995628 -109.966252)
		(end 26.995628 -171.170346)
		(width 0.127)
		(layer "In2.Cu")
		(net "T2_BLAD4_EN")
	)
	(segment
		(start 86.983316 -55.361586)
		(end 82.893154 -59.451748)
		(width 0.127)
		(layer "In2.Cu")
		(net "T2_BLAD4_EN")
	)
	(segment
		(start 27.778202 -107.502198)
		(end 27.778202 -109.183678)
		(width 0.127)
		(layer "In2.Cu")
		(net "T2_BLAD4_EN")
	)
	(segment
		(start 11.680698 -229.567232)
		(end 7.793228 -229.567232)
		(width 0.127)
		(layer "In2.Cu")
		(net "T2_BLAD4_EN")
	)
	(segment
		(start 27.778202 -109.183678)
		(end 26.995628 -109.966252)
		(width 0.127)
		(layer "In2.Cu")
		(net "T2_BLAD4_EN")
	)
	(segment
		(start 53.659786 -89.712038)
		(end 30.007306 -89.712038)
		(width 0.127)
		(layer "In2.Cu")
		(net "T2_BLAD4_EN")
	)
	(segment
		(start 87.27948 -50.499518)
		(end 87.27948 -51.091338)
		(width 0.127)
		(layer "In2.Cu")
		(net "T2_BLAD4_EN")
	)
	(segment
		(start 3.321304 -230.482394)
		(end 3.13309 -230.670608)
		(width 0.127)
		(layer "In2.Cu")
		(net "T2_BLAD4_EN")
	)
	(segment
		(start 89.143078 -49.761902)
		(end 88.017096 -49.761902)
		(width 0.127)
		(layer "In2.Cu")
		(net "T2_BLAD4_EN")
	)
	(segment
		(start 7.793228 -229.567232)
		(end 6.878066 -230.482394)
		(width 0.127)
		(layer "In2.Cu")
		(net "T2_BLAD4_EN")
	)
	(segment
		(start 22.380448 -213.75751)
		(end 22.380448 -218.867482)
		(width 0.127)
		(layer "In2.Cu")
		(net "T2_BLAD4_EN")
	)
	(segment
		(start 77.690218 -65.681606)
		(end 53.659786 -89.712038)
		(width 0.127)
		(layer "In2.Cu")
		(net "T2_BLAD4_EN")
	)
	(segment
		(start 82.893154 -60.47867)
		(end 77.690218 -65.681606)
		(width 0.127)
		(layer "In2.Cu")
		(net "T2_BLAD4_EN")
	)
	(segment
		(start 18.55851 -197.878446)
		(end 22.34565 -201.665586)
		(width 0.127)
		(layer "In2.Cu")
		(net "T2_BLAD4_EN")
	)
	(segment
		(start 26.072592 -93.646752)
		(end 26.072592 -100.84054)
		(width 0.127)
		(layer "In2.Cu")
		(net "T2_BLAD4_EN")
	)
	(segment
		(start 22.34565 -201.665586)
		(end 22.34565 -213.722712)
		(width 0.127)
		(layer "In2.Cu")
		(net "T2_BLAD4_EN")
	)
	(via
		(at 81.524094 -63.52667)
		(size 0.508)
		(drill 0.254)
		(layers "F.Cu" "B.Cu")
		(net "T2_BLAD3_EN")
	)
	(segment
		(start 88.600026 -52.448968)
		(end 88.600026 -51.145186)
		(width 0.127)
		(layer "In2.Cu")
		(net "T2_BLAD3_EN")
	)
	(segment
		(start 8.099044 -231.463088)
		(end 7.137146 -232.424986)
		(width 0.127)
		(layer "In2.Cu")
		(net "T2_BLAD3_EN")
	)
	(segment
		(start 28.642818 -111.126016)
		(end 27.788616 -111.980218)
		(width 0.127)
		(layer "In2.Cu")
		(net "T2_BLAD3_EN")
	)
	(segment
		(start 87.971376 -57.079388)
		(end 87.971376 -54.965346)
		(width 0.127)
		(layer "In2.Cu")
		(net "T2_BLAD3_EN")
	)
	(segment
		(start 23.075646 -201.304398)
		(end 23.075646 -219.65158)
		(width 0.127)
		(layer "In2.Cu")
		(net "T2_BLAD3_EN")
	)
	(segment
		(start 27.98699 -105.427272)
		(end 28.642818 -106.0831)
		(width 0.127)
		(layer "In2.Cu")
		(net "T2_BLAD3_EN")
	)
	(segment
		(start 27.98699 -100.46081)
		(end 27.98699 -105.427272)
		(width 0.127)
		(layer "In2.Cu")
		(net "T2_BLAD3_EN")
	)
	(segment
		(start 27.788616 -111.980218)
		(end 27.788616 -171.34459)
		(width 0.127)
		(layer "In2.Cu")
		(net "T2_BLAD3_EN")
	)
	(segment
		(start 19.252438 -179.880768)
		(end 19.252438 -197.48119)
		(width 0.127)
		(layer "In2.Cu")
		(net "T2_BLAD3_EN")
	)
	(segment
		(start 28.642818 -99.804982)
		(end 27.98699 -100.46081)
		(width 0.127)
		(layer "In2.Cu")
		(net "T2_BLAD3_EN")
	)
	(segment
		(start 54.654958 -90.395806)
		(end 30.812486 -90.395806)
		(width 0.127)
		(layer "In2.Cu")
		(net "T2_BLAD3_EN")
	)
	(segment
		(start 30.812486 -90.395806)
		(end 28.642818 -92.565474)
		(width 0.127)
		(layer "In2.Cu")
		(net "T2_BLAD3_EN")
	)
	(segment
		(start 88.600026 -51.145186)
		(end 88.17991 -50.72507)
		(width 0.127)
		(layer "In2.Cu")
		(net "T2_BLAD3_EN")
	)
	(segment
		(start 27.788616 -171.34459)
		(end 19.252438 -179.880768)
		(width 0.127)
		(layer "In2.Cu")
		(net "T2_BLAD3_EN")
	)
	(segment
		(start 88.978486 -53.958236)
		(end 88.978486 -52.827428)
		(width 0.127)
		(layer "In2.Cu")
		(net "T2_BLAD3_EN")
	)
	(segment
		(start 4.703318 -232.424986)
		(end 3.948938 -231.670606)
		(width 0.127)
		(layer "In2.Cu")
		(net "T2_BLAD3_EN")
	)
	(segment
		(start 28.642818 -92.565474)
		(end 28.642818 -99.804982)
		(width 0.127)
		(layer "In2.Cu")
		(net "T2_BLAD3_EN")
	)
	(segment
		(start 81.524094 -63.52667)
		(end 54.654958 -90.395806)
		(width 0.127)
		(layer "In2.Cu")
		(net "T2_BLAD3_EN")
	)
	(segment
		(start 7.137146 -232.424986)
		(end 4.703318 -232.424986)
		(width 0.127)
		(layer "In2.Cu")
		(net "T2_BLAD3_EN")
	)
	(segment
		(start 19.252438 -197.48119)
		(end 23.075646 -201.304398)
		(width 0.127)
		(layer "In2.Cu")
		(net "T2_BLAD3_EN")
	)
	(segment
		(start 88.978486 -52.827428)
		(end 88.600026 -52.448968)
		(width 0.127)
		(layer "In2.Cu")
		(net "T2_BLAD3_EN")
	)
	(segment
		(start 87.971376 -54.965346)
		(end 88.978486 -53.958236)
		(width 0.127)
		(layer "In2.Cu")
		(net "T2_BLAD3_EN")
	)
	(segment
		(start 23.075646 -219.65158)
		(end 11.264138 -231.463088)
		(width 0.127)
		(layer "In2.Cu")
		(net "T2_BLAD3_EN")
	)
	(segment
		(start 11.264138 -231.463088)
		(end 8.099044 -231.463088)
		(width 0.127)
		(layer "In2.Cu")
		(net "T2_BLAD3_EN")
	)
	(segment
		(start 28.642818 -106.0831)
		(end 28.642818 -111.126016)
		(width 0.127)
		(layer "In2.Cu")
		(net "T2_BLAD3_EN")
	)
	(segment
		(start 81.524094 -63.52667)
		(end 87.971376 -57.079388)
		(width 0.127)
		(layer "In2.Cu")
		(net "T2_BLAD3_EN")
	)
	(segment
		(start 40.258492 -110.774226)
		(end 41.025318 -110.774226)
		(width 0.4572)
		(layer "F.Cu")
		(net "P12V")
	)
	(segment
		(start 40.336724 -464.36915)
		(end 41.108376 -464.36915)
		(width 0.4572)
		(layer "F.Cu")
		(net "P12V")
	)
	(segment
		(start 40.273986 -22.379432)
		(end 40.980106 -22.379432)
		(width 0.4572)
		(layer "F.Cu")
		(net "P12V")
	)
	(segment
		(start 40.263826 -199.171814)
		(end 41.015666 -199.171814)
		(width 0.4572)
		(layer "F.Cu")
		(net "P12V")
	)
	(segment
		(start 81.347056 -297.892216)
		(end 82.144362 -297.892216)
		(width 0.4572)
		(layer "F.Cu")
		(net "P12V")
	)
	(segment
		(start 73.332848 -473.59951)
		(end 74.323956 -473.59951)
		(width 0.4572)
		(layer "F.Cu")
		(net "P12V")
	)
	(via
		(at 66.437256 -414.613852)
		(size 1.016)
		(drill 0.508)
		(layers "F.Cu" "B.Cu")
		(net "P12V")
	)
	(via
		(at 42.341546 -252.461776)
		(size 1.016)
		(drill 0.508)
		(layers "F.Cu" "B.Cu")
		(net "P12V")
	)
	(via
		(at 64.215772 -61.641736)
		(size 1.016)
		(drill 0.508)
		(layers "F.Cu" "B.Cu")
		(net "P12V")
	)
	(via
		(at 78.603856 -379.469142)
		(size 1.016)
		(drill 0.508)
		(layers "F.Cu" "B.Cu")
		(net "P12V")
	)
	(via
		(at 66.437256 -417.282122)
		(size 1.016)
		(drill 0.508)
		(layers "F.Cu" "B.Cu")
		(net "P12V")
	)
	(via
		(at 73.177908 -11.575288)
		(size 1.016)
		(drill 0.508)
		(layers "F.Cu" "B.Cu")
		(net "P12V")
	)
	(via
		(at 69.428868 -421.616632)
		(size 1.016)
		(drill 0.508)
		(layers "F.Cu" "B.Cu")
		(net "P12V")
	)
	(via
		(at 69.428868 -419.65372)
		(size 1.016)
		(drill 0.508)
		(layers "F.Cu" "B.Cu")
		(net "P12V")
	)
	(via
		(at 87.329264 -86.985094)
		(size 1.016)
		(drill 0.508)
		(layers "F.Cu" "B.Cu")
		(net "P12V")
	)
	(via
		(at 57.041542 -525.142206)
		(size 1.016)
		(drill 0.508)
		(layers "F.Cu" "B.Cu")
		(net "P12V")
	)
	(via
		(at 77.002386 -300.869604)
		(size 1.016)
		(drill 0.508)
		(layers "F.Cu" "B.Cu")
		(net "P12V")
	)
	(via
		(at 67.207384 -58.973466)
		(size 1.016)
		(drill 0.508)
		(layers "F.Cu" "B.Cu")
		(net "P12V")
	)
	(via
		(at 61.910214 -43.213274)
		(size 1.016)
		(drill 0.508)
		(layers "F.Cu" "B.Cu")
		(net "P12V")
	)
	(via
		(at 59.798966 -336.36839)
		(size 1.016)
		(drill 0.508)
		(layers "F.Cu" "B.Cu")
		(net "P12V")
	)
	(via
		(at 69.730874 -103.451406)
		(size 1.016)
		(drill 0.508)
		(layers "F.Cu" "B.Cu")
		(net "P12V")
	)
	(via
		(at 78.03261 -487.001312)
		(size 1.016)
		(drill 0.508)
		(layers "F.Cu" "B.Cu")
		(net "P12V")
	)
	(via
		(at 69.734176 -245.644924)
		(size 1.016)
		(drill 0.508)
		(layers "F.Cu" "B.Cu")
		(net "P12V")
	)
	(via
		(at 66.349626 -285.588456)
		(size 1.016)
		(drill 0.508)
		(layers "F.Cu" "B.Cu")
		(net "P12V")
	)
	(via
		(at 42.271696 -254.90678)
		(size 1.016)
		(drill 0.508)
		(layers "F.Cu" "B.Cu")
		(net "P12V")
	)
	(via
		(at 79.96174 -487.001312)
		(size 1.016)
		(drill 0.508)
		(layers "F.Cu" "B.Cu")
		(net "P12V")
	)
	(via
		(at 74.312526 -135.321548)
		(size 1.016)
		(drill 0.508)
		(layers "F.Cu" "B.Cu")
		(net "P12V")
	)
	(via
		(at 64.698372 -431.193702)
		(size 1.016)
		(drill 0.508)
		(layers "F.Cu" "B.Cu")
		(net "P12V")
	)
	(via
		(at 76.336398 -133.105398)
		(size 1.016)
		(drill 0.508)
		(layers "F.Cu" "B.Cu")
		(net "P12V")
	)
	(via
		(at 55.714646 -332.466696)
		(size 1.016)
		(drill 0.508)
		(layers "F.Cu" "B.Cu")
		(net "P12V")
	)
	(via
		(at 69.734176 -243.804186)
		(size 1.016)
		(drill 0.508)
		(layers "F.Cu" "B.Cu")
		(net "P12V")
	)
	(via
		(at 68.737988 -335.014316)
		(size 1.016)
		(drill 0.508)
		(layers "F.Cu" "B.Cu")
		(net "P12V")
	)
	(via
		(at 82.585306 -135.330946)
		(size 1.016)
		(drill 0.508)
		(layers "F.Cu" "B.Cu")
		(net "P12V")
	)
	(via
		(at 42.15765 -72.847962)
		(size 1.016)
		(drill 0.508)
		(layers "F.Cu" "B.Cu")
		(net "P12V")
	)
	(via
		(at 65.933574 -332.87081)
		(size 1.016)
		(drill 0.508)
		(layers "F.Cu" "B.Cu")
		(net "P12V")
	)
	(via
		(at 70.851776 -150.35403)
		(size 1.016)
		(drill 0.508)
		(layers "F.Cu" "B.Cu")
		(net "P12V")
	)
	(via
		(at 70.658228 -300.85157)
		(size 1.016)
		(drill 0.508)
		(layers "F.Cu" "B.Cu")
		(net "P12V")
	)
	(via
		(at 42.15765 -70.179692)
		(size 1.016)
		(drill 0.508)
		(layers "F.Cu" "B.Cu")
		(net "P12V")
	)
	(via
		(at 67.082416 -11.575288)
		(size 1.016)
		(drill 0.508)
		(layers "F.Cu" "B.Cu")
		(net "P12V")
	)
	(via
		(at 67.082416 -13.955776)
		(size 1.016)
		(drill 0.508)
		(layers "F.Cu" "B.Cu")
		(net "P12V")
	)
	(via
		(at 68.979288 -16.624046)
		(size 1.016)
		(drill 0.508)
		(layers "F.Cu" "B.Cu")
		(net "P12V")
	)
	(via
		(at 67.918584 -460.278988)
		(size 1.016)
		(drill 0.508)
		(layers "F.Cu" "B.Cu")
		(net "P12V")
	)
	(via
		(at 74.34961 -375.945146)
		(size 1.016)
		(drill 0.508)
		(layers "F.Cu" "B.Cu")
		(net "P12V")
	)
	(via
		(at 67.082416 -16.624046)
		(size 1.016)
		(drill 0.508)
		(layers "F.Cu" "B.Cu")
		(net "P12V")
	)
	(via
		(at 77.002386 -302.832516)
		(size 1.016)
		(drill 0.508)
		(layers "F.Cu" "B.Cu")
		(net "P12V")
	)
	(via
		(at 70.851776 -147.68576)
		(size 1.016)
		(drill 0.508)
		(layers "F.Cu" "B.Cu")
		(net "P12V")
	)
	(via
		(at 40.980106 -22.379432)
		(size 0.508)
		(drill 0.254)
		(layers "F.Cu" "B.Cu")
		(net "P12V")
	)
	(via
		(at 57.557924 -336.36839)
		(size 1.016)
		(drill 0.508)
		(layers "F.Cu" "B.Cu")
		(net "P12V")
	)
	(via
		(at 82.585306 -131.224528)
		(size 1.016)
		(drill 0.508)
		(layers "F.Cu" "B.Cu")
		(net "P12V")
	)
	(via
		(at 78.695042 -372.364508)
		(size 1.016)
		(drill 0.508)
		(layers "F.Cu" "B.Cu")
		(net "P12V")
	)
	(via
		(at 61.97092 -195.821046)
		(size 1.016)
		(drill 0.508)
		(layers "F.Cu" "B.Cu")
		(net "P12V")
	)
	(via
		(at 61.70295 -340.31936)
		(size 1.016)
		(drill 0.508)
		(layers "F.Cu" "B.Cu")
		(net "P12V")
	)
	(via
		(at 76.470764 -374.130316)
		(size 1.016)
		(drill 0.508)
		(layers "F.Cu" "B.Cu")
		(net "P12V")
	)
	(via
		(at 66.705734 -251.600462)
		(size 1.016)
		(drill 0.508)
		(layers "F.Cu" "B.Cu")
		(net "P12V")
	)
	(via
		(at 79.231744 -300.86935)
		(size 1.016)
		(drill 0.508)
		(layers "F.Cu" "B.Cu")
		(net "P12V")
	)
	(via
		(at 55.671212 -338.409534)
		(size 1.016)
		(drill 0.508)
		(layers "F.Cu" "B.Cu")
		(net "P12V")
	)
	(via
		(at 62.377828 -522.9987)
		(size 1.016)
		(drill 0.508)
		(layers "F.Cu" "B.Cu")
		(net "P12V")
	)
	(via
		(at 67.207384 -65.976246)
		(size 1.016)
		(drill 0.508)
		(layers "F.Cu" "B.Cu")
		(net "P12V")
	)
	(via
		(at 63.573152 -465.61629)
		(size 1.016)
		(drill 0.508)
		(layers "F.Cu" "B.Cu")
		(net "P12V")
	)
	(via
		(at 84.52485 -80.933036)
		(size 1.016)
		(drill 0.508)
		(layers "F.Cu" "B.Cu")
		(net "P12V")
	)
	(via
		(at 39.947088 -158.516066)
		(size 1.016)
		(drill 0.508)
		(layers "F.Cu" "B.Cu")
		(net "P12V")
	)
	(via
		(at 40.256968 -426.280072)
		(size 1.016)
		(drill 0.508)
		(layers "F.Cu" "B.Cu")
		(net "P12V")
	)
	(via
		(at 74.34961 -379.46838)
		(size 1.016)
		(drill 0.508)
		(layers "F.Cu" "B.Cu")
		(net "P12V")
	)
	(via
		(at 64.775334 -195.821046)
		(size 1.016)
		(drill 0.508)
		(layers "F.Cu" "B.Cu")
		(net "P12V")
	)
	(via
		(at 40.256968 -420.940992)
		(size 1.016)
		(drill 0.508)
		(layers "F.Cu" "B.Cu")
		(net "P12V")
	)
	(via
		(at 67.860164 -154.68854)
		(size 1.016)
		(drill 0.508)
		(layers "F.Cu" "B.Cu")
		(net "P12V")
	)
	(via
		(at 66.846196 -219.173298)
		(size 1.016)
		(drill 0.508)
		(layers "F.Cu" "B.Cu")
		(net "P12V")
	)
	(via
		(at 87.308436 -79.24292)
		(size 1.016)
		(drill 0.508)
		(layers "F.Cu" "B.Cu")
		(net "P12V")
	)
	(via
		(at 39.560246 -337.503262)
		(size 1.016)
		(drill 0.508)
		(layers "F.Cu" "B.Cu")
		(net "P12V")
	)
	(via
		(at 69.730874 -106.119676)
		(size 1.016)
		(drill 0.508)
		(layers "F.Cu" "B.Cu")
		(net "P12V")
	)
	(via
		(at 39.560246 -334.834992)
		(size 1.016)
		(drill 0.508)
		(layers "F.Cu" "B.Cu")
		(net "P12V")
	)
	(via
		(at 74.312526 -133.178042)
		(size 1.016)
		(drill 0.508)
		(layers "F.Cu" "B.Cu")
		(net "P12V")
	)
	(via
		(at 67.207384 -68.119752)
		(size 1.016)
		(drill 0.508)
		(layers "F.Cu" "B.Cu")
		(net "P12V")
	)
	(via
		(at 73.177908 -16.624046)
		(size 1.016)
		(drill 0.508)
		(layers "F.Cu" "B.Cu")
		(net "P12V")
	)
	(via
		(at 65.933574 -330.907898)
		(size 1.016)
		(drill 0.508)
		(layers "F.Cu" "B.Cu")
		(net "P12V")
	)
	(via
		(at 72.827134 -304.921666)
		(size 1.016)
		(drill 0.508)
		(layers "F.Cu" "B.Cu")
		(net "P12V")
	)
	(via
		(at 76.288646 -488.722162)
		(size 1.016)
		(drill 0.508)
		(layers "F.Cu" "B.Cu")
		(net "P12V")
	)
	(via
		(at 59.80811 -330.70165)
		(size 1.016)
		(drill 0.508)
		(layers "F.Cu" "B.Cu")
		(net "P12V")
	)
	(via
		(at 74.323956 -473.59951)
		(size 0.508)
		(drill 0.254)
		(layers "F.Cu" "B.Cu")
		(net "P12V")
	)
	(via
		(at 68.60921 -525.142206)
		(size 1.016)
		(drill 0.508)
		(layers "F.Cu" "B.Cu")
		(net "P12V")
	)
	(via
		(at 74.312526 -131.21513)
		(size 1.016)
		(drill 0.508)
		(layers "F.Cu" "B.Cu")
		(net "P12V")
	)
	(via
		(at 80.057498 -170.627802)
		(size 1.016)
		(drill 0.508)
		(layers "F.Cu" "B.Cu")
		(net "P12V")
	)
	(via
		(at 67.274694 -41.069768)
		(size 1.016)
		(drill 0.508)
		(layers "F.Cu" "B.Cu")
		(net "P12V")
	)
	(via
		(at 80.464914 -133.205728)
		(size 1.016)
		(drill 0.508)
		(layers "F.Cu" "B.Cu")
		(net "P12V")
	)
	(via
		(at 64.283082 -41.069768)
		(size 1.016)
		(drill 0.508)
		(layers "F.Cu" "B.Cu")
		(net "P12V")
	)
	(via
		(at 15.018258 -319.442338)
		(size 0.508)
		(drill 0.254)
		(layers "F.Cu" "B.Cu")
		(net "P12V")
	)
	(via
		(at 55.680356 -326.967088)
		(size 1.016)
		(drill 0.508)
		(layers "F.Cu" "B.Cu")
		(net "P12V")
	)
	(via
		(at 80.802226 -255.854962)
		(size 1.016)
		(drill 0.508)
		(layers "F.Cu" "B.Cu")
		(net "P12V")
	)
	(via
		(at 63.573152 -467.38286)
		(size 1.016)
		(drill 0.508)
		(layers "F.Cu" "B.Cu")
		(net "P12V")
	)
	(via
		(at 67.274694 -39.106856)
		(size 1.016)
		(drill 0.508)
		(layers "F.Cu" "B.Cu")
		(net "P12V")
	)
	(via
		(at 65.617598 -522.9987)
		(size 1.016)
		(drill 0.508)
		(layers "F.Cu" "B.Cu")
		(net "P12V")
	)
	(via
		(at 78.027276 -259.246878)
		(size 1.016)
		(drill 0.508)
		(layers "F.Cu" "B.Cu")
		(net "P12V")
	)
	(via
		(at 76.470764 -372.363746)
		(size 1.016)
		(drill 0.508)
		(layers "F.Cu" "B.Cu")
		(net "P12V")
	)
	(via
		(at 59.573414 -525.142206)
		(size 1.016)
		(drill 0.508)
		(layers "F.Cu" "B.Cu")
		(net "P12V")
	)
	(via
		(at 77.002386 -304.976022)
		(size 1.016)
		(drill 0.508)
		(layers "F.Cu" "B.Cu")
		(net "P12V")
	)
	(via
		(at 84.52485 -86.985094)
		(size 1.016)
		(drill 0.508)
		(layers "F.Cu" "B.Cu")
		(net "P12V")
	)
	(via
		(at 62.377828 -513.32511)
		(size 1.016)
		(drill 0.508)
		(layers "F.Cu" "B.Cu")
		(net "P12V")
	)
	(via
		(at 74.39533 -374.130316)
		(size 1.016)
		(drill 0.508)
		(layers "F.Cu" "B.Cu")
		(net "P12V")
	)
	(via
		(at 84.52485 -85.159088)
		(size 1.016)
		(drill 0.508)
		(layers "F.Cu" "B.Cu")
		(net "P12V")
	)
	(via
		(at 78.223364 -133.133338)
		(size 1.016)
		(drill 0.508)
		(layers "F.Cu" "B.Cu")
		(net "P12V")
	)
	(via
		(at 64.698372 -433.5653)
		(size 1.016)
		(drill 0.508)
		(layers "F.Cu" "B.Cu")
		(net "P12V")
	)
	(via
		(at 39.947088 -155.847796)
		(size 1.016)
		(drill 0.508)
		(layers "F.Cu" "B.Cu")
		(net "P12V")
	)
	(via
		(at 42.15765 -75.21956)
		(size 1.016)
		(drill 0.508)
		(layers "F.Cu" "B.Cu")
		(net "P12V")
	)
	(via
		(at 64.215772 -56.302656)
		(size 1.016)
		(drill 0.508)
		(layers "F.Cu" "B.Cu")
		(net "P12V")
	)
	(via
		(at 64.698372 -425.854622)
		(size 1.016)
		(drill 0.508)
		(layers "F.Cu" "B.Cu")
		(net "P12V")
	)
	(via
		(at 67.918584 -458.522324)
		(size 1.016)
		(drill 0.508)
		(layers "F.Cu" "B.Cu")
		(net "P12V")
	)
	(via
		(at 60.895484 -106.146092)
		(size 1.016)
		(drill 0.508)
		(layers "F.Cu" "B.Cu")
		(net "P12V")
	)
	(via
		(at 67.436492 -437.42356)
		(size 1.016)
		(drill 0.508)
		(layers "F.Cu" "B.Cu")
		(net "P12V")
	)
	(via
		(at 65.648586 -465.61629)
		(size 1.016)
		(drill 0.508)
		(layers "F.Cu" "B.Cu")
		(net "P12V")
	)
	(via
		(at 77.253084 -174.962312)
		(size 1.016)
		(drill 0.508)
		(layers "F.Cu" "B.Cu")
		(net "P12V")
	)
	(via
		(at 57.601358 -332.466696)
		(size 1.016)
		(drill 0.508)
		(layers "F.Cu" "B.Cu")
		(net "P12V")
	)
	(via
		(at 66.742564 -243.804186)
		(size 1.016)
		(drill 0.508)
		(layers "F.Cu" "B.Cu")
		(net "P12V")
	)
	(via
		(at 79.231744 -302.832262)
		(size 1.016)
		(drill 0.508)
		(layers "F.Cu" "B.Cu")
		(net "P12V")
	)
	(via
		(at 39.560246 -341.837772)
		(size 1.016)
		(drill 0.508)
		(layers "F.Cu" "B.Cu")
		(net "P12V")
	)
	(via
		(at 78.03261 -485.244648)
		(size 1.016)
		(drill 0.508)
		(layers "F.Cu" "B.Cu")
		(net "P12V")
	)
	(via
		(at 67.040506 -389.671306)
		(size 1.016)
		(drill 0.508)
		(layers "F.Cu" "B.Cu")
		(net "P12V")
	)
	(via
		(at 61.746384 -332.466696)
		(size 1.016)
		(drill 0.508)
		(layers "F.Cu" "B.Cu")
		(net "P12V")
	)
	(via
		(at 59.573414 -521.035788)
		(size 1.016)
		(drill 0.508)
		(layers "F.Cu" "B.Cu")
		(net "P12V")
	)
	(via
		(at 42.271696 -256.869692)
		(size 1.016)
		(drill 0.508)
		(layers "F.Cu" "B.Cu")
		(net "P12V")
	)
	(via
		(at 61.70295 -338.409534)
		(size 1.016)
		(drill 0.508)
		(layers "F.Cu" "B.Cu")
		(net "P12V")
	)
	(via
		(at 67.57416 -103.415084)
		(size 1.016)
		(drill 0.508)
		(layers "F.Cu" "B.Cu")
		(net "P12V")
	)
	(via
		(at 59.80811 -328.800714)
		(size 1.016)
		(drill 0.508)
		(layers "F.Cu" "B.Cu")
		(net "P12V")
	)
	(via
		(at 57.557924 -340.31936)
		(size 1.016)
		(drill 0.508)
		(layers "F.Cu" "B.Cu")
		(net "P12V")
	)
	(via
		(at 70.7136 -389.717026)
		(size 1.016)
		(drill 0.508)
		(layers "F.Cu" "B.Cu")
		(net "P12V")
	)
	(via
		(at 65.617598 -518.66419)
		(size 1.016)
		(drill 0.508)
		(layers "F.Cu" "B.Cu")
		(net "P12V")
	)
	(via
		(at 74.39533 -370.607082)
		(size 1.016)
		(drill 0.508)
		(layers "F.Cu" "B.Cu")
		(net "P12V")
	)
	(via
		(at 66.705734 -247.494044)
		(size 1.016)
		(drill 0.508)
		(layers "F.Cu" "B.Cu")
		(net "P12V")
	)
	(via
		(at 62.377828 -525.142206)
		(size 1.016)
		(drill 0.508)
		(layers "F.Cu" "B.Cu")
		(net "P12V")
	)
	(via
		(at 66.705734 -249.456956)
		(size 1.016)
		(drill 0.508)
		(layers "F.Cu" "B.Cu")
		(net "P12V")
	)
	(via
		(at 60.895484 -103.477822)
		(size 1.016)
		(drill 0.508)
		(layers "F.Cu" "B.Cu")
		(net "P12V")
	)
	(via
		(at 57.041542 -521.035788)
		(size 1.016)
		(drill 0.508)
		(layers "F.Cu" "B.Cu")
		(net "P12V")
	)
	(via
		(at 67.860164 -156.832046)
		(size 1.016)
		(drill 0.508)
		(layers "F.Cu" "B.Cu")
		(net "P12V")
	)
	(via
		(at 55.680356 -328.800714)
		(size 1.016)
		(drill 0.508)
		(layers "F.Cu" "B.Cu")
		(net "P12V")
	)
	(via
		(at 68.969636 -391.42797)
		(size 1.016)
		(drill 0.508)
		(layers "F.Cu" "B.Cu")
		(net "P12V")
	)
	(via
		(at 69.730874 -100.780596)
		(size 1.016)
		(drill 0.508)
		(layers "F.Cu" "B.Cu")
		(net "P12V")
	)
	(via
		(at 14.837664 -323.185282)
		(size 0.508)
		(drill 0.254)
		(layers "F.Cu" "B.Cu")
		(net "P12V")
	)
	(via
		(at 63.854584 -217.210386)
		(size 1.016)
		(drill 0.508)
		(layers "F.Cu" "B.Cu")
		(net "P12V")
	)
	(via
		(at 68.60921 -521.035788)
		(size 1.016)
		(drill 0.508)
		(layers "F.Cu" "B.Cu")
		(net "P12V")
	)
	(via
		(at 69.428868 -423.760138)
		(size 1.016)
		(drill 0.508)
		(layers "F.Cu" "B.Cu")
		(net "P12V")
	)
	(via
		(at 74.359516 -485.198928)
		(size 1.016)
		(drill 0.508)
		(layers "F.Cu" "B.Cu")
		(net "P12V")
	)
	(via
		(at 65.933574 -328.5363)
		(size 1.016)
		(drill 0.508)
		(layers "F.Cu" "B.Cu")
		(net "P12V")
	)
	(via
		(at 65.167764 -11.575288)
		(size 1.016)
		(drill 0.508)
		(layers "F.Cu" "B.Cu")
		(net "P12V")
	)
	(via
		(at 70.86981 -285.515558)
		(size 1.016)
		(drill 0.508)
		(layers "F.Cu" "B.Cu")
		(net "P12V")
	)
	(via
		(at 65.167764 -16.624046)
		(size 1.016)
		(drill 0.508)
		(layers "F.Cu" "B.Cu")
		(net "P12V")
	)
	(via
		(at 63.618872 -462.044796)
		(size 1.016)
		(drill 0.508)
		(layers "F.Cu" "B.Cu")
		(net "P12V")
	)
	(via
		(at 64.215772 -65.976246)
		(size 1.016)
		(drill 0.508)
		(layers "F.Cu" "B.Cu")
		(net "P12V")
	)
	(via
		(at 39.560246 -339.87486)
		(size 1.016)
		(drill 0.508)
		(layers "F.Cu" "B.Cu")
		(net "P12V")
	)
	(via
		(at 66.742564 -241.133376)
		(size 1.016)
		(drill 0.508)
		(layers "F.Cu" "B.Cu")
		(net "P12V")
	)
	(via
		(at 67.827398 -465.617052)
		(size 1.016)
		(drill 0.508)
		(layers "F.Cu" "B.Cu")
		(net "P12V")
	)
	(via
		(at 63.854584 -221.316804)
		(size 1.016)
		(drill 0.508)
		(layers "F.Cu" "B.Cu")
		(net "P12V")
	)
	(via
		(at 40.256968 -428.65167)
		(size 1.016)
		(drill 0.508)
		(layers "F.Cu" "B.Cu")
		(net "P12V")
	)
	(via
		(at 68.969636 -393.19454)
		(size 1.016)
		(drill 0.508)
		(layers "F.Cu" "B.Cu")
		(net "P12V")
	)
	(via
		(at 67.57416 -100.744274)
		(size 1.016)
		(drill 0.508)
		(layers "F.Cu" "B.Cu")
		(net "P12V")
	)
	(via
		(at 80.057498 -174.962312)
		(size 1.016)
		(drill 0.508)
		(layers "F.Cu" "B.Cu")
		(net "P12V")
	)
	(via
		(at 76.425044 -379.46838)
		(size 1.016)
		(drill 0.508)
		(layers "F.Cu" "B.Cu")
		(net "P12V")
	)
	(via
		(at 71.057516 -16.624046)
		(size 1.016)
		(drill 0.508)
		(layers "F.Cu" "B.Cu")
		(net "P12V")
	)
	(via
		(at 40.256968 -432.758088)
		(size 1.016)
		(drill 0.508)
		(layers "F.Cu" "B.Cu")
		(net "P12V")
	)
	(via
		(at 80.057498 -177.105818)
		(size 1.016)
		(drill 0.508)
		(layers "F.Cu" "B.Cu")
		(net "P12V")
	)
	(via
		(at 66.437256 -419.65372)
		(size 1.016)
		(drill 0.508)
		(layers "F.Cu" "B.Cu")
		(net "P12V")
	)
	(via
		(at 55.671212 -336.36839)
		(size 1.016)
		(drill 0.508)
		(layers "F.Cu" "B.Cu")
		(net "P12V")
	)
	(via
		(at 64.215772 -64.013334)
		(size 1.016)
		(drill 0.508)
		(layers "F.Cu" "B.Cu")
		(net "P12V")
	)
	(via
		(at 80.057498 -165.724078)
		(size 1.016)
		(drill 0.508)
		(layers "F.Cu" "B.Cu")
		(net "P12V")
	)
	(via
		(at 59.798966 -338.409534)
		(size 1.016)
		(drill 0.508)
		(layers "F.Cu" "B.Cu")
		(net "P12V")
	)
	(via
		(at 68.737988 -323.19722)
		(size 1.016)
		(drill 0.508)
		(layers "F.Cu" "B.Cu")
		(net "P12V")
	)
	(via
		(at 68.60921 -515.99592)
		(size 1.016)
		(drill 0.508)
		(layers "F.Cu" "B.Cu")
		(net "P12V")
	)
	(via
		(at 62.377828 -515.99592)
		(size 1.016)
		(drill 0.508)
		(layers "F.Cu" "B.Cu")
		(net "P12V")
	)
	(via
		(at 80.81518 -260.878574)
		(size 1.016)
		(drill 0.508)
		(layers "F.Cu" "B.Cu")
		(net "P12V")
	)
	(via
		(at 77.253084 -172.9994)
		(size 1.016)
		(drill 0.508)
		(layers "F.Cu" "B.Cu")
		(net "P12V")
	)
	(via
		(at 67.502786 -431.193702)
		(size 1.016)
		(drill 0.508)
		(layers "F.Cu" "B.Cu")
		(net "P12V")
	)
	(via
		(at 67.860164 -145.450306)
		(size 1.016)
		(drill 0.508)
		(layers "F.Cu" "B.Cu")
		(net "P12V")
	)
	(via
		(at 71.057516 -13.955776)
		(size 1.016)
		(drill 0.508)
		(layers "F.Cu" "B.Cu")
		(net "P12V")
	)
	(via
		(at 65.617598 -513.32511)
		(size 1.016)
		(drill 0.508)
		(layers "F.Cu" "B.Cu")
		(net "P12V")
	)
	(via
		(at 70.851776 -154.68854)
		(size 1.016)
		(drill 0.508)
		(layers "F.Cu" "B.Cu")
		(net "P12V")
	)
	(via
		(at 65.648586 -467.38286)
		(size 1.016)
		(drill 0.508)
		(layers "F.Cu" "B.Cu")
		(net "P12V")
	)
	(via
		(at 64.775334 -193.67754)
		(size 1.016)
		(drill 0.508)
		(layers "F.Cu" "B.Cu")
		(net "P12V")
	)
	(via
		(at 67.860164 -152.725628)
		(size 1.016)
		(drill 0.508)
		(layers "F.Cu" "B.Cu")
		(net "P12V")
	)
	(via
		(at 59.1058 -41.069768)
		(size 1.016)
		(drill 0.508)
		(layers "F.Cu" "B.Cu")
		(net "P12V")
	)
	(via
		(at 80.057498 -167.959532)
		(size 1.016)
		(drill 0.508)
		(layers "F.Cu" "B.Cu")
		(net "P12V")
	)
	(via
		(at 87.306404 -88.55837)
		(size 1.016)
		(drill 0.508)
		(layers "F.Cu" "B.Cu")
		(net "P12V")
	)
	(via
		(at 62.377828 -518.66419)
		(size 1.016)
		(drill 0.508)
		(layers "F.Cu" "B.Cu")
		(net "P12V")
	)
	(via
		(at 79.231744 -304.975768)
		(size 1.016)
		(drill 0.508)
		(layers "F.Cu" "B.Cu")
		(net "P12V")
	)
	(via
		(at 66.742564 -245.644924)
		(size 1.016)
		(drill 0.508)
		(layers "F.Cu" "B.Cu")
		(net "P12V")
	)
	(via
		(at 67.57416 -106.083354)
		(size 1.016)
		(drill 0.508)
		(layers "F.Cu" "B.Cu")
		(net "P12V")
	)
	(via
		(at 56.573928 -43.213274)
		(size 1.016)
		(drill 0.508)
		(layers "F.Cu" "B.Cu")
		(net "P12V")
	)
	(via
		(at 39.947088 -160.887664)
		(size 1.016)
		(drill 0.508)
		(layers "F.Cu" "B.Cu")
		(net "P12V")
	)
	(via
		(at 59.798966 -334.477868)
		(size 1.016)
		(drill 0.508)
		(layers "F.Cu" "B.Cu")
		(net "P12V")
	)
	(via
		(at 77.253084 -167.959532)
		(size 1.016)
		(drill 0.508)
		(layers "F.Cu" "B.Cu")
		(net "P12V")
	)
	(via
		(at 73.244202 -285.47949)
		(size 1.016)
		(drill 0.508)
		(layers "F.Cu" "B.Cu")
		(net "P12V")
	)
	(via
		(at 63.573152 -463.859626)
		(size 1.016)
		(drill 0.508)
		(layers "F.Cu" "B.Cu")
		(net "P12V")
	)
	(via
		(at 80.464914 -131.242816)
		(size 1.016)
		(drill 0.508)
		(layers "F.Cu" "B.Cu")
		(net "P12V")
	)
	(via
		(at 60.895484 -100.807012)
		(size 1.016)
		(drill 0.508)
		(layers "F.Cu" "B.Cu")
		(net "P12V")
	)
	(via
		(at 67.207384 -56.302656)
		(size 1.016)
		(drill 0.508)
		(layers "F.Cu" "B.Cu")
		(net "P12V")
	)
	(via
		(at 74.851514 -302.832516)
		(size 1.016)
		(drill 0.508)
		(layers "F.Cu" "B.Cu")
		(net "P12V")
	)
	(via
		(at 76.336398 -131.142486)
		(size 1.016)
		(drill 0.508)
		(layers "F.Cu" "B.Cu")
		(net "P12V")
	)
	(via
		(at 68.57365 -290.89096)
		(size 1.016)
		(drill 0.508)
		(layers "F.Cu" "B.Cu")
		(net "P12V")
	)
	(via
		(at 59.573414 -518.66419)
		(size 1.016)
		(drill 0.508)
		(layers "F.Cu" "B.Cu")
		(net "P12V")
	)
	(via
		(at 64.775334 -191.714628)
		(size 1.016)
		(drill 0.508)
		(layers "F.Cu" "B.Cu")
		(net "P12V")
	)
	(via
		(at 61.70295 -336.36839)
		(size 1.016)
		(drill 0.508)
		(layers "F.Cu" "B.Cu")
		(net "P12V")
	)
	(via
		(at 78.03261 -488.767882)
		(size 1.016)
		(drill 0.508)
		(layers "F.Cu" "B.Cu")
		(net "P12V")
	)
	(via
		(at 80.057498 -172.9994)
		(size 1.016)
		(drill 0.508)
		(layers "F.Cu" "B.Cu")
		(net "P12V")
	)
	(via
		(at 74.34961 -377.70181)
		(size 1.016)
		(drill 0.508)
		(layers "F.Cu" "B.Cu")
		(net "P12V")
	)
	(via
		(at 39.947088 -164.994082)
		(size 1.016)
		(drill 0.508)
		(layers "F.Cu" "B.Cu")
		(net "P12V")
	)
	(via
		(at 70.658228 -304.957988)
		(size 1.016)
		(drill 0.508)
		(layers "F.Cu" "B.Cu")
		(net "P12V")
	)
	(via
		(at 74.851514 -304.976022)
		(size 1.016)
		(drill 0.508)
		(layers "F.Cu" "B.Cu")
		(net "P12V")
	)
	(via
		(at 42.15765 -77.182472)
		(size 1.016)
		(drill 0.508)
		(layers "F.Cu" "B.Cu")
		(net "P12V")
	)
	(via
		(at 82.144362 -297.892216)
		(size 0.508)
		(drill 0.254)
		(layers "F.Cu" "B.Cu")
		(net "P12V")
	)
	(via
		(at 76.288646 -486.955592)
		(size 1.016)
		(drill 0.508)
		(layers "F.Cu" "B.Cu")
		(net "P12V")
	)
	(via
		(at 40.256968 -430.614582)
		(size 1.016)
		(drill 0.508)
		(layers "F.Cu" "B.Cu")
		(net "P12V")
	)
	(via
		(at 78.603856 -375.945908)
		(size 1.016)
		(drill 0.508)
		(layers "F.Cu" "B.Cu")
		(net "P12V")
	)
	(via
		(at 57.041542 -515.99592)
		(size 1.016)
		(drill 0.508)
		(layers "F.Cu" "B.Cu")
		(net "P12V")
	)
	(via
		(at 72.64273 -393.24026)
		(size 1.016)
		(drill 0.508)
		(layers "F.Cu" "B.Cu")
		(net "P12V")
	)
	(via
		(at 68.969636 -389.671306)
		(size 1.016)
		(drill 0.508)
		(layers "F.Cu" "B.Cu")
		(net "P12V")
	)
	(via
		(at 63.173356 -103.514144)
		(size 1.016)
		(drill 0.508)
		(layers "F.Cu" "B.Cu")
		(net "P12V")
	)
	(via
		(at 78.695042 -370.607844)
		(size 1.016)
		(drill 0.508)
		(layers "F.Cu" "B.Cu")
		(net "P12V")
	)
	(via
		(at 69.697346 -249.456956)
		(size 1.016)
		(drill 0.508)
		(layers "F.Cu" "B.Cu")
		(net "P12V")
	)
	(via
		(at 42.271696 -259.013198)
		(size 1.016)
		(drill 0.508)
		(layers "F.Cu" "B.Cu")
		(net "P12V")
	)
	(via
		(at 39.947088 -153.612342)
		(size 1.016)
		(drill 0.508)
		(layers "F.Cu" "B.Cu")
		(net "P12V")
	)
	(via
		(at 80.78216 -262.564372)
		(size 1.016)
		(drill 0.508)
		(layers "F.Cu" "B.Cu")
		(net "P12V")
	)
	(via
		(at 78.223364 -135.276844)
		(size 1.016)
		(drill 0.508)
		(layers "F.Cu" "B.Cu")
		(net "P12V")
	)
	(via
		(at 74.359516 -488.722162)
		(size 1.016)
		(drill 0.508)
		(layers "F.Cu" "B.Cu")
		(net "P12V")
	)
	(via
		(at 84.50199 -88.55837)
		(size 1.016)
		(drill 0.508)
		(layers "F.Cu" "B.Cu")
		(net "P12V")
	)
	(via
		(at 63.173356 -106.182414)
		(size 1.016)
		(drill 0.508)
		(layers "F.Cu" "B.Cu")
		(net "P12V")
	)
	(via
		(at 39.560246 -343.981278)
		(size 1.016)
		(drill 0.508)
		(layers "F.Cu" "B.Cu")
		(net "P12V")
	)
	(via
		(at 67.860164 -147.68576)
		(size 1.016)
		(drill 0.508)
		(layers "F.Cu" "B.Cu")
		(net "P12V")
	)
	(via
		(at 65.423288 -106.0831)
		(size 1.016)
		(drill 0.508)
		(layers "F.Cu" "B.Cu")
		(net "P12V")
	)
	(via
		(at 69.697346 -251.600462)
		(size 1.016)
		(drill 0.508)
		(layers "F.Cu" "B.Cu")
		(net "P12V")
	)
	(via
		(at 66.846196 -217.210386)
		(size 1.016)
		(drill 0.508)
		(layers "F.Cu" "B.Cu")
		(net "P12V")
	)
	(via
		(at 78.695042 -374.131078)
		(size 1.016)
		(drill 0.508)
		(layers "F.Cu" "B.Cu")
		(net "P12V")
	)
	(via
		(at 67.040506 -391.42797)
		(size 1.016)
		(drill 0.508)
		(layers "F.Cu" "B.Cu")
		(net "P12V")
	)
	(via
		(at 55.671212 -340.31936)
		(size 1.016)
		(drill 0.508)
		(layers "F.Cu" "B.Cu")
		(net "P12V")
	)
	(via
		(at 74.39533 -372.363746)
		(size 1.016)
		(drill 0.508)
		(layers "F.Cu" "B.Cu")
		(net "P12V")
	)
	(via
		(at 76.288646 -485.198928)
		(size 1.016)
		(drill 0.508)
		(layers "F.Cu" "B.Cu")
		(net "P12V")
	)
	(via
		(at 70.851776 -152.725628)
		(size 1.016)
		(drill 0.508)
		(layers "F.Cu" "B.Cu")
		(net "P12V")
	)
	(via
		(at 57.567068 -326.967088)
		(size 1.016)
		(drill 0.508)
		(layers "F.Cu" "B.Cu")
		(net "P12V")
	)
	(via
		(at 42.341546 -247.122696)
		(size 1.016)
		(drill 0.508)
		(layers "F.Cu" "B.Cu")
		(net "P12V")
	)
	(via
		(at 79.96174 -488.767882)
		(size 1.016)
		(drill 0.508)
		(layers "F.Cu" "B.Cu")
		(net "P12V")
	)
	(via
		(at 70.658228 -302.814482)
		(size 1.016)
		(drill 0.508)
		(layers "F.Cu" "B.Cu")
		(net "P12V")
	)
	(via
		(at 57.567068 -328.800714)
		(size 1.016)
		(drill 0.508)
		(layers "F.Cu" "B.Cu")
		(net "P12V")
	)
	(via
		(at 70.86981 -290.854638)
		(size 1.016)
		(drill 0.508)
		(layers "F.Cu" "B.Cu")
		(net "P12V")
	)
	(via
		(at 78.603856 -377.702572)
		(size 1.016)
		(drill 0.508)
		(layers "F.Cu" "B.Cu")
		(net "P12V")
	)
	(via
		(at 42.15765 -67.508882)
		(size 1.016)
		(drill 0.508)
		(layers "F.Cu" "B.Cu")
		(net "P12V")
	)
	(via
		(at 65.617598 -515.99592)
		(size 1.016)
		(drill 0.508)
		(layers "F.Cu" "B.Cu")
		(net "P12V")
	)
	(via
		(at 68.737988 -332.87081)
		(size 1.016)
		(drill 0.508)
		(layers "F.Cu" "B.Cu")
		(net "P12V")
	)
	(via
		(at 79.96174 -485.244648)
		(size 1.016)
		(drill 0.508)
		(layers "F.Cu" "B.Cu")
		(net "P12V")
	)
	(via
		(at 76.470764 -370.607082)
		(size 1.016)
		(drill 0.508)
		(layers "F.Cu" "B.Cu")
		(net "P12V")
	)
	(via
		(at 61.712094 -330.70165)
		(size 1.016)
		(drill 0.508)
		(layers "F.Cu" "B.Cu")
		(net "P12V")
	)
	(via
		(at 72.827134 -302.77816)
		(size 1.016)
		(drill 0.508)
		(layers "F.Cu" "B.Cu")
		(net "P12V")
	)
	(via
		(at 65.167764 -13.955776)
		(size 1.016)
		(drill 0.508)
		(layers "F.Cu" "B.Cu")
		(net "P12V")
	)
	(via
		(at 59.573414 -515.99592)
		(size 1.016)
		(drill 0.508)
		(layers "F.Cu" "B.Cu")
		(net "P12V")
	)
	(via
		(at 42.341546 -249.793506)
		(size 1.016)
		(drill 0.508)
		(layers "F.Cu" "B.Cu")
		(net "P12V")
	)
	(via
		(at 59.573414 -522.9987)
		(size 1.016)
		(drill 0.508)
		(layers "F.Cu" "B.Cu")
		(net "P12V")
	)
	(via
		(at 65.694306 -462.044796)
		(size 1.016)
		(drill 0.508)
		(layers "F.Cu" "B.Cu")
		(net "P12V")
	)
	(via
		(at 39.947088 -162.850576)
		(size 1.016)
		(drill 0.508)
		(layers "F.Cu" "B.Cu")
		(net "P12V")
	)
	(via
		(at 63.854584 -219.173298)
		(size 1.016)
		(drill 0.508)
		(layers "F.Cu" "B.Cu")
		(net "P12V")
	)
	(via
		(at 67.502786 -425.854622)
		(size 1.016)
		(drill 0.508)
		(layers "F.Cu" "B.Cu")
		(net "P12V")
	)
	(via
		(at 67.860164 -150.35403)
		(size 1.016)
		(drill 0.508)
		(layers "F.Cu" "B.Cu")
		(net "P12V")
	)
	(via
		(at 70.86981 -288.186368)
		(size 1.016)
		(drill 0.508)
		(layers "F.Cu" "B.Cu")
		(net "P12V")
	)
	(via
		(at 73.177908 -13.955776)
		(size 1.016)
		(drill 0.508)
		(layers "F.Cu" "B.Cu")
		(net "P12V")
	)
	(via
		(at 56.573928 -41.069768)
		(size 1.016)
		(drill 0.508)
		(layers "F.Cu" "B.Cu")
		(net "P12V")
	)
	(via
		(at 59.439048 -195.821046)
		(size 1.016)
		(drill 0.508)
		(layers "F.Cu" "B.Cu")
		(net "P12V")
	)
	(via
		(at 76.425044 -375.945146)
		(size 1.016)
		(drill 0.508)
		(layers "F.Cu" "B.Cu")
		(net "P12V")
	)
	(via
		(at 67.274694 -43.213274)
		(size 1.016)
		(drill 0.508)
		(layers "F.Cu" "B.Cu")
		(net "P12V")
	)
	(via
		(at 65.617598 -525.142206)
		(size 1.016)
		(drill 0.508)
		(layers "F.Cu" "B.Cu")
		(net "P12V")
	)
	(via
		(at 66.349626 -288.259266)
		(size 1.016)
		(drill 0.508)
		(layers "F.Cu" "B.Cu")
		(net "P12V")
	)
	(via
		(at 65.933574 -335.014316)
		(size 1.016)
		(drill 0.508)
		(layers "F.Cu" "B.Cu")
		(net "P12V")
	)
	(via
		(at 77.253084 -177.105818)
		(size 1.016)
		(drill 0.508)
		(layers "F.Cu" "B.Cu")
		(net "P12V")
	)
	(via
		(at 64.698372 -428.525432)
		(size 1.016)
		(drill 0.508)
		(layers "F.Cu" "B.Cu")
		(net "P12V")
	)
	(via
		(at 57.557924 -338.409534)
		(size 1.016)
		(drill 0.508)
		(layers "F.Cu" "B.Cu")
		(net "P12V")
	)
	(via
		(at 77.977746 -262.564372)
		(size 1.016)
		(drill 0.508)
		(layers "F.Cu" "B.Cu")
		(net "P12V")
	)
	(via
		(at 76.425044 -377.70181)
		(size 1.016)
		(drill 0.508)
		(layers "F.Cu" "B.Cu")
		(net "P12V")
	)
	(via
		(at 59.439048 -191.714628)
		(size 1.016)
		(drill 0.508)
		(layers "F.Cu" "B.Cu")
		(net "P12V")
	)
	(via
		(at 82.585306 -133.18744)
		(size 1.016)
		(drill 0.508)
		(layers "F.Cu" "B.Cu")
		(net "P12V")
	)
	(via
		(at 65.933574 -323.19722)
		(size 1.016)
		(drill 0.508)
		(layers "F.Cu" "B.Cu")
		(net "P12V")
	)
	(via
		(at 64.632078 -437.42356)
		(size 1.016)
		(drill 0.508)
		(layers "F.Cu" "B.Cu")
		(net "P12V")
	)
	(via
		(at 68.57365 -285.55188)
		(size 1.016)
		(drill 0.508)
		(layers "F.Cu" "B.Cu")
		(net "P12V")
	)
	(via
		(at 69.428868 -414.613852)
		(size 1.016)
		(drill 0.508)
		(layers "F.Cu" "B.Cu")
		(net "P12V")
	)
	(via
		(at 55.680356 -330.70165)
		(size 1.016)
		(drill 0.508)
		(layers "F.Cu" "B.Cu")
		(net "P12V")
	)
	(via
		(at 78.010766 -260.878574)
		(size 1.016)
		(drill 0.508)
		(layers "F.Cu" "B.Cu")
		(net "P12V")
	)
	(via
		(at 68.979288 -13.955776)
		(size 1.016)
		(drill 0.508)
		(layers "F.Cu" "B.Cu")
		(net "P12V")
	)
	(via
		(at 87.329264 -82.78749)
		(size 1.016)
		(drill 0.508)
		(layers "F.Cu" "B.Cu")
		(net "P12V")
	)
	(via
		(at 69.428868 -417.282122)
		(size 1.016)
		(drill 0.508)
		(layers "F.Cu" "B.Cu")
		(net "P12V")
	)
	(via
		(at 57.041542 -513.32511)
		(size 1.016)
		(drill 0.508)
		(layers "F.Cu" "B.Cu")
		(net "P12V")
	)
	(via
		(at 64.283082 -43.213274)
		(size 1.016)
		(drill 0.508)
		(layers "F.Cu" "B.Cu")
		(net "P12V")
	)
	(via
		(at 65.648586 -463.859626)
		(size 1.016)
		(drill 0.508)
		(layers "F.Cu" "B.Cu")
		(net "P12V")
	)
	(via
		(at 68.979288 -11.575288)
		(size 1.016)
		(drill 0.508)
		(layers "F.Cu" "B.Cu")
		(net "P12V")
	)
	(via
		(at 65.694306 -458.521562)
		(size 1.016)
		(drill 0.508)
		(layers "F.Cu" "B.Cu")
		(net "P12V")
	)
	(via
		(at 68.737988 -328.5363)
		(size 1.016)
		(drill 0.508)
		(layers "F.Cu" "B.Cu")
		(net "P12V")
	)
	(via
		(at 74.851514 -300.869604)
		(size 1.016)
		(drill 0.508)
		(layers "F.Cu" "B.Cu")
		(net "P12V")
	)
	(via
		(at 67.502786 -433.5653)
		(size 1.016)
		(drill 0.508)
		(layers "F.Cu" "B.Cu")
		(net "P12V")
	)
	(via
		(at 66.437256 -411.943042)
		(size 1.016)
		(drill 0.508)
		(layers "F.Cu" "B.Cu")
		(net "P12V")
	)
	(via
		(at 59.573414 -513.32511)
		(size 1.016)
		(drill 0.508)
		(layers "F.Cu" "B.Cu")
		(net "P12V")
	)
	(via
		(at 69.697346 -247.494044)
		(size 1.016)
		(drill 0.508)
		(layers "F.Cu" "B.Cu")
		(net "P12V")
	)
	(via
		(at 70.7136 -393.24026)
		(size 1.016)
		(drill 0.508)
		(layers "F.Cu" "B.Cu")
		(net "P12V")
	)
	(via
		(at 78.223364 -131.170426)
		(size 1.016)
		(drill 0.508)
		(layers "F.Cu" "B.Cu")
		(net "P12V")
	)
	(via
		(at 57.567068 -330.70165)
		(size 1.016)
		(drill 0.508)
		(layers "F.Cu" "B.Cu")
		(net "P12V")
	)
	(via
		(at 63.173356 -100.843334)
		(size 1.016)
		(drill 0.508)
		(layers "F.Cu" "B.Cu")
		(net "P12V")
	)
	(via
		(at 80.85201 -254.326644)
		(size 1.016)
		(drill 0.508)
		(layers "F.Cu" "B.Cu")
		(net "P12V")
	)
	(via
		(at 14.822424 -325.072248)
		(size 0.508)
		(drill 0.254)
		(layers "F.Cu" "B.Cu")
		(net "P12V")
	)
	(via
		(at 67.502786 -435.528212)
		(size 1.016)
		(drill 0.508)
		(layers "F.Cu" "B.Cu")
		(net "P12V")
	)
	(via
		(at 59.8424 -332.466696)
		(size 1.016)
		(drill 0.508)
		(layers "F.Cu" "B.Cu")
		(net "P12V")
	)
	(via
		(at 72.64273 -389.717026)
		(size 1.016)
		(drill 0.508)
		(layers "F.Cu" "B.Cu")
		(net "P12V")
	)
	(via
		(at 63.817754 -288.259266)
		(size 1.016)
		(drill 0.508)
		(layers "F.Cu" "B.Cu")
		(net "P12V")
	)
	(via
		(at 87.329264 -85.159088)
		(size 1.016)
		(drill 0.508)
		(layers "F.Cu" "B.Cu")
		(net "P12V")
	)
	(via
		(at 74.359516 -486.955592)
		(size 1.016)
		(drill 0.508)
		(layers "F.Cu" "B.Cu")
		(net "P12V")
	)
	(via
		(at 64.698372 -435.528212)
		(size 1.016)
		(drill 0.508)
		(layers "F.Cu" "B.Cu")
		(net "P12V")
	)
	(via
		(at 73.244202 -288.1503)
		(size 1.016)
		(drill 0.508)
		(layers "F.Cu" "B.Cu")
		(net "P12V")
	)
	(via
		(at 61.910214 -39.106856)
		(size 1.016)
		(drill 0.508)
		(layers "F.Cu" "B.Cu")
		(net "P12V")
	)
	(via
		(at 69.428868 -411.943042)
		(size 1.016)
		(drill 0.508)
		(layers "F.Cu" "B.Cu")
		(net "P12V")
	)
	(via
		(at 68.57365 -288.22269)
		(size 1.016)
		(drill 0.508)
		(layers "F.Cu" "B.Cu")
		(net "P12V")
	)
	(via
		(at 61.70295 -334.477868)
		(size 1.016)
		(drill 0.508)
		(layers "F.Cu" "B.Cu")
		(net "P12V")
	)
	(via
		(at 66.437256 -423.760138)
		(size 1.016)
		(drill 0.508)
		(layers "F.Cu" "B.Cu")
		(net "P12V")
	)
	(via
		(at 80.818736 -257.579876)
		(size 1.016)
		(drill 0.508)
		(layers "F.Cu" "B.Cu")
		(net "P12V")
	)
	(via
		(at 41.108376 -464.36915)
		(size 0.508)
		(drill 0.254)
		(layers "F.Cu" "B.Cu")
		(net "P12V")
	)
	(via
		(at 59.1058 -43.213274)
		(size 1.016)
		(drill 0.508)
		(layers "F.Cu" "B.Cu")
		(net "P12V")
	)
	(via
		(at 41.025318 -110.774226)
		(size 0.508)
		(drill 0.254)
		(layers "F.Cu" "B.Cu")
		(net "P12V")
	)
	(via
		(at 64.283082 -39.106856)
		(size 1.016)
		(drill 0.508)
		(layers "F.Cu" "B.Cu")
		(net "P12V")
	)
	(via
		(at 87.329264 -80.933036)
		(size 1.016)
		(drill 0.508)
		(layers "F.Cu" "B.Cu")
		(net "P12V")
	)
	(via
		(at 78.014322 -257.579876)
		(size 1.016)
		(drill 0.508)
		(layers "F.Cu" "B.Cu")
		(net "P12V")
	)
	(via
		(at 77.253084 -165.724078)
		(size 1.016)
		(drill 0.508)
		(layers "F.Cu" "B.Cu")
		(net "P12V")
	)
	(via
		(at 73.244202 -290.81857)
		(size 1.016)
		(drill 0.508)
		(layers "F.Cu" "B.Cu")
		(net "P12V")
	)
	(via
		(at 68.60921 -522.9987)
		(size 1.016)
		(drill 0.508)
		(layers "F.Cu" "B.Cu")
		(net "P12V")
	)
	(via
		(at 59.1058 -39.106856)
		(size 1.016)
		(drill 0.508)
		(layers "F.Cu" "B.Cu")
		(net "P12V")
	)
	(via
		(at 59.798966 -340.31936)
		(size 1.016)
		(drill 0.508)
		(layers "F.Cu" "B.Cu")
		(net "P12V")
	)
	(via
		(at 61.712094 -328.800714)
		(size 1.016)
		(drill 0.508)
		(layers "F.Cu" "B.Cu")
		(net "P12V")
	)
	(via
		(at 66.846196 -221.316804)
		(size 1.016)
		(drill 0.508)
		(layers "F.Cu" "B.Cu")
		(net "P12V")
	)
	(via
		(at 64.215772 -58.973466)
		(size 1.016)
		(drill 0.508)
		(layers "F.Cu" "B.Cu")
		(net "P12V")
	)
	(via
		(at 66.437256 -421.616632)
		(size 1.016)
		(drill 0.508)
		(layers "F.Cu" "B.Cu")
		(net "P12V")
	)
	(via
		(at 63.817754 -285.588456)
		(size 1.016)
		(drill 0.508)
		(layers "F.Cu" "B.Cu")
		(net "P12V")
	)
	(via
		(at 62.377828 -521.035788)
		(size 1.016)
		(drill 0.508)
		(layers "F.Cu" "B.Cu")
		(net "P12V")
	)
	(via
		(at 80.464914 -135.349234)
		(size 1.016)
		(drill 0.508)
		(layers "F.Cu" "B.Cu")
		(net "P12V")
	)
	(via
		(at 39.560246 -332.164182)
		(size 1.016)
		(drill 0.508)
		(layers "F.Cu" "B.Cu")
		(net "P12V")
	)
	(via
		(at 42.15765 -79.325978)
		(size 1.016)
		(drill 0.508)
		(layers "F.Cu" "B.Cu")
		(net "P12V")
	)
	(via
		(at 71.057516 -11.575288)
		(size 1.016)
		(drill 0.508)
		(layers "F.Cu" "B.Cu")
		(net "P12V")
	)
	(via
		(at 63.618872 -460.278226)
		(size 1.016)
		(drill 0.508)
		(layers "F.Cu" "B.Cu")
		(net "P12V")
	)
	(via
		(at 77.253084 -170.627802)
		(size 1.016)
		(drill 0.508)
		(layers "F.Cu" "B.Cu")
		(net "P12V")
	)
	(via
		(at 77.997812 -255.854962)
		(size 1.016)
		(drill 0.508)
		(layers "F.Cu" "B.Cu")
		(net "P12V")
	)
	(via
		(at 56.573928 -39.106856)
		(size 1.016)
		(drill 0.508)
		(layers "F.Cu" "B.Cu")
		(net "P12V")
	)
	(via
		(at 65.694306 -460.278226)
		(size 1.016)
		(drill 0.508)
		(layers "F.Cu" "B.Cu")
		(net "P12V")
	)
	(via
		(at 67.502786 -428.525432)
		(size 1.016)
		(drill 0.508)
		(layers "F.Cu" "B.Cu")
		(net "P12V")
	)
	(via
		(at 59.439048 -193.67754)
		(size 1.016)
		(drill 0.508)
		(layers "F.Cu" "B.Cu")
		(net "P12V")
	)
	(via
		(at 63.618872 -458.521562)
		(size 1.016)
		(drill 0.508)
		(layers "F.Cu" "B.Cu")
		(net "P12V")
	)
	(via
		(at 68.737988 -330.907898)
		(size 1.016)
		(drill 0.508)
		(layers "F.Cu" "B.Cu")
		(net "P12V")
	)
	(via
		(at 84.504022 -79.24292)
		(size 1.016)
		(drill 0.508)
		(layers "F.Cu" "B.Cu")
		(net "P12V")
	)
	(via
		(at 65.617598 -521.035788)
		(size 1.016)
		(drill 0.508)
		(layers "F.Cu" "B.Cu")
		(net "P12V")
	)
	(via
		(at 40.256968 -423.611802)
		(size 1.016)
		(drill 0.508)
		(layers "F.Cu" "B.Cu")
		(net "P12V")
	)
	(via
		(at 84.52485 -82.78749)
		(size 1.016)
		(drill 0.508)
		(layers "F.Cu" "B.Cu")
		(net "P12V")
	)
	(via
		(at 70.851776 -145.450306)
		(size 1.016)
		(drill 0.508)
		(layers "F.Cu" "B.Cu")
		(net "P12V")
	)
	(via
		(at 67.827398 -463.860388)
		(size 1.016)
		(drill 0.508)
		(layers "F.Cu" "B.Cu")
		(net "P12V")
	)
	(via
		(at 66.349626 -290.927536)
		(size 1.016)
		(drill 0.508)
		(layers "F.Cu" "B.Cu")
		(net "P12V")
	)
	(via
		(at 41.015666 -199.171814)
		(size 0.508)
		(drill 0.254)
		(layers "F.Cu" "B.Cu")
		(net "P12V")
	)
	(via
		(at 68.60921 -518.66419)
		(size 1.016)
		(drill 0.508)
		(layers "F.Cu" "B.Cu")
		(net "P12V")
	)
	(via
		(at 70.7136 -391.47369)
		(size 1.016)
		(drill 0.508)
		(layers "F.Cu" "B.Cu")
		(net "P12V")
	)
	(via
		(at 67.040506 -393.19454)
		(size 1.016)
		(drill 0.508)
		(layers "F.Cu" "B.Cu")
		(net "P12V")
	)
	(via
		(at 67.918584 -462.045558)
		(size 1.016)
		(drill 0.508)
		(layers "F.Cu" "B.Cu")
		(net "P12V")
	)
	(via
		(at 63.817754 -290.927536)
		(size 1.016)
		(drill 0.508)
		(layers "F.Cu" "B.Cu")
		(net "P12V")
	)
	(via
		(at 70.851776 -156.832046)
		(size 1.016)
		(drill 0.508)
		(layers "F.Cu" "B.Cu")
		(net "P12V")
	)
	(via
		(at 72.827134 -300.815248)
		(size 1.016)
		(drill 0.508)
		(layers "F.Cu" "B.Cu")
		(net "P12V")
	)
	(via
		(at 67.207384 -61.641736)
		(size 1.016)
		(drill 0.508)
		(layers "F.Cu" "B.Cu")
		(net "P12V")
	)
	(via
		(at 61.97092 -191.714628)
		(size 1.016)
		(drill 0.508)
		(layers "F.Cu" "B.Cu")
		(net "P12V")
	)
	(via
		(at 78.047596 -254.326644)
		(size 1.016)
		(drill 0.508)
		(layers "F.Cu" "B.Cu")
		(net "P12V")
	)
	(via
		(at 68.60921 -513.32511)
		(size 1.016)
		(drill 0.508)
		(layers "F.Cu" "B.Cu")
		(net "P12V")
	)
	(via
		(at 72.64273 -391.47369)
		(size 1.016)
		(drill 0.508)
		(layers "F.Cu" "B.Cu")
		(net "P12V")
	)
	(via
		(at 64.215772 -68.119752)
		(size 1.016)
		(drill 0.508)
		(layers "F.Cu" "B.Cu")
		(net "P12V")
	)
	(via
		(at 65.933574 -325.86803)
		(size 1.016)
		(drill 0.508)
		(layers "F.Cu" "B.Cu")
		(net "P12V")
	)
	(via
		(at 57.041542 -522.9987)
		(size 1.016)
		(drill 0.508)
		(layers "F.Cu" "B.Cu")
		(net "P12V")
	)
	(via
		(at 57.557924 -334.477868)
		(size 1.016)
		(drill 0.508)
		(layers "F.Cu" "B.Cu")
		(net "P12V")
	)
	(via
		(at 61.97092 -193.67754)
		(size 1.016)
		(drill 0.508)
		(layers "F.Cu" "B.Cu")
		(net "P12V")
	)
	(via
		(at 67.827398 -467.383622)
		(size 1.016)
		(drill 0.508)
		(layers "F.Cu" "B.Cu")
		(net "P12V")
	)
	(via
		(at 55.671212 -334.477868)
		(size 1.016)
		(drill 0.508)
		(layers "F.Cu" "B.Cu")
		(net "P12V")
	)
	(via
		(at 69.734176 -241.133376)
		(size 1.016)
		(drill 0.508)
		(layers "F.Cu" "B.Cu")
		(net "P12V")
	)
	(via
		(at 80.83169 -259.246878)
		(size 1.016)
		(drill 0.508)
		(layers "F.Cu" "B.Cu")
		(net "P12V")
	)
	(via
		(at 65.423288 -103.41483)
		(size 1.016)
		(drill 0.508)
		(layers "F.Cu" "B.Cu")
		(net "P12V")
	)
	(via
		(at 61.910214 -41.069768)
		(size 1.016)
		(drill 0.508)
		(layers "F.Cu" "B.Cu")
		(net "P12V")
	)
	(via
		(at 68.737988 -325.86803)
		(size 1.016)
		(drill 0.508)
		(layers "F.Cu" "B.Cu")
		(net "P12V")
	)
	(via
		(at 57.041542 -518.66419)
		(size 1.016)
		(drill 0.508)
		(layers "F.Cu" "B.Cu")
		(net "P12V")
	)
	(via
		(at 76.336398 -135.248904)
		(size 1.016)
		(drill 0.508)
		(layers "F.Cu" "B.Cu")
		(net "P12V")
	)
	(via
		(at 65.423288 -100.74402)
		(size 1.016)
		(drill 0.508)
		(layers "F.Cu" "B.Cu")
		(net "P12V")
	)
	(via
		(at 67.207384 -64.013334)
		(size 1.016)
		(drill 0.508)
		(layers "F.Cu" "B.Cu")
		(net "P12V")
	)
	(via
		(at 81.374488 -57.398666)
		(size 0.508)
		(drill 0.254)
		(layers "F.Cu" "B.Cu")
		(net "T2_BLAD4_TXD")
	)
	(segment
		(start 7.736332 -219.449396)
		(end 8.665972 -219.449396)
		(width 0.127)
		(layer "In5.Cu")
		(net "T2_BLAD4_TXD")
	)
	(segment
		(start 83.754468 -50.348134)
		(end 85.978746 -48.123856)
		(width 0.127)
		(layer "In5.Cu")
		(net "T2_BLAD4_TXD")
	)
	(segment
		(start 15.03299 -197.200012)
		(end 15.03299 -176.554892)
		(width 0.127)
		(layer "In5.Cu")
		(net "T2_BLAD4_TXD")
	)
	(segment
		(start 80.743552 -57.398666)
		(end 81.374488 -57.398666)
		(width 0.127)
		(layer "In5.Cu")
		(net "T2_BLAD4_TXD")
	)
	(segment
		(start 6.645656 -220.540072)
		(end 7.736332 -219.449396)
		(width 0.127)
		(layer "In5.Cu")
		(net "T2_BLAD4_TXD")
	)
	(segment
		(start 18.873978 -110.674658)
		(end 18.873978 -93.01226)
		(width 0.127)
		(layer "In5.Cu")
		(net "T2_BLAD4_TXD")
	)
	(segment
		(start 51.030886 -87.111332)
		(end 80.743552 -57.398666)
		(width 0.127)
		(layer "In5.Cu")
		(net "T2_BLAD4_TXD")
	)
	(segment
		(start 9.456674 -218.658694)
		(end 9.456674 -202.776328)
		(width 0.127)
		(layer "In5.Cu")
		(net "T2_BLAD4_TXD")
	)
	(segment
		(start 24.774906 -87.111332)
		(end 51.030886 -87.111332)
		(width 0.127)
		(layer "In5.Cu")
		(net "T2_BLAD4_TXD")
	)
	(segment
		(start 8.665972 -219.449396)
		(end 9.456674 -218.658694)
		(width 0.127)
		(layer "In5.Cu")
		(net "T2_BLAD4_TXD")
	)
	(segment
		(start 85.978746 -48.123856)
		(end 92.406216 -48.123856)
		(width 0.127)
		(layer "In5.Cu")
		(net "T2_BLAD4_TXD")
	)
	(segment
		(start 1.948942 -220.670628)
		(end 4.083304 -220.670628)
		(width 0.127)
		(layer "In5.Cu")
		(net "T2_BLAD4_TXD")
	)
	(segment
		(start 93.220032 -50.231548)
		(end 92.72651 -50.72507)
		(width 0.127)
		(layer "In5.Cu")
		(net "T2_BLAD4_TXD")
	)
	(segment
		(start 92.406216 -48.123856)
		(end 93.220032 -48.937672)
		(width 0.127)
		(layer "In5.Cu")
		(net "T2_BLAD4_TXD")
	)
	(segment
		(start 81.374488 -57.398666)
		(end 83.754468 -55.018686)
		(width 0.127)
		(layer "In5.Cu")
		(net "T2_BLAD4_TXD")
	)
	(segment
		(start 24.734774 -116.535454)
		(end 18.873978 -110.674658)
		(width 0.127)
		(layer "In5.Cu")
		(net "T2_BLAD4_TXD")
	)
	(segment
		(start 4.21386 -220.540072)
		(end 6.645656 -220.540072)
		(width 0.127)
		(layer "In5.Cu")
		(net "T2_BLAD4_TXD")
	)
	(segment
		(start 92.72651 -50.72507)
		(end 90.71991 -50.72507)
		(width 0.127)
		(layer "In5.Cu")
		(net "T2_BLAD4_TXD")
	)
	(segment
		(start 83.754468 -55.018686)
		(end 83.754468 -50.348134)
		(width 0.127)
		(layer "In5.Cu")
		(net "T2_BLAD4_TXD")
	)
	(segment
		(start 93.220032 -48.937672)
		(end 93.220032 -50.231548)
		(width 0.127)
		(layer "In5.Cu")
		(net "T2_BLAD4_TXD")
	)
	(segment
		(start 15.03299 -176.554892)
		(end 24.734774 -166.853108)
		(width 0.127)
		(layer "In5.Cu")
		(net "T2_BLAD4_TXD")
	)
	(segment
		(start 24.734774 -166.853108)
		(end 24.734774 -116.535454)
		(width 0.127)
		(layer "In5.Cu")
		(net "T2_BLAD4_TXD")
	)
	(segment
		(start 9.456674 -202.776328)
		(end 15.03299 -197.200012)
		(width 0.127)
		(layer "In5.Cu")
		(net "T2_BLAD4_TXD")
	)
	(segment
		(start 18.873978 -93.01226)
		(end 24.774906 -87.111332)
		(width 0.127)
		(layer "In5.Cu")
		(net "T2_BLAD4_TXD")
	)
	(segment
		(start 4.083304 -220.670628)
		(end 4.21386 -220.540072)
		(width 0.127)
		(layer "In5.Cu")
		(net "T2_BLAD4_TXD")
	)
	(segment
		(start 30.45968 -461.829912)
		(end 27.640026 -461.829912)
		(width 0.4572)
		(layer "F.Cu")
		(net "PSU6_REMOTE_N")
	)
	(via
		(at 84.429346 -489.403898)
		(size 0.508)
		(drill 0.254)
		(layers "F.Cu" "B.Cu")
		(net "T12_BLAD1_EN")
	)
	(segment
		(start 8.048498 -322.436744)
		(end 7.122414 -321.51066)
		(width 0.127)
		(layer "In2.Cu")
		(net "T12_BLAD1_EN")
	)
	(segment
		(start 86.948264 -497.76507)
		(end 84.429346 -495.246152)
		(width 0.127)
		(layer "In2.Cu")
		(net "T12_BLAD1_EN")
	)
	(segment
		(start 72.50811 -456.81011)
		(end 40.495982 -456.81011)
		(width 0.127)
		(layer "In2.Cu")
		(net "T12_BLAD1_EN")
	)
	(segment
		(start 84.429346 -495.246152)
		(end 84.429346 -489.403898)
		(width 0.127)
		(layer "In2.Cu")
		(net "T12_BLAD1_EN")
	)
	(segment
		(start 37.584634 -447.215768)
		(end 35.859212 -445.490346)
		(width 0.127)
		(layer "In2.Cu")
		(net "T12_BLAD1_EN")
	)
	(segment
		(start 23.506176 -438.534048)
		(end 23.506176 -380.669546)
		(width 0.127)
		(layer "In2.Cu")
		(net "T12_BLAD1_EN")
	)
	(segment
		(start 12.853162 -370.016532)
		(end 12.853162 -333.965804)
		(width 0.127)
		(layer "In2.Cu")
		(net "T12_BLAD1_EN")
	)
	(segment
		(start 40.495982 -456.81011)
		(end 37.584634 -453.898762)
		(width 0.127)
		(layer "In2.Cu")
		(net "T12_BLAD1_EN")
	)
	(segment
		(start 7.122414 -321.51066)
		(end 4.790694 -321.51066)
		(width 0.127)
		(layer "In2.Cu")
		(net "T12_BLAD1_EN")
	)
	(segment
		(start 4.790694 -321.51066)
		(end 3.949954 -320.66992)
		(width 0.127)
		(layer "In2.Cu")
		(net "T12_BLAD1_EN")
	)
	(segment
		(start 83.433158 -486.045764)
		(end 83.433158 -467.735158)
		(width 0.127)
		(layer "In2.Cu")
		(net "T12_BLAD1_EN")
	)
	(segment
		(start 88.17991 -497.76507)
		(end 86.948264 -497.76507)
		(width 0.127)
		(layer "In2.Cu")
		(net "T12_BLAD1_EN")
	)
	(segment
		(start 35.859212 -445.490346)
		(end 30.462474 -445.490346)
		(width 0.127)
		(layer "In2.Cu")
		(net "T12_BLAD1_EN")
	)
	(segment
		(start 10.899902 -324.329552)
		(end 9.007094 -322.436744)
		(width 0.127)
		(layer "In2.Cu")
		(net "T12_BLAD1_EN")
	)
	(segment
		(start 84.429346 -489.403898)
		(end 84.429346 -487.041952)
		(width 0.127)
		(layer "In2.Cu")
		(net "T12_BLAD1_EN")
	)
	(segment
		(start 12.853162 -333.965804)
		(end 10.899902 -332.012544)
		(width 0.127)
		(layer "In2.Cu")
		(net "T12_BLAD1_EN")
	)
	(segment
		(start 37.584634 -453.898762)
		(end 37.584634 -447.215768)
		(width 0.127)
		(layer "In2.Cu")
		(net "T12_BLAD1_EN")
	)
	(segment
		(start 30.462474 -445.490346)
		(end 23.506176 -438.534048)
		(width 0.127)
		(layer "In2.Cu")
		(net "T12_BLAD1_EN")
	)
	(segment
		(start 23.506176 -380.669546)
		(end 12.853162 -370.016532)
		(width 0.127)
		(layer "In2.Cu")
		(net "T12_BLAD1_EN")
	)
	(segment
		(start 84.429346 -487.041952)
		(end 83.433158 -486.045764)
		(width 0.127)
		(layer "In2.Cu")
		(net "T12_BLAD1_EN")
	)
	(segment
		(start 83.433158 -467.735158)
		(end 72.50811 -456.81011)
		(width 0.127)
		(layer "In2.Cu")
		(net "T12_BLAD1_EN")
	)
	(segment
		(start 9.007094 -322.436744)
		(end 8.048498 -322.436744)
		(width 0.127)
		(layer "In2.Cu")
		(net "T12_BLAD1_EN")
	)
	(segment
		(start 10.899902 -332.012544)
		(end 10.899902 -324.329552)
		(width 0.127)
		(layer "In2.Cu")
		(net "T12_BLAD1_EN")
	)
	(via
		(at 84.085684 -58.933334)
		(size 0.508)
		(drill 0.254)
		(layers "F.Cu" "B.Cu")
		(net "T2_BLAD2_TXD")
	)
	(segment
		(start 16.960596 -178.25466)
		(end 16.960596 -198.467726)
		(width 0.127)
		(layer "In5.Cu")
		(net "T2_BLAD2_TXD")
	)
	(segment
		(start 11.167618 -222.50527)
		(end 9.779254 -223.893634)
		(width 0.127)
		(layer "In5.Cu")
		(net "T2_BLAD2_TXD")
	)
	(segment
		(start 11.167618 -204.260704)
		(end 11.167618 -222.50527)
		(width 0.127)
		(layer "In5.Cu")
		(net "T2_BLAD2_TXD")
	)
	(segment
		(start 77.8129 -66.4464)
		(end 76.572618 -66.4464)
		(width 0.127)
		(layer "In5.Cu")
		(net "T2_BLAD2_TXD")
	)
	(segment
		(start 86.244176 -56.774842)
		(end 84.085684 -58.933334)
		(width 0.127)
		(layer "In5.Cu")
		(net "T2_BLAD2_TXD")
	)
	(segment
		(start 7.925562 -223.893634)
		(end 7.003542 -224.815654)
		(width 0.127)
		(layer "In5.Cu")
		(net "T2_BLAD2_TXD")
	)
	(segment
		(start 78.946756 -64.072262)
		(end 78.946756 -65.312544)
		(width 0.127)
		(layer "In5.Cu")
		(net "T2_BLAD2_TXD")
	)
	(segment
		(start 21.018754 -109.454696)
		(end 26.491438 -114.92738)
		(width 0.127)
		(layer "In5.Cu")
		(net "T2_BLAD2_TXD")
	)
	(segment
		(start 9.779254 -223.893634)
		(end 7.925562 -223.893634)
		(width 0.127)
		(layer "In5.Cu")
		(net "T2_BLAD2_TXD")
	)
	(segment
		(start 4.803902 -224.815654)
		(end 3.948938 -225.670618)
		(width 0.127)
		(layer "In5.Cu")
		(net "T2_BLAD2_TXD")
	)
	(segment
		(start 16.960596 -198.467726)
		(end 11.167618 -204.260704)
		(width 0.127)
		(layer "In5.Cu")
		(net "T2_BLAD2_TXD")
	)
	(segment
		(start 76.572618 -66.4464)
		(end 54.185058 -88.83396)
		(width 0.127)
		(layer "In5.Cu")
		(net "T2_BLAD2_TXD")
	)
	(segment
		(start 26.491438 -168.723818)
		(end 16.960596 -178.25466)
		(width 0.127)
		(layer "In5.Cu")
		(net "T2_BLAD2_TXD")
	)
	(segment
		(start 90.71991 -53.26507)
		(end 87.210138 -56.774842)
		(width 0.127)
		(layer "In5.Cu")
		(net "T2_BLAD2_TXD")
	)
	(segment
		(start 78.946756 -65.312544)
		(end 77.8129 -66.4464)
		(width 0.127)
		(layer "In5.Cu")
		(net "T2_BLAD2_TXD")
	)
	(segment
		(start 87.210138 -56.774842)
		(end 86.244176 -56.774842)
		(width 0.127)
		(layer "In5.Cu")
		(net "T2_BLAD2_TXD")
	)
	(segment
		(start 26.069798 -88.83396)
		(end 21.018754 -93.885004)
		(width 0.127)
		(layer "In5.Cu")
		(net "T2_BLAD2_TXD")
	)
	(segment
		(start 21.018754 -93.885004)
		(end 21.018754 -109.454696)
		(width 0.127)
		(layer "In5.Cu")
		(net "T2_BLAD2_TXD")
	)
	(segment
		(start 84.085684 -58.933334)
		(end 78.946756 -64.072262)
		(width 0.127)
		(layer "In5.Cu")
		(net "T2_BLAD2_TXD")
	)
	(segment
		(start 7.003542 -224.815654)
		(end 4.803902 -224.815654)
		(width 0.127)
		(layer "In5.Cu")
		(net "T2_BLAD2_TXD")
	)
	(segment
		(start 54.185058 -88.83396)
		(end 26.069798 -88.83396)
		(width 0.127)
		(layer "In5.Cu")
		(net "T2_BLAD2_TXD")
	)
	(segment
		(start 26.491438 -114.92738)
		(end 26.491438 -168.723818)
		(width 0.127)
		(layer "In5.Cu")
		(net "T2_BLAD2_TXD")
	)
	(segment
		(start 30.45968 -285.02991)
		(end 28.25369 -285.02991)
		(width 0.508)
		(layer "F.Cu")
		(net "PSU4_REMOTE_N")
	)
	(segment
		(start 28.253436 -285.030164)
		(end 27.643836 -285.030164)
		(width 0.508)
		(layer "F.Cu")
		(net "PSU4_REMOTE_N")
	)
	(segment
		(start 28.25369 -285.02991)
		(end 28.253436 -285.030164)
		(width 0.508)
		(layer "F.Cu")
		(net "PSU4_REMOTE_N")
	)
	(via
		(at 88.309704 -488.22991)
		(size 0.508)
		(drill 0.254)
		(layers "F.Cu" "B.Cu")
		(net "T12_BLAD4_EN")
	)
	(segment
		(start 11.94181 -331.653134)
		(end 13.843762 -333.555086)
		(width 0.127)
		(layer "In2.Cu")
		(net "T12_BLAD4_EN")
	)
	(segment
		(start 9.392666 -318.752728)
		(end 11.94181 -321.301872)
		(width 0.127)
		(layer "In2.Cu")
		(net "T12_BLAD4_EN")
	)
	(segment
		(start 36.24707 -444.215774)
		(end 38.798246 -446.76695)
		(width 0.127)
		(layer "In2.Cu")
		(net "T12_BLAD4_EN")
	)
	(segment
		(start 1.949958 -317.669926)
		(end 6.724904 -317.669926)
		(width 0.127)
		(layer "In2.Cu")
		(net "T12_BLAD4_EN")
	)
	(segment
		(start 84.716874 -467.302342)
		(end 84.716874 -484.63454)
		(width 0.127)
		(layer "In2.Cu")
		(net "T12_BLAD4_EN")
	)
	(segment
		(start 38.798246 -453.395842)
		(end 40.998902 -455.596498)
		(width 0.127)
		(layer "In2.Cu")
		(net "T12_BLAD4_EN")
	)
	(segment
		(start 6.724904 -317.669926)
		(end 7.807706 -318.752728)
		(width 0.127)
		(layer "In2.Cu")
		(net "T12_BLAD4_EN")
	)
	(segment
		(start 89.44991 -489.367576)
		(end 88.309704 -488.22737)
		(width 0.127)
		(layer "In2.Cu")
		(net "T12_BLAD4_EN")
	)
	(segment
		(start 30.58922 -444.215774)
		(end 36.24707 -444.215774)
		(width 0.127)
		(layer "In2.Cu")
		(net "T12_BLAD4_EN")
	)
	(segment
		(start 24.577548 -438.204102)
		(end 30.58922 -444.215774)
		(width 0.127)
		(layer "In2.Cu")
		(net "T12_BLAD4_EN")
	)
	(segment
		(start 7.807706 -318.752728)
		(end 9.392666 -318.752728)
		(width 0.127)
		(layer "In2.Cu")
		(net "T12_BLAD4_EN")
	)
	(segment
		(start 11.94181 -321.301872)
		(end 11.94181 -331.653134)
		(width 0.127)
		(layer "In2.Cu")
		(net "T12_BLAD4_EN")
	)
	(segment
		(start 24.577548 -380.233174)
		(end 24.577548 -438.204102)
		(width 0.127)
		(layer "In2.Cu")
		(net "T12_BLAD4_EN")
	)
	(segment
		(start 40.998902 -455.596498)
		(end 73.01103 -455.596498)
		(width 0.127)
		(layer "In2.Cu")
		(net "T12_BLAD4_EN")
	)
	(segment
		(start 88.309704 -488.22737)
		(end 88.309704 -488.22991)
		(width 0.127)
		(layer "In2.Cu")
		(net "T12_BLAD4_EN")
	)
	(segment
		(start 84.716874 -484.63454)
		(end 88.309704 -488.22737)
		(width 0.127)
		(layer "In2.Cu")
		(net "T12_BLAD4_EN")
	)
	(segment
		(start 38.798246 -446.76695)
		(end 38.798246 -453.395842)
		(width 0.127)
		(layer "In2.Cu")
		(net "T12_BLAD4_EN")
	)
	(segment
		(start 13.843762 -333.555086)
		(end 13.843762 -369.499388)
		(width 0.127)
		(layer "In2.Cu")
		(net "T12_BLAD4_EN")
	)
	(segment
		(start 89.44991 -493.95507)
		(end 89.44991 -489.367576)
		(width 0.127)
		(layer "In2.Cu")
		(net "T12_BLAD4_EN")
	)
	(segment
		(start 73.01103 -455.596498)
		(end 84.716874 -467.302342)
		(width 0.127)
		(layer "In2.Cu")
		(net "T12_BLAD4_EN")
	)
	(segment
		(start 13.843762 -369.499388)
		(end 24.577548 -380.233174)
		(width 0.127)
		(layer "In2.Cu")
		(net "T12_BLAD4_EN")
	)
	(via
		(at 83.80222 -62.403736)
		(size 0.508)
		(drill 0.254)
		(layers "F.Cu" "B.Cu")
		(net "T2_BLAD2_EN")
	)
	(segment
		(start 6.09981 -232.861866)
		(end 4.533646 -234.42803)
		(width 0.127)
		(layer "In2.Cu")
		(net "T2_BLAD2_EN")
	)
	(segment
		(start 83.80222 -62.403736)
		(end 55.445152 -90.760804)
		(width 0.127)
		(layer "In2.Cu")
		(net "T2_BLAD2_EN")
	)
	(segment
		(start 89.44991 -51.99507)
		(end 89.44991 -54.494938)
		(width 0.127)
		(layer "In2.Cu")
		(net "T2_BLAD2_EN")
	)
	(segment
		(start 28.205938 -171.44365)
		(end 19.610578 -180.03901)
		(width 0.127)
		(layer "In2.Cu")
		(net "T2_BLAD2_EN")
	)
	(segment
		(start 28.973018 -92.751656)
		(end 28.973018 -99.941888)
		(width 0.127)
		(layer "In2.Cu")
		(net "T2_BLAD2_EN")
	)
	(segment
		(start 89.44991 -54.494938)
		(end 88.69426 -55.250588)
		(width 0.127)
		(layer "In2.Cu")
		(net "T2_BLAD2_EN")
	)
	(segment
		(start 88.69426 -57.511696)
		(end 83.80222 -62.403736)
		(width 0.127)
		(layer "In2.Cu")
		(net "T2_BLAD2_EN")
	)
	(segment
		(start 28.205938 -112.030002)
		(end 28.205938 -171.44365)
		(width 0.127)
		(layer "In2.Cu")
		(net "T2_BLAD2_EN")
	)
	(segment
		(start 19.610578 -180.03901)
		(end 19.610578 -197.33006)
		(width 0.127)
		(layer "In2.Cu")
		(net "T2_BLAD2_EN")
	)
	(segment
		(start 28.973018 -111.262922)
		(end 28.205938 -112.030002)
		(width 0.127)
		(layer "In2.Cu")
		(net "T2_BLAD2_EN")
	)
	(segment
		(start 8.261604 -231.855518)
		(end 7.255256 -232.861866)
		(width 0.127)
		(layer "In2.Cu")
		(net "T2_BLAD2_EN")
	)
	(segment
		(start 3.706368 -234.42803)
		(end 1.948942 -232.670604)
		(width 0.127)
		(layer "In2.Cu")
		(net "T2_BLAD2_EN")
	)
	(segment
		(start 28.973018 -105.625646)
		(end 28.973018 -111.262922)
		(width 0.127)
		(layer "In2.Cu")
		(net "T2_BLAD2_EN")
	)
	(segment
		(start 55.445152 -90.760804)
		(end 30.96387 -90.760804)
		(width 0.127)
		(layer "In2.Cu")
		(net "T2_BLAD2_EN")
	)
	(segment
		(start 88.69426 -55.250588)
		(end 88.69426 -57.511696)
		(width 0.127)
		(layer "In2.Cu")
		(net "T2_BLAD2_EN")
	)
	(segment
		(start 7.255256 -232.861866)
		(end 6.09981 -232.861866)
		(width 0.127)
		(layer "In2.Cu")
		(net "T2_BLAD2_EN")
	)
	(segment
		(start 23.418038 -219.826586)
		(end 11.389106 -231.855518)
		(width 0.127)
		(layer "In2.Cu")
		(net "T2_BLAD2_EN")
	)
	(segment
		(start 19.610578 -197.33006)
		(end 23.418038 -201.13752)
		(width 0.127)
		(layer "In2.Cu")
		(net "T2_BLAD2_EN")
	)
	(segment
		(start 28.435554 -100.479352)
		(end 28.435554 -105.088182)
		(width 0.127)
		(layer "In2.Cu")
		(net "T2_BLAD2_EN")
	)
	(segment
		(start 4.533646 -234.42803)
		(end 3.706368 -234.42803)
		(width 0.127)
		(layer "In2.Cu")
		(net "T2_BLAD2_EN")
	)
	(segment
		(start 23.418038 -201.13752)
		(end 23.418038 -219.826586)
		(width 0.127)
		(layer "In2.Cu")
		(net "T2_BLAD2_EN")
	)
	(segment
		(start 30.96387 -90.760804)
		(end 28.973018 -92.751656)
		(width 0.127)
		(layer "In2.Cu")
		(net "T2_BLAD2_EN")
	)
	(segment
		(start 28.973018 -99.941888)
		(end 28.435554 -100.479352)
		(width 0.127)
		(layer "In2.Cu")
		(net "T2_BLAD2_EN")
	)
	(segment
		(start 28.435554 -105.088182)
		(end 28.973018 -105.625646)
		(width 0.127)
		(layer "In2.Cu")
		(net "T2_BLAD2_EN")
	)
	(segment
		(start 11.389106 -231.855518)
		(end 8.261604 -231.855518)
		(width 0.127)
		(layer "In2.Cu")
		(net "T2_BLAD2_EN")
	)
	(via
		(at 86.445344 -488.291886)
		(size 0.508)
		(drill 0.254)
		(layers "F.Cu" "B.Cu")
		(net "T12_BLAD3_EN")
	)
	(segment
		(start 86.445344 -488.291886)
		(end 86.445344 -487.471974)
		(width 0.127)
		(layer "In2.Cu")
		(net "T12_BLAD3_EN")
	)
	(segment
		(start 30.595062 -444.688722)
		(end 24.241506 -438.335166)
		(width 0.127)
		(layer "In2.Cu")
		(net "T12_BLAD3_EN")
	)
	(segment
		(start 13.513562 -369.644422)
		(end 13.513562 -333.691992)
		(width 0.127)
		(layer "In2.Cu")
		(net "T12_BLAD3_EN")
	)
	(segment
		(start 88.17991 -495.22507)
		(end 88.17991 -490.026452)
		(width 0.127)
		(layer "In2.Cu")
		(net "T12_BLAD3_EN")
	)
	(segment
		(start 40.848026 -455.960734)
		(end 38.43401 -453.546718)
		(width 0.127)
		(layer "In2.Cu")
		(net "T12_BLAD3_EN")
	)
	(segment
		(start 86.445344 -487.471974)
		(end 84.282534 -485.309164)
		(width 0.127)
		(layer "In2.Cu")
		(net "T12_BLAD3_EN")
	)
	(segment
		(start 4.694682 -319.414652)
		(end 3.949954 -318.669924)
		(width 0.127)
		(layer "In2.Cu")
		(net "T12_BLAD3_EN")
	)
	(segment
		(start 84.282534 -485.309164)
		(end 84.282534 -467.383114)
		(width 0.127)
		(layer "In2.Cu")
		(net "T12_BLAD3_EN")
	)
	(segment
		(start 24.241506 -380.372366)
		(end 13.513562 -369.644422)
		(width 0.127)
		(layer "In2.Cu")
		(net "T12_BLAD3_EN")
	)
	(segment
		(start 11.61161 -322.52158)
		(end 9.496298 -320.406268)
		(width 0.127)
		(layer "In2.Cu")
		(net "T12_BLAD3_EN")
	)
	(segment
		(start 38.43401 -446.955926)
		(end 36.166806 -444.688722)
		(width 0.127)
		(layer "In2.Cu")
		(net "T12_BLAD3_EN")
	)
	(segment
		(start 8.153654 -320.406268)
		(end 7.162038 -319.414652)
		(width 0.127)
		(layer "In2.Cu")
		(net "T12_BLAD3_EN")
	)
	(segment
		(start 72.860154 -455.960734)
		(end 40.848026 -455.960734)
		(width 0.127)
		(layer "In2.Cu")
		(net "T12_BLAD3_EN")
	)
	(segment
		(start 13.513562 -333.691992)
		(end 11.61161 -331.79004)
		(width 0.127)
		(layer "In2.Cu")
		(net "T12_BLAD3_EN")
	)
	(segment
		(start 11.61161 -331.79004)
		(end 11.61161 -322.52158)
		(width 0.127)
		(layer "In2.Cu")
		(net "T12_BLAD3_EN")
	)
	(segment
		(start 38.43401 -453.546718)
		(end 38.43401 -446.955926)
		(width 0.127)
		(layer "In2.Cu")
		(net "T12_BLAD3_EN")
	)
	(segment
		(start 9.496298 -320.406268)
		(end 8.153654 -320.406268)
		(width 0.127)
		(layer "In2.Cu")
		(net "T12_BLAD3_EN")
	)
	(segment
		(start 7.162038 -319.414652)
		(end 4.694682 -319.414652)
		(width 0.127)
		(layer "In2.Cu")
		(net "T12_BLAD3_EN")
	)
	(segment
		(start 36.166806 -444.688722)
		(end 30.595062 -444.688722)
		(width 0.127)
		(layer "In2.Cu")
		(net "T12_BLAD3_EN")
	)
	(segment
		(start 24.241506 -438.335166)
		(end 24.241506 -380.372366)
		(width 0.127)
		(layer "In2.Cu")
		(net "T12_BLAD3_EN")
	)
	(segment
		(start 84.282534 -467.383114)
		(end 72.860154 -455.960734)
		(width 0.127)
		(layer "In2.Cu")
		(net "T12_BLAD3_EN")
	)
	(segment
		(start 88.17991 -490.026452)
		(end 86.445344 -488.291886)
		(width 0.127)
		(layer "In2.Cu")
		(net "T12_BLAD3_EN")
	)
	(via
		(at 81.762346 -60.486798)
		(size 0.508)
		(drill 0.254)
		(layers "F.Cu" "B.Cu")
		(net "T2_BLAD2_RXD")
	)
	(segment
		(start 81.762346 -60.486798)
		(end 85.88248 -56.366664)
		(width 0.127)
		(layer "In5.Cu")
		(net "T2_BLAD2_RXD")
	)
	(segment
		(start 20.630896 -109.8423)
		(end 20.630896 -93.627702)
		(width 0.127)
		(layer "In5.Cu")
		(net "T2_BLAD2_RXD")
	)
	(segment
		(start 26.126186 -115.33759)
		(end 20.630896 -109.8423)
		(width 0.127)
		(layer "In5.Cu")
		(net "T2_BLAD2_RXD")
	)
	(segment
		(start 6.86181 -224.473516)
		(end 7.78383 -223.551496)
		(width 0.127)
		(layer "In5.Cu")
		(net "T2_BLAD2_RXD")
	)
	(segment
		(start 9.637522 -223.551496)
		(end 10.82548 -222.363538)
		(width 0.127)
		(layer "In5.Cu")
		(net "T2_BLAD2_RXD")
	)
	(segment
		(start 10.82548 -203.987146)
		(end 16.584422 -198.228204)
		(width 0.127)
		(layer "In5.Cu")
		(net "T2_BLAD2_RXD")
	)
	(segment
		(start 16.584422 -198.228204)
		(end 16.584422 -177.96891)
		(width 0.127)
		(layer "In5.Cu")
		(net "T2_BLAD2_RXD")
	)
	(segment
		(start 25.766776 -88.491822)
		(end 53.757322 -88.491822)
		(width 0.127)
		(layer "In5.Cu")
		(net "T2_BLAD2_RXD")
	)
	(segment
		(start 10.82548 -222.363538)
		(end 10.82548 -203.987146)
		(width 0.127)
		(layer "In5.Cu")
		(net "T2_BLAD2_RXD")
	)
	(segment
		(start 1.948942 -226.670616)
		(end 4.146042 -224.473516)
		(width 0.127)
		(layer "In5.Cu")
		(net "T2_BLAD2_RXD")
	)
	(segment
		(start 20.630896 -93.627702)
		(end 25.766776 -88.491822)
		(width 0.127)
		(layer "In5.Cu")
		(net "T2_BLAD2_RXD")
	)
	(segment
		(start 90.695018 -51.99507)
		(end 91.98991 -51.99507)
		(width 0.127)
		(layer "In5.Cu")
		(net "T2_BLAD2_RXD")
	)
	(segment
		(start 86.323424 -56.366664)
		(end 90.695018 -51.99507)
		(width 0.127)
		(layer "In5.Cu")
		(net "T2_BLAD2_RXD")
	)
	(segment
		(start 7.78383 -223.551496)
		(end 9.637522 -223.551496)
		(width 0.127)
		(layer "In5.Cu")
		(net "T2_BLAD2_RXD")
	)
	(segment
		(start 85.88248 -56.366664)
		(end 86.323424 -56.366664)
		(width 0.127)
		(layer "In5.Cu")
		(net "T2_BLAD2_RXD")
	)
	(segment
		(start 26.126186 -168.427146)
		(end 26.126186 -115.33759)
		(width 0.127)
		(layer "In5.Cu")
		(net "T2_BLAD2_RXD")
	)
	(segment
		(start 16.584422 -177.96891)
		(end 26.126186 -168.427146)
		(width 0.127)
		(layer "In5.Cu")
		(net "T2_BLAD2_RXD")
	)
	(segment
		(start 53.757322 -88.491822)
		(end 81.762346 -60.486798)
		(width 0.127)
		(layer "In5.Cu")
		(net "T2_BLAD2_RXD")
	)
	(segment
		(start 4.146042 -224.473516)
		(end 6.86181 -224.473516)
		(width 0.127)
		(layer "In5.Cu")
		(net "T2_BLAD2_RXD")
	)
	(segment
		(start 19.95678 -316.854586)
		(end 22.981158 -319.878964)
		(width 0.1524)
		(layer "F.Cu")
		(net "I2C_PSU3_SDA")
	)
	(segment
		(start 22.981158 -319.878964)
		(end 22.981158 -335.465674)
		(width 0.1524)
		(layer "F.Cu")
		(net "I2C_PSU3_SDA")
	)
	(segment
		(start 23.133558 -335.618074)
		(end 23.17496 -335.618074)
		(width 0.1524)
		(layer "F.Cu")
		(net "I2C_PSU3_SDA")
	)
	(segment
		(start 22.981158 -335.465674)
		(end 23.133558 -335.618074)
		(width 0.1524)
		(layer "F.Cu")
		(net "I2C_PSU3_SDA")
	)
	(segment
		(start 23.17496 -335.618074)
		(end 25.582626 -338.02574)
		(width 0.1524)
		(layer "F.Cu")
		(net "I2C_PSU3_SDA")
	)
	(segment
		(start 11.808714 -316.854586)
		(end 19.95678 -316.854586)
		(width 0.1524)
		(layer "F.Cu")
		(net "I2C_PSU3_SDA")
	)
	(segment
		(start 6.449822 -318.669924)
		(end 9.993376 -318.669924)
		(width 0.1524)
		(layer "F.Cu")
		(net "I2C_PSU3_SDA")
	)
	(segment
		(start 9.993376 -318.669924)
		(end 11.808714 -316.854586)
		(width 0.1524)
		(layer "F.Cu")
		(net "I2C_PSU3_SDA")
	)
	(via
		(at 25.582626 -338.02574)
		(size 0.508)
		(drill 0.254)
		(layers "F.Cu" "B.Cu")
		(net "I2C_PSU3_SDA")
	)
	(segment
		(start 29.064966 -374.501156)
		(end 27.37231 -376.193812)
		(width 0.1524)
		(layer "B.Cu")
		(net "I2C_PSU3_SDA")
	)
	(segment
		(start 27.37231 -376.193812)
		(end 27.37231 -438.422542)
		(width 0.1524)
		(layer "B.Cu")
		(net "I2C_PSU3_SDA")
	)
	(segment
		(start 37.043868 -359.694226)
		(end 37.043868 -363.730286)
		(width 0.1524)
		(layer "B.Cu")
		(net "I2C_PSU3_SDA")
	)
	(segment
		(start 34.231326 -365.460026)
		(end 34.231326 -371.258846)
		(width 0.1524)
		(layer "B.Cu")
		(net "I2C_PSU3_SDA")
	)
	(segment
		(start 35.079432 -364.61192)
		(end 34.231326 -365.460026)
		(width 0.1524)
		(layer "B.Cu")
		(net "I2C_PSU3_SDA")
	)
	(segment
		(start 26.491692 -351.849944)
		(end 26.491692 -338.934806)
		(width 0.1524)
		(layer "B.Cu")
		(net "I2C_PSU3_SDA")
	)
	(segment
		(start 32.831786 -358.190038)
		(end 26.491692 -351.849944)
		(width 0.1524)
		(layer "B.Cu")
		(net "I2C_PSU3_SDA")
	)
	(segment
		(start 27.37231 -438.422542)
		(end 35.53968 -446.589912)
		(width 0.1524)
		(layer "B.Cu")
		(net "I2C_PSU3_SDA")
	)
	(segment
		(start 34.231326 -371.258846)
		(end 30.989016 -374.501156)
		(width 0.1524)
		(layer "B.Cu")
		(net "I2C_PSU3_SDA")
	)
	(segment
		(start 35.53968 -358.190038)
		(end 37.043868 -359.694226)
		(width 0.1524)
		(layer "B.Cu")
		(net "I2C_PSU3_SDA")
	)
	(segment
		(start 30.989016 -374.501156)
		(end 29.064966 -374.501156)
		(width 0.1524)
		(layer "B.Cu")
		(net "I2C_PSU3_SDA")
	)
	(segment
		(start 26.491692 -338.934806)
		(end 25.582626 -338.02574)
		(width 0.1524)
		(layer "B.Cu")
		(net "I2C_PSU3_SDA")
	)
	(segment
		(start 36.162234 -364.61192)
		(end 35.079432 -364.61192)
		(width 0.1524)
		(layer "B.Cu")
		(net "I2C_PSU3_SDA")
	)
	(segment
		(start 35.53968 -358.190038)
		(end 32.831786 -358.190038)
		(width 0.1524)
		(layer "B.Cu")
		(net "I2C_PSU3_SDA")
	)
	(segment
		(start 37.043868 -363.730286)
		(end 36.162234 -364.61192)
		(width 0.1524)
		(layer "B.Cu")
		(net "I2C_PSU3_SDA")
	)
	(via
		(at 87.478108 -485.425242)
		(size 0.508)
		(drill 0.254)
		(layers "F.Cu" "B.Cu")
		(net "T12_BLAD1_TXD")
	)
	(segment
		(start 25.282398 -379.89383)
		(end 16.50746 -371.118892)
		(width 0.127)
		(layer "In2.Cu")
		(net "T12_BLAD1_TXD")
	)
	(segment
		(start 16.50746 -324.08876)
		(end 8.83285 -316.413896)
		(width 0.127)
		(layer "In2.Cu")
		(net "T12_BLAD1_TXD")
	)
	(segment
		(start 30.717744 -443.280546)
		(end 25.282398 -437.8452)
		(width 0.127)
		(layer "In2.Cu")
		(net "T12_BLAD1_TXD")
	)
	(segment
		(start 39.565326 -446.390014)
		(end 36.455858 -443.280546)
		(width 0.127)
		(layer "In2.Cu")
		(net "T12_BLAD1_TXD")
	)
	(segment
		(start 16.50746 -371.118892)
		(end 16.50746 -324.08876)
		(width 0.127)
		(layer "In2.Cu")
		(net "T12_BLAD1_TXD")
	)
	(segment
		(start 85.483954 -466.984334)
		(end 73.329038 -454.829418)
		(width 0.127)
		(layer "In2.Cu")
		(net "T12_BLAD1_TXD")
	)
	(segment
		(start 41.31691 -454.829418)
		(end 39.565326 -453.077834)
		(width 0.127)
		(layer "In2.Cu")
		(net "T12_BLAD1_TXD")
	)
	(segment
		(start 92.947998 -497.004594)
		(end 91.089734 -498.862858)
		(width 0.127)
		(layer "In2.Cu")
		(net "T12_BLAD1_TXD")
	)
	(segment
		(start 4.771898 -315.491876)
		(end 3.949954 -314.669932)
		(width 0.127)
		(layer "In2.Cu")
		(net "T12_BLAD1_TXD")
	)
	(segment
		(start 92.695014 -490.642148)
		(end 92.695014 -493.006126)
		(width 0.127)
		(layer "In2.Cu")
		(net "T12_BLAD1_TXD")
	)
	(segment
		(start 7.22122 -315.491876)
		(end 4.771898 -315.491876)
		(width 0.127)
		(layer "In2.Cu")
		(net "T12_BLAD1_TXD")
	)
	(segment
		(start 87.478108 -485.425242)
		(end 85.483954 -483.431088)
		(width 0.127)
		(layer "In2.Cu")
		(net "T12_BLAD1_TXD")
	)
	(segment
		(start 87.478108 -485.425242)
		(end 92.695014 -490.642148)
		(width 0.127)
		(layer "In2.Cu")
		(net "T12_BLAD1_TXD")
	)
	(segment
		(start 92.947998 -493.25911)
		(end 92.947998 -497.004594)
		(width 0.127)
		(layer "In2.Cu")
		(net "T12_BLAD1_TXD")
	)
	(segment
		(start 73.329038 -454.829418)
		(end 41.31691 -454.829418)
		(width 0.127)
		(layer "In2.Cu")
		(net "T12_BLAD1_TXD")
	)
	(segment
		(start 39.565326 -453.077834)
		(end 39.565326 -446.390014)
		(width 0.127)
		(layer "In2.Cu")
		(net "T12_BLAD1_TXD")
	)
	(segment
		(start 36.455858 -443.280546)
		(end 30.717744 -443.280546)
		(width 0.127)
		(layer "In2.Cu")
		(net "T12_BLAD1_TXD")
	)
	(segment
		(start 92.695014 -493.006126)
		(end 92.947998 -493.25911)
		(width 0.127)
		(layer "In2.Cu")
		(net "T12_BLAD1_TXD")
	)
	(segment
		(start 85.483954 -483.431088)
		(end 85.483954 -466.984334)
		(width 0.127)
		(layer "In2.Cu")
		(net "T12_BLAD1_TXD")
	)
	(segment
		(start 8.14324 -316.413896)
		(end 7.22122 -315.491876)
		(width 0.127)
		(layer "In2.Cu")
		(net "T12_BLAD1_TXD")
	)
	(segment
		(start 86.737698 -498.862858)
		(end 85.63991 -497.76507)
		(width 0.127)
		(layer "In2.Cu")
		(net "T12_BLAD1_TXD")
	)
	(segment
		(start 91.089734 -498.862858)
		(end 86.737698 -498.862858)
		(width 0.127)
		(layer "In2.Cu")
		(net "T12_BLAD1_TXD")
	)
	(segment
		(start 8.83285 -316.413896)
		(end 8.14324 -316.413896)
		(width 0.127)
		(layer "In2.Cu")
		(net "T12_BLAD1_TXD")
	)
	(segment
		(start 25.282398 -437.8452)
		(end 25.282398 -379.89383)
		(width 0.127)
		(layer "In2.Cu")
		(net "T12_BLAD1_TXD")
	)
	(via
		(at 77.791818 -61.21654)
		(size 0.508)
		(drill 0.254)
		(layers "F.Cu" "B.Cu")
		(net "T2_BLAD1_TXD")
	)
	(segment
		(start 6.847332 -228.39807)
		(end 7.739888 -227.505514)
		(width 0.127)
		(layer "In2.Cu")
		(net "T2_BLAD1_TXD")
	)
	(segment
		(start 29.584142 -88.992964)
		(end 53.073808 -88.992964)
		(width 0.127)
		(layer "In2.Cu")
		(net "T2_BLAD1_TXD")
	)
	(segment
		(start 26.32202 -109.55655)
		(end 27.01036 -108.86821)
		(width 0.127)
		(layer "In2.Cu")
		(net "T2_BLAD1_TXD")
	)
	(segment
		(start 25.407366 -93.16974)
		(end 29.584142 -88.992964)
		(width 0.127)
		(layer "In2.Cu")
		(net "T2_BLAD1_TXD")
	)
	(segment
		(start 11.234166 -225.911156)
		(end 11.234166 -204.546454)
		(width 0.127)
		(layer "In2.Cu")
		(net "T2_BLAD1_TXD")
	)
	(segment
		(start 17.88668 -197.89394)
		(end 17.88668 -179.262278)
		(width 0.127)
		(layer "In2.Cu")
		(net "T2_BLAD1_TXD")
	)
	(segment
		(start 77.45095 -61.557408)
		(end 77.791818 -61.21654)
		(width 0.127)
		(layer "In2.Cu")
		(net "T2_BLAD1_TXD")
	)
	(segment
		(start 25.407366 -101.394768)
		(end 25.407366 -93.16974)
		(width 0.127)
		(layer "In2.Cu")
		(net "T2_BLAD1_TXD")
	)
	(segment
		(start 85.63991 -53.26507)
		(end 85.63991 -55.201566)
		(width 0.127)
		(layer "In2.Cu")
		(net "T2_BLAD1_TXD")
	)
	(segment
		(start 25.826974 -103.677466)
		(end 25.826974 -101.814376)
		(width 0.127)
		(layer "In2.Cu")
		(net "T2_BLAD1_TXD")
	)
	(segment
		(start 82.92846 -57.913016)
		(end 81.095342 -57.913016)
		(width 0.127)
		(layer "In2.Cu")
		(net "T2_BLAD1_TXD")
	)
	(segment
		(start 85.63991 -55.201566)
		(end 82.92846 -57.913016)
		(width 0.127)
		(layer "In2.Cu")
		(net "T2_BLAD1_TXD")
	)
	(segment
		(start 27.01036 -107.668568)
		(end 26.515568 -107.173776)
		(width 0.127)
		(layer "In2.Cu")
		(net "T2_BLAD1_TXD")
	)
	(segment
		(start 27.01036 -108.86821)
		(end 27.01036 -107.668568)
		(width 0.127)
		(layer "In2.Cu")
		(net "T2_BLAD1_TXD")
	)
	(segment
		(start 11.234166 -204.546454)
		(end 17.88668 -197.89394)
		(width 0.127)
		(layer "In2.Cu")
		(net "T2_BLAD1_TXD")
	)
	(segment
		(start 77.45095 -64.615822)
		(end 77.45095 -61.557408)
		(width 0.127)
		(layer "In2.Cu")
		(net "T2_BLAD1_TXD")
	)
	(segment
		(start 4.676394 -228.39807)
		(end 6.847332 -228.39807)
		(width 0.127)
		(layer "In2.Cu")
		(net "T2_BLAD1_TXD")
	)
	(segment
		(start 26.515568 -107.173776)
		(end 26.515568 -104.36606)
		(width 0.127)
		(layer "In2.Cu")
		(net "T2_BLAD1_TXD")
	)
	(segment
		(start 9.639808 -227.505514)
		(end 11.234166 -225.911156)
		(width 0.127)
		(layer "In2.Cu")
		(net "T2_BLAD1_TXD")
	)
	(segment
		(start 26.32202 -170.826938)
		(end 26.32202 -109.55655)
		(width 0.127)
		(layer "In2.Cu")
		(net "T2_BLAD1_TXD")
	)
	(segment
		(start 25.826974 -101.814376)
		(end 25.407366 -101.394768)
		(width 0.127)
		(layer "In2.Cu")
		(net "T2_BLAD1_TXD")
	)
	(segment
		(start 81.095342 -57.913016)
		(end 77.791818 -61.21654)
		(width 0.127)
		(layer "In2.Cu")
		(net "T2_BLAD1_TXD")
	)
	(segment
		(start 3.948938 -227.670614)
		(end 4.676394 -228.39807)
		(width 0.127)
		(layer "In2.Cu")
		(net "T2_BLAD1_TXD")
	)
	(segment
		(start 53.073808 -88.992964)
		(end 77.45095 -64.615822)
		(width 0.127)
		(layer "In2.Cu")
		(net "T2_BLAD1_TXD")
	)
	(segment
		(start 17.88668 -179.262278)
		(end 26.32202 -170.826938)
		(width 0.127)
		(layer "In2.Cu")
		(net "T2_BLAD1_TXD")
	)
	(segment
		(start 7.739888 -227.505514)
		(end 9.639808 -227.505514)
		(width 0.127)
		(layer "In2.Cu")
		(net "T2_BLAD1_TXD")
	)
	(segment
		(start 26.515568 -104.36606)
		(end 25.826974 -103.677466)
		(width 0.127)
		(layer "In2.Cu")
		(net "T2_BLAD1_TXD")
	)
	(segment
		(start 28.17876 -373.43207)
		(end 27.56916 -373.43207)
		(width 0.508)
		(layer "F.Cu")
		(net "PSU5_REMOTE_N")
	)
	(segment
		(start 28.180792 -373.430038)
		(end 28.17876 -373.43207)
		(width 0.508)
		(layer "F.Cu")
		(net "PSU5_REMOTE_N")
	)
	(segment
		(start 30.45968 -373.430038)
		(end 28.180792 -373.430038)
		(width 0.508)
		(layer "F.Cu")
		(net "PSU5_REMOTE_N")
	)
	(via
		(at 93.915992 -488.13593)
		(size 0.508)
		(drill 0.254)
		(layers "F.Cu" "B.Cu")
		(net "T12_BLAD3_TXD")
	)
	(segment
		(start 21.293582 -350.985074)
		(end 21.293582 -372.118382)
		(width 0.127)
		(layer "In5.Cu")
		(net "T12_BLAD3_TXD")
	)
	(segment
		(start 93.915992 -488.13593)
		(end 86.826852 -495.22507)
		(width 0.127)
		(layer "In5.Cu")
		(net "T12_BLAD3_TXD")
	)
	(segment
		(start 86.826852 -495.22507)
		(end 85.63991 -495.22507)
		(width 0.127)
		(layer "In5.Cu")
		(net "T12_BLAD3_TXD")
	)
	(segment
		(start 28.567634 -379.392434)
		(end 28.567634 -437.781446)
		(width 0.127)
		(layer "In5.Cu")
		(net "T12_BLAD3_TXD")
	)
	(segment
		(start 5.925058 -311.441846)
		(end 6.836156 -311.441846)
		(width 0.127)
		(layer "In5.Cu")
		(net "T12_BLAD3_TXD")
	)
	(segment
		(start 75.056238 -442.962284)
		(end 76.123546 -441.894976)
		(width 0.127)
		(layer "In5.Cu")
		(net "T12_BLAD3_TXD")
	)
	(segment
		(start 88.679782 -441.894976)
		(end 98.076004 -451.291198)
		(width 0.127)
		(layer "In5.Cu")
		(net "T12_BLAD3_TXD")
	)
	(segment
		(start 6.836156 -311.441846)
		(end 7.88162 -310.396382)
		(width 0.127)
		(layer "In5.Cu")
		(net "T12_BLAD3_TXD")
	)
	(segment
		(start 4.32943 -309.846218)
		(end 5.925058 -311.441846)
		(width 0.127)
		(layer "In5.Cu")
		(net "T12_BLAD3_TXD")
	)
	(segment
		(start 20.897596 -350.589088)
		(end 21.293582 -350.985074)
		(width 0.127)
		(layer "In5.Cu")
		(net "T12_BLAD3_TXD")
	)
	(segment
		(start 98.076004 -451.291198)
		(end 98.076004 -483.975918)
		(width 0.127)
		(layer "In5.Cu")
		(net "T12_BLAD3_TXD")
	)
	(segment
		(start 2.126234 -309.846218)
		(end 4.32943 -309.846218)
		(width 0.127)
		(layer "In5.Cu")
		(net "T12_BLAD3_TXD")
	)
	(segment
		(start 98.076004 -483.975918)
		(end 93.915992 -488.13593)
		(width 0.127)
		(layer "In5.Cu")
		(net "T12_BLAD3_TXD")
	)
	(segment
		(start 1.949958 -309.669942)
		(end 2.126234 -309.846218)
		(width 0.127)
		(layer "In5.Cu")
		(net "T12_BLAD3_TXD")
	)
	(segment
		(start 21.293582 -372.118382)
		(end 28.567634 -379.392434)
		(width 0.127)
		(layer "In5.Cu")
		(net "T12_BLAD3_TXD")
	)
	(segment
		(start 20.897596 -318.046862)
		(end 20.897596 -350.589088)
		(width 0.127)
		(layer "In5.Cu")
		(net "T12_BLAD3_TXD")
	)
	(segment
		(start 28.567634 -437.781446)
		(end 33.748472 -442.962284)
		(width 0.127)
		(layer "In5.Cu")
		(net "T12_BLAD3_TXD")
	)
	(segment
		(start 33.748472 -442.962284)
		(end 75.056238 -442.962284)
		(width 0.127)
		(layer "In5.Cu")
		(net "T12_BLAD3_TXD")
	)
	(segment
		(start 76.123546 -441.894976)
		(end 88.679782 -441.894976)
		(width 0.127)
		(layer "In5.Cu")
		(net "T12_BLAD3_TXD")
	)
	(segment
		(start 7.88162 -310.396382)
		(end 13.247116 -310.396382)
		(width 0.127)
		(layer "In5.Cu")
		(net "T12_BLAD3_TXD")
	)
	(segment
		(start 13.247116 -310.396382)
		(end 20.897596 -318.046862)
		(width 0.127)
		(layer "In5.Cu")
		(net "T12_BLAD3_TXD")
	)
	(via
		(at 79.99476 -64.029082)
		(size 0.508)
		(drill 0.254)
		(layers "F.Cu" "B.Cu")
		(net "T2_BLAD1_EN")
	)
	(segment
		(start 18.894298 -179.738782)
		(end 18.894298 -197.690232)
		(width 0.127)
		(layer "In2.Cu")
		(net "T2_BLAD1_EN")
	)
	(segment
		(start 28.122626 -109.444536)
		(end 27.355546 -110.211616)
		(width 0.127)
		(layer "In2.Cu")
		(net "T2_BLAD1_EN")
	)
	(segment
		(start 22.710648 -219.1893)
		(end 11.962638 -229.93731)
		(width 0.127)
		(layer "In2.Cu")
		(net "T2_BLAD1_EN")
	)
	(segment
		(start 3.693414 -230.833168)
		(end 3.232912 -231.29367)
		(width 0.127)
		(layer "In2.Cu")
		(net "T2_BLAD1_EN")
	)
	(segment
		(start 26.50871 -93.67774)
		(end 26.50871 -100.613718)
		(width 0.127)
		(layer "In2.Cu")
		(net "T2_BLAD1_EN")
	)
	(segment
		(start 27.355546 -171.277534)
		(end 18.894298 -179.738782)
		(width 0.127)
		(layer "In2.Cu")
		(net "T2_BLAD1_EN")
	)
	(segment
		(start 3.232912 -232.954576)
		(end 3.948938 -233.670602)
		(width 0.127)
		(layer "In2.Cu")
		(net "T2_BLAD1_EN")
	)
	(segment
		(start 79.99476 -64.029336)
		(end 53.981858 -90.042238)
		(width 0.127)
		(layer "In2.Cu")
		(net "T2_BLAD1_EN")
	)
	(segment
		(start 7.023608 -230.833168)
		(end 3.693414 -230.833168)
		(width 0.127)
		(layer "In2.Cu")
		(net "T2_BLAD1_EN")
	)
	(segment
		(start 53.981858 -90.042238)
		(end 30.144212 -90.042238)
		(width 0.127)
		(layer "In2.Cu")
		(net "T2_BLAD1_EN")
	)
	(segment
		(start 11.962638 -229.93731)
		(end 7.919466 -229.93731)
		(width 0.127)
		(layer "In2.Cu")
		(net "T2_BLAD1_EN")
	)
	(segment
		(start 7.919466 -229.93731)
		(end 7.023608 -230.833168)
		(width 0.127)
		(layer "In2.Cu")
		(net "T2_BLAD1_EN")
	)
	(segment
		(start 79.99476 -64.029082)
		(end 79.99476 -64.029336)
		(width 0.127)
		(layer "In2.Cu")
		(net "T2_BLAD1_EN")
	)
	(segment
		(start 30.144212 -90.042238)
		(end 26.50871 -93.67774)
		(width 0.127)
		(layer "In2.Cu")
		(net "T2_BLAD1_EN")
	)
	(segment
		(start 88.17991 -54.107588)
		(end 88.17991 -53.26507)
		(width 0.127)
		(layer "In2.Cu")
		(net "T2_BLAD1_EN")
	)
	(segment
		(start 28.122626 -107.379516)
		(end 28.122626 -109.444536)
		(width 0.127)
		(layer "In2.Cu")
		(net "T2_BLAD1_EN")
	)
	(segment
		(start 87.477346 -54.810152)
		(end 88.17991 -54.107588)
		(width 0.127)
		(layer "In2.Cu")
		(net "T2_BLAD1_EN")
	)
	(segment
		(start 27.585416 -106.842306)
		(end 28.122626 -107.379516)
		(width 0.127)
		(layer "In2.Cu")
		(net "T2_BLAD1_EN")
	)
	(segment
		(start 22.710648 -201.506582)
		(end 22.710648 -219.1893)
		(width 0.127)
		(layer "In2.Cu")
		(net "T2_BLAD1_EN")
	)
	(segment
		(start 18.894298 -197.690232)
		(end 22.710648 -201.506582)
		(width 0.127)
		(layer "In2.Cu")
		(net "T2_BLAD1_EN")
	)
	(segment
		(start 27.585416 -101.690424)
		(end 27.585416 -106.842306)
		(width 0.127)
		(layer "In2.Cu")
		(net "T2_BLAD1_EN")
	)
	(segment
		(start 87.477346 -56.54675)
		(end 87.477346 -54.810152)
		(width 0.127)
		(layer "In2.Cu")
		(net "T2_BLAD1_EN")
	)
	(segment
		(start 3.232912 -231.29367)
		(end 3.232912 -232.954576)
		(width 0.127)
		(layer "In2.Cu")
		(net "T2_BLAD1_EN")
	)
	(segment
		(start 26.50871 -100.613718)
		(end 27.585416 -101.690424)
		(width 0.127)
		(layer "In2.Cu")
		(net "T2_BLAD1_EN")
	)
	(segment
		(start 79.99476 -64.029336)
		(end 87.477346 -56.54675)
		(width 0.127)
		(layer "In2.Cu")
		(net "T2_BLAD1_EN")
	)
	(segment
		(start 27.355546 -110.211616)
		(end 27.355546 -171.277534)
		(width 0.127)
		(layer "In2.Cu")
		(net "T2_BLAD1_EN")
	)
	(via
		(at 96.368362 -486.984294)
		(size 0.508)
		(drill 0.254)
		(layers "F.Cu" "B.Cu")
		(net "T12_BLAD4_RXD")
	)
	(segment
		(start 4.986274 -307.633624)
		(end 3.949954 -308.669944)
		(width 0.127)
		(layer "In5.Cu")
		(net "T12_BLAD4_RXD")
	)
	(segment
		(start 75.69581 -441.039504)
		(end 74.52614 -442.209174)
		(width 0.127)
		(layer "In5.Cu")
		(net "T12_BLAD4_RXD")
	)
	(segment
		(start 91.98991 -491.362746)
		(end 91.98991 -493.95507)
		(width 0.127)
		(layer "In5.Cu")
		(net "T12_BLAD4_RXD")
	)
	(segment
		(start 21.557996 -316.461902)
		(end 13.512546 -308.416452)
		(width 0.127)
		(layer "In5.Cu")
		(net "T12_BLAD4_RXD")
	)
	(segment
		(start 21.557996 -350.315276)
		(end 21.557996 -316.461902)
		(width 0.127)
		(layer "In5.Cu")
		(net "T12_BLAD4_RXD")
	)
	(segment
		(start 98.782632 -450.840348)
		(end 88.981788 -441.039504)
		(width 0.127)
		(layer "In5.Cu")
		(net "T12_BLAD4_RXD")
	)
	(segment
		(start 88.981788 -441.039504)
		(end 75.69581 -441.039504)
		(width 0.127)
		(layer "In5.Cu")
		(net "T12_BLAD4_RXD")
	)
	(segment
		(start 13.512546 -308.416452)
		(end 8.05688 -308.416452)
		(width 0.127)
		(layer "In5.Cu")
		(net "T12_BLAD4_RXD")
	)
	(segment
		(start 98.782632 -484.570024)
		(end 98.782632 -450.840348)
		(width 0.127)
		(layer "In5.Cu")
		(net "T12_BLAD4_RXD")
	)
	(segment
		(start 74.52614 -442.209174)
		(end 34.157412 -442.209174)
		(width 0.127)
		(layer "In5.Cu")
		(net "T12_BLAD4_RXD")
	)
	(segment
		(start 96.368362 -486.984294)
		(end 91.98991 -491.362746)
		(width 0.127)
		(layer "In5.Cu")
		(net "T12_BLAD4_RXD")
	)
	(segment
		(start 29.278326 -377.794012)
		(end 21.953982 -370.469668)
		(width 0.127)
		(layer "In5.Cu")
		(net "T12_BLAD4_RXD")
	)
	(segment
		(start 29.278326 -437.330088)
		(end 29.278326 -377.794012)
		(width 0.127)
		(layer "In5.Cu")
		(net "T12_BLAD4_RXD")
	)
	(segment
		(start 21.953982 -370.469668)
		(end 21.953982 -350.711262)
		(width 0.127)
		(layer "In5.Cu")
		(net "T12_BLAD4_RXD")
	)
	(segment
		(start 8.05688 -308.416452)
		(end 7.274052 -307.633624)
		(width 0.127)
		(layer "In5.Cu")
		(net "T12_BLAD4_RXD")
	)
	(segment
		(start 21.953982 -350.711262)
		(end 21.557996 -350.315276)
		(width 0.127)
		(layer "In5.Cu")
		(net "T12_BLAD4_RXD")
	)
	(segment
		(start 7.274052 -307.633624)
		(end 4.986274 -307.633624)
		(width 0.127)
		(layer "In5.Cu")
		(net "T12_BLAD4_RXD")
	)
	(segment
		(start 34.157412 -442.209174)
		(end 29.278326 -437.330088)
		(width 0.127)
		(layer "In5.Cu")
		(net "T12_BLAD4_RXD")
	)
	(segment
		(start 96.368362 -486.984294)
		(end 98.782632 -484.570024)
		(width 0.127)
		(layer "In5.Cu")
		(net "T12_BLAD4_RXD")
	)
	(via
		(at 80.794352 -58.88228)
		(size 0.508)
		(drill 0.254)
		(layers "F.Cu" "B.Cu")
		(net "T2_BLAD4_RXD")
	)
	(segment
		(start 91.942666 -49.45507)
		(end 91.007946 -48.52035)
		(width 0.127)
		(layer "In5.Cu")
		(net "T2_BLAD4_RXD")
	)
	(segment
		(start 25.088342 -167.32123)
		(end 15.39113 -177.018442)
		(width 0.127)
		(layer "In5.Cu")
		(net "T2_BLAD4_RXD")
	)
	(segment
		(start 19.376136 -93.016832)
		(end 19.376136 -110.595156)
		(width 0.127)
		(layer "In5.Cu")
		(net "T2_BLAD4_RXD")
	)
	(segment
		(start 84.194904 -55.481728)
		(end 80.794352 -58.88228)
		(width 0.127)
		(layer "In5.Cu")
		(net "T2_BLAD4_RXD")
	)
	(segment
		(start 7.992618 -219.779596)
		(end 6.901942 -220.870272)
		(width 0.127)
		(layer "In5.Cu")
		(net "T2_BLAD4_RXD")
	)
	(segment
		(start 15.39113 -197.539102)
		(end 9.799066 -203.131166)
		(width 0.127)
		(layer "In5.Cu")
		(net "T2_BLAD4_RXD")
	)
	(segment
		(start 51.335432 -87.469472)
		(end 24.923496 -87.469472)
		(width 0.127)
		(layer "In5.Cu")
		(net "T2_BLAD4_RXD")
	)
	(segment
		(start 4.749292 -220.870272)
		(end 3.948938 -221.670626)
		(width 0.127)
		(layer "In5.Cu")
		(net "T2_BLAD4_RXD")
	)
	(segment
		(start 84.194904 -50.55489)
		(end 84.194904 -55.481728)
		(width 0.127)
		(layer "In5.Cu")
		(net "T2_BLAD4_RXD")
	)
	(segment
		(start 24.923496 -87.469472)
		(end 19.376136 -93.016832)
		(width 0.127)
		(layer "In5.Cu")
		(net "T2_BLAD4_RXD")
	)
	(segment
		(start 86.229444 -48.52035)
		(end 84.194904 -50.55489)
		(width 0.127)
		(layer "In5.Cu")
		(net "T2_BLAD4_RXD")
	)
	(segment
		(start 9.799066 -219.00134)
		(end 9.02081 -219.779596)
		(width 0.127)
		(layer "In5.Cu")
		(net "T2_BLAD4_RXD")
	)
	(segment
		(start 76.914756 -61.890148)
		(end 51.335432 -87.469472)
		(width 0.127)
		(layer "In5.Cu")
		(net "T2_BLAD4_RXD")
	)
	(segment
		(start 19.376136 -110.595156)
		(end 25.088342 -116.307362)
		(width 0.127)
		(layer "In5.Cu")
		(net "T2_BLAD4_RXD")
	)
	(segment
		(start 9.799066 -203.131166)
		(end 9.799066 -219.00134)
		(width 0.127)
		(layer "In5.Cu")
		(net "T2_BLAD4_RXD")
	)
	(segment
		(start 91.007946 -48.52035)
		(end 86.229444 -48.52035)
		(width 0.127)
		(layer "In5.Cu")
		(net "T2_BLAD4_RXD")
	)
	(segment
		(start 15.39113 -177.018442)
		(end 15.39113 -197.539102)
		(width 0.127)
		(layer "In5.Cu")
		(net "T2_BLAD4_RXD")
	)
	(segment
		(start 91.98991 -49.45507)
		(end 91.942666 -49.45507)
		(width 0.127)
		(layer "In5.Cu")
		(net "T2_BLAD4_RXD")
	)
	(segment
		(start 80.794352 -58.88228)
		(end 77.786484 -61.890148)
		(width 0.127)
		(layer "In5.Cu")
		(net "T2_BLAD4_RXD")
	)
	(segment
		(start 9.02081 -219.779596)
		(end 7.992618 -219.779596)
		(width 0.127)
		(layer "In5.Cu")
		(net "T2_BLAD4_RXD")
	)
	(segment
		(start 25.088342 -116.307362)
		(end 25.088342 -167.32123)
		(width 0.127)
		(layer "In5.Cu")
		(net "T2_BLAD4_RXD")
	)
	(segment
		(start 77.786484 -61.890148)
		(end 76.914756 -61.890148)
		(width 0.127)
		(layer "In5.Cu")
		(net "T2_BLAD4_RXD")
	)
	(segment
		(start 6.901942 -220.870272)
		(end 4.749292 -220.870272)
		(width 0.127)
		(layer "In5.Cu")
		(net "T2_BLAD4_RXD")
	)
	(via
		(at 85.930486 -489.616242)
		(size 0.508)
		(drill 0.254)
		(layers "F.Cu" "B.Cu")
		(net "T12_BLAD2_EN")
	)
	(segment
		(start 2.772918 -319.669922)
		(end 2.883662 -319.780666)
		(width 0.127)
		(layer "In2.Cu")
		(net "T12_BLAD2_EN")
	)
	(segment
		(start 30.527244 -445.08801)
		(end 35.923982 -445.08801)
		(width 0.127)
		(layer "In2.Cu")
		(net "T12_BLAD2_EN")
	)
	(segment
		(start 13.183362 -333.828898)
		(end 13.183362 -369.879118)
		(width 0.127)
		(layer "In2.Cu")
		(net "T12_BLAD2_EN")
	)
	(segment
		(start 11.230102 -323.059298)
		(end 11.230102 -331.875638)
		(width 0.127)
		(layer "In2.Cu")
		(net "T12_BLAD2_EN")
	)
	(segment
		(start 2.883662 -319.780666)
		(end 7.0104 -319.780666)
		(width 0.127)
		(layer "In2.Cu")
		(net "T12_BLAD2_EN")
	)
	(segment
		(start 83.883246 -485.658414)
		(end 85.930486 -487.705654)
		(width 0.127)
		(layer "In2.Cu")
		(net "T12_BLAD2_EN")
	)
	(segment
		(start 89.44991 -496.49507)
		(end 88.70188 -496.49507)
		(width 0.127)
		(layer "In2.Cu")
		(net "T12_BLAD2_EN")
	)
	(segment
		(start 1.949958 -319.669922)
		(end 2.772918 -319.669922)
		(width 0.127)
		(layer "In2.Cu")
		(net "T12_BLAD2_EN")
	)
	(segment
		(start 85.930486 -494.248186)
		(end 85.930486 -489.616242)
		(width 0.127)
		(layer "In2.Cu")
		(net "T12_BLAD2_EN")
	)
	(segment
		(start 7.0104 -319.780666)
		(end 8.002016 -320.772282)
		(width 0.127)
		(layer "In2.Cu")
		(net "T12_BLAD2_EN")
	)
	(segment
		(start 38.034722 -447.19875)
		(end 38.034722 -453.712326)
		(width 0.127)
		(layer "In2.Cu")
		(net "T12_BLAD2_EN")
	)
	(segment
		(start 23.842218 -380.537974)
		(end 23.842218 -438.402984)
		(width 0.127)
		(layer "In2.Cu")
		(net "T12_BLAD2_EN")
	)
	(segment
		(start 35.923982 -445.08801)
		(end 38.034722 -447.19875)
		(width 0.127)
		(layer "In2.Cu")
		(net "T12_BLAD2_EN")
	)
	(segment
		(start 83.883246 -467.548722)
		(end 83.883246 -485.658414)
		(width 0.127)
		(layer "In2.Cu")
		(net "T12_BLAD2_EN")
	)
	(segment
		(start 88.328246 -496.121436)
		(end 87.803736 -496.121436)
		(width 0.127)
		(layer "In2.Cu")
		(net "T12_BLAD2_EN")
	)
	(segment
		(start 87.803736 -496.121436)
		(end 85.930486 -494.248186)
		(width 0.127)
		(layer "In2.Cu")
		(net "T12_BLAD2_EN")
	)
	(segment
		(start 40.682418 -456.360022)
		(end 72.694546 -456.360022)
		(width 0.127)
		(layer "In2.Cu")
		(net "T12_BLAD2_EN")
	)
	(segment
		(start 72.694546 -456.360022)
		(end 83.883246 -467.548722)
		(width 0.127)
		(layer "In2.Cu")
		(net "T12_BLAD2_EN")
	)
	(segment
		(start 13.183362 -369.879118)
		(end 23.842218 -380.537974)
		(width 0.127)
		(layer "In2.Cu")
		(net "T12_BLAD2_EN")
	)
	(segment
		(start 8.002016 -320.772282)
		(end 8.943086 -320.772282)
		(width 0.127)
		(layer "In2.Cu")
		(net "T12_BLAD2_EN")
	)
	(segment
		(start 8.943086 -320.772282)
		(end 11.230102 -323.059298)
		(width 0.127)
		(layer "In2.Cu")
		(net "T12_BLAD2_EN")
	)
	(segment
		(start 38.034722 -453.712326)
		(end 40.682418 -456.360022)
		(width 0.127)
		(layer "In2.Cu")
		(net "T12_BLAD2_EN")
	)
	(segment
		(start 88.70188 -496.49507)
		(end 88.328246 -496.121436)
		(width 0.127)
		(layer "In2.Cu")
		(net "T12_BLAD2_EN")
	)
	(segment
		(start 23.842218 -438.402984)
		(end 30.527244 -445.08801)
		(width 0.127)
		(layer "In2.Cu")
		(net "T12_BLAD2_EN")
	)
	(segment
		(start 11.230102 -331.875638)
		(end 13.183362 -333.828898)
		(width 0.127)
		(layer "In2.Cu")
		(net "T12_BLAD2_EN")
	)
	(segment
		(start 85.930486 -487.705654)
		(end 85.930486 -489.616242)
		(width 0.127)
		(layer "In2.Cu")
		(net "T12_BLAD2_EN")
	)
	(via
		(at 78.246478 -63.211202)
		(size 0.508)
		(drill 0.254)
		(layers "F.Cu" "B.Cu")
		(net "T2_BLAD1_RXD")
	)
	(segment
		(start 78.246478 -63.211202)
		(end 81.66354 -59.79414)
		(width 0.127)
		(layer "In2.Cu")
		(net "T2_BLAD1_RXD")
	)
	(segment
		(start 78.246478 -63.211202)
		(end 78.246478 -64.440308)
		(width 0.127)
		(layer "In2.Cu")
		(net "T2_BLAD1_RXD")
	)
	(segment
		(start 86.915244 -52.000404)
		(end 86.90991 -51.99507)
		(width 0.127)
		(layer "In2.Cu")
		(net "T2_BLAD1_RXD")
	)
	(segment
		(start 25.742392 -93.318584)
		(end 25.742392 -101.184202)
		(width 0.127)
		(layer "In2.Cu")
		(net "T2_BLAD1_RXD")
	)
	(segment
		(start 21.949664 -201.80808)
		(end 21.949664 -213.666578)
		(width 0.127)
		(layer "In2.Cu")
		(net "T2_BLAD1_RXD")
	)
	(segment
		(start 7.896098 -227.882196)
		(end 7.003542 -228.774752)
		(width 0.127)
		(layer "In2.Cu")
		(net "T2_BLAD1_RXD")
	)
	(segment
		(start 25.742392 -101.184202)
		(end 26.157174 -101.598984)
		(width 0.127)
		(layer "In2.Cu")
		(net "T2_BLAD1_RXD")
	)
	(segment
		(start 3.444494 -228.670612)
		(end 1.948942 -228.670612)
		(width 0.127)
		(layer "In2.Cu")
		(net "T2_BLAD1_RXD")
	)
	(segment
		(start 3.548634 -228.774752)
		(end 3.444494 -228.670612)
		(width 0.127)
		(layer "In2.Cu")
		(net "T2_BLAD1_RXD")
	)
	(segment
		(start 78.246478 -64.440308)
		(end 53.351684 -89.335102)
		(width 0.127)
		(layer "In2.Cu")
		(net "T2_BLAD1_RXD")
	)
	(segment
		(start 7.003542 -228.774752)
		(end 3.548634 -228.774752)
		(width 0.127)
		(layer "In2.Cu")
		(net "T2_BLAD1_RXD")
	)
	(segment
		(start 26.652728 -109.75086)
		(end 26.652728 -170.9801)
		(width 0.127)
		(layer "In2.Cu")
		(net "T2_BLAD1_RXD")
	)
	(segment
		(start 18.222468 -179.41036)
		(end 18.222468 -198.080884)
		(width 0.127)
		(layer "In2.Cu")
		(net "T2_BLAD1_RXD")
	)
	(segment
		(start 26.157174 -103.540306)
		(end 26.925016 -104.308148)
		(width 0.127)
		(layer "In2.Cu")
		(net "T2_BLAD1_RXD")
	)
	(segment
		(start 26.652728 -170.9801)
		(end 18.222468 -179.41036)
		(width 0.127)
		(layer "In2.Cu")
		(net "T2_BLAD1_RXD")
	)
	(segment
		(start 29.725874 -89.335102)
		(end 25.742392 -93.318584)
		(width 0.127)
		(layer "In2.Cu")
		(net "T2_BLAD1_RXD")
	)
	(segment
		(start 18.222468 -198.080884)
		(end 21.949664 -201.80808)
		(width 0.127)
		(layer "In2.Cu")
		(net "T2_BLAD1_RXD")
	)
	(segment
		(start 86.608412 -54.057296)
		(end 86.608412 -52.307236)
		(width 0.127)
		(layer "In2.Cu")
		(net "T2_BLAD1_RXD")
	)
	(segment
		(start 81.66354 -58.821066)
		(end 82.191352 -58.293254)
		(width 0.127)
		(layer "In2.Cu")
		(net "T2_BLAD1_RXD")
	)
	(segment
		(start 82.191352 -58.293254)
		(end 83.417156 -58.293254)
		(width 0.127)
		(layer "In2.Cu")
		(net "T2_BLAD1_RXD")
	)
	(segment
		(start 26.925016 -107.116118)
		(end 27.34056 -107.531662)
		(width 0.127)
		(layer "In2.Cu")
		(net "T2_BLAD1_RXD")
	)
	(segment
		(start 86.608412 -52.307236)
		(end 86.915244 -52.000404)
		(width 0.127)
		(layer "In2.Cu")
		(net "T2_BLAD1_RXD")
	)
	(segment
		(start 81.66354 -59.79414)
		(end 81.66354 -58.821066)
		(width 0.127)
		(layer "In2.Cu")
		(net "T2_BLAD1_RXD")
	)
	(segment
		(start 26.157174 -101.598984)
		(end 26.157174 -103.540306)
		(width 0.127)
		(layer "In2.Cu")
		(net "T2_BLAD1_RXD")
	)
	(segment
		(start 86.39302 -54.272688)
		(end 86.608412 -54.057296)
		(width 0.127)
		(layer "In2.Cu")
		(net "T2_BLAD1_RXD")
	)
	(segment
		(start 86.39302 -55.31739)
		(end 86.39302 -54.272688)
		(width 0.127)
		(layer "In2.Cu")
		(net "T2_BLAD1_RXD")
	)
	(segment
		(start 13.468604 -222.147638)
		(end 13.468604 -224.317052)
		(width 0.127)
		(layer "In2.Cu")
		(net "T2_BLAD1_RXD")
	)
	(segment
		(start 27.34056 -109.063028)
		(end 26.652728 -109.75086)
		(width 0.127)
		(layer "In2.Cu")
		(net "T2_BLAD1_RXD")
	)
	(segment
		(start 21.949664 -213.666578)
		(end 13.468604 -222.147638)
		(width 0.127)
		(layer "In2.Cu")
		(net "T2_BLAD1_RXD")
	)
	(segment
		(start 13.468604 -224.317052)
		(end 9.90346 -227.882196)
		(width 0.127)
		(layer "In2.Cu")
		(net "T2_BLAD1_RXD")
	)
	(segment
		(start 27.34056 -107.531662)
		(end 27.34056 -109.063028)
		(width 0.127)
		(layer "In2.Cu")
		(net "T2_BLAD1_RXD")
	)
	(segment
		(start 26.925016 -104.308148)
		(end 26.925016 -107.116118)
		(width 0.127)
		(layer "In2.Cu")
		(net "T2_BLAD1_RXD")
	)
	(segment
		(start 83.417156 -58.293254)
		(end 86.39302 -55.31739)
		(width 0.127)
		(layer "In2.Cu")
		(net "T2_BLAD1_RXD")
	)
	(segment
		(start 9.90346 -227.882196)
		(end 7.896098 -227.882196)
		(width 0.127)
		(layer "In2.Cu")
		(net "T2_BLAD1_RXD")
	)
	(segment
		(start 53.351684 -89.335102)
		(end 29.725874 -89.335102)
		(width 0.127)
		(layer "In2.Cu")
		(net "T2_BLAD1_RXD")
	)
	(via
		(at 87.766398 -486.805732)
		(size 0.508)
		(drill 0.254)
		(layers "F.Cu" "B.Cu")
		(net "T12_BLAD1_RXD")
	)
	(segment
		(start 89.939622 -494.763806)
		(end 89.939622 -495.616992)
		(width 0.127)
		(layer "In2.Cu")
		(net "T12_BLAD1_RXD")
	)
	(segment
		(start 89.754964 -497.48059)
		(end 89.124282 -497.48059)
		(width 0.127)
		(layer "In2.Cu")
		(net "T12_BLAD1_RXD")
	)
	(segment
		(start 88.138762 -496.49507)
		(end 86.90991 -496.49507)
		(width 0.127)
		(layer "In2.Cu")
		(net "T12_BLAD1_RXD")
	)
	(segment
		(start 39.130732 -446.512696)
		(end 36.447984 -443.829948)
		(width 0.127)
		(layer "In2.Cu")
		(net "T12_BLAD1_RXD")
	)
	(segment
		(start 73.148952 -455.264012)
		(end 41.136824 -455.264012)
		(width 0.127)
		(layer "In2.Cu")
		(net "T12_BLAD1_RXD")
	)
	(segment
		(start 24.917908 -380.027688)
		(end 15.18793 -370.29771)
		(width 0.127)
		(layer "In2.Cu")
		(net "T12_BLAD1_RXD")
	)
	(segment
		(start 90.278966 -489.3183)
		(end 90.278966 -494.424462)
		(width 0.127)
		(layer "In2.Cu")
		(net "T12_BLAD1_RXD")
	)
	(segment
		(start 85.064092 -484.103426)
		(end 85.064092 -467.179152)
		(width 0.127)
		(layer "In2.Cu")
		(net "T12_BLAD1_RXD")
	)
	(segment
		(start 85.064092 -467.179152)
		(end 73.148952 -455.264012)
		(width 0.127)
		(layer "In2.Cu")
		(net "T12_BLAD1_RXD")
	)
	(segment
		(start 4.49453 -315.938154)
		(end 4.226306 -315.66993)
		(width 0.127)
		(layer "In2.Cu")
		(net "T12_BLAD1_RXD")
	)
	(segment
		(start 89.124282 -497.48059)
		(end 88.138762 -496.49507)
		(width 0.127)
		(layer "In2.Cu")
		(net "T12_BLAD1_RXD")
	)
	(segment
		(start 89.939622 -495.616992)
		(end 90.41511 -496.09248)
		(width 0.127)
		(layer "In2.Cu")
		(net "T12_BLAD1_RXD")
	)
	(segment
		(start 87.766398 -486.805732)
		(end 85.064092 -484.103426)
		(width 0.127)
		(layer "In2.Cu")
		(net "T12_BLAD1_RXD")
	)
	(segment
		(start 15.18793 -370.29771)
		(end 15.18793 -327.982326)
		(width 0.127)
		(layer "In2.Cu")
		(net "T12_BLAD1_RXD")
	)
	(segment
		(start 90.41511 -496.820444)
		(end 89.754964 -497.48059)
		(width 0.127)
		(layer "In2.Cu")
		(net "T12_BLAD1_RXD")
	)
	(segment
		(start 30.6705 -443.829948)
		(end 24.917908 -438.077356)
		(width 0.127)
		(layer "In2.Cu")
		(net "T12_BLAD1_RXD")
	)
	(segment
		(start 90.41511 -496.09248)
		(end 90.41511 -496.820444)
		(width 0.127)
		(layer "In2.Cu")
		(net "T12_BLAD1_RXD")
	)
	(segment
		(start 12.757404 -320.92138)
		(end 8.589518 -316.753494)
		(width 0.127)
		(layer "In2.Cu")
		(net "T12_BLAD1_RXD")
	)
	(segment
		(start 15.18793 -327.982326)
		(end 12.757404 -325.5518)
		(width 0.127)
		(layer "In2.Cu")
		(net "T12_BLAD1_RXD")
	)
	(segment
		(start 7.046214 -315.938154)
		(end 4.49453 -315.938154)
		(width 0.127)
		(layer "In2.Cu")
		(net "T12_BLAD1_RXD")
	)
	(segment
		(start 4.226306 -315.66993)
		(end 1.949958 -315.66993)
		(width 0.127)
		(layer "In2.Cu")
		(net "T12_BLAD1_RXD")
	)
	(segment
		(start 87.766398 -486.805732)
		(end 90.278966 -489.3183)
		(width 0.127)
		(layer "In2.Cu")
		(net "T12_BLAD1_RXD")
	)
	(segment
		(start 7.861554 -316.753494)
		(end 7.046214 -315.938154)
		(width 0.127)
		(layer "In2.Cu")
		(net "T12_BLAD1_RXD")
	)
	(segment
		(start 24.917908 -438.077356)
		(end 24.917908 -380.027688)
		(width 0.127)
		(layer "In2.Cu")
		(net "T12_BLAD1_RXD")
	)
	(segment
		(start 39.130732 -453.25792)
		(end 39.130732 -446.512696)
		(width 0.127)
		(layer "In2.Cu")
		(net "T12_BLAD1_RXD")
	)
	(segment
		(start 41.136824 -455.264012)
		(end 39.130732 -453.25792)
		(width 0.127)
		(layer "In2.Cu")
		(net "T12_BLAD1_RXD")
	)
	(segment
		(start 90.278966 -494.424462)
		(end 89.939622 -494.763806)
		(width 0.127)
		(layer "In2.Cu")
		(net "T12_BLAD1_RXD")
	)
	(segment
		(start 8.589518 -316.753494)
		(end 7.861554 -316.753494)
		(width 0.127)
		(layer "In2.Cu")
		(net "T12_BLAD1_RXD")
	)
	(segment
		(start 36.447984 -443.829948)
		(end 30.6705 -443.829948)
		(width 0.127)
		(layer "In2.Cu")
		(net "T12_BLAD1_RXD")
	)
	(segment
		(start 12.757404 -325.5518)
		(end 12.757404 -320.92138)
		(width 0.127)
		(layer "In2.Cu")
		(net "T12_BLAD1_RXD")
	)
	(via
		(at 92.306394 -488.558586)
		(size 0.508)
		(drill 0.254)
		(layers "F.Cu" "B.Cu")
		(net "T12_BLAD3_RXD")
	)
	(segment
		(start 88.540082 -442.365638)
		(end 97.710498 -451.536054)
		(width 0.127)
		(layer "In5.Cu")
		(net "T12_BLAD3_RXD")
	)
	(segment
		(start 75.512168 -443.3189)
		(end 76.46543 -442.365638)
		(width 0.127)
		(layer "In5.Cu")
		(net "T12_BLAD3_RXD")
	)
	(segment
		(start 3.949954 -310.66994)
		(end 5.119878 -311.839864)
		(width 0.127)
		(layer "In5.Cu")
		(net "T12_BLAD3_RXD")
	)
	(segment
		(start 33.523682 -443.3189)
		(end 75.512168 -443.3189)
		(width 0.127)
		(layer "In5.Cu")
		(net "T12_BLAD3_RXD")
	)
	(segment
		(start 97.710498 -483.154482)
		(end 92.306394 -488.558586)
		(width 0.127)
		(layer "In5.Cu")
		(net "T12_BLAD3_RXD")
	)
	(segment
		(start 97.710498 -451.536054)
		(end 97.710498 -483.154482)
		(width 0.127)
		(layer "In5.Cu")
		(net "T12_BLAD3_RXD")
	)
	(segment
		(start 86.90991 -493.95507)
		(end 92.306394 -488.558586)
		(width 0.127)
		(layer "In5.Cu")
		(net "T12_BLAD3_RXD")
	)
	(segment
		(start 76.46543 -442.365638)
		(end 88.540082 -442.365638)
		(width 0.127)
		(layer "In5.Cu")
		(net "T12_BLAD3_RXD")
	)
	(segment
		(start 7.117588 -311.839864)
		(end 8.114538 -310.842914)
		(width 0.127)
		(layer "In5.Cu")
		(net "T12_BLAD3_RXD")
	)
	(segment
		(start 13.165328 -310.842914)
		(end 20.567396 -318.244982)
		(width 0.127)
		(layer "In5.Cu")
		(net "T12_BLAD3_RXD")
	)
	(segment
		(start 20.963382 -372.369588)
		(end 28.214066 -379.620272)
		(width 0.127)
		(layer "In5.Cu")
		(net "T12_BLAD3_RXD")
	)
	(segment
		(start 28.214066 -379.620272)
		(end 28.214066 -438.009284)
		(width 0.127)
		(layer "In5.Cu")
		(net "T12_BLAD3_RXD")
	)
	(segment
		(start 28.214066 -438.009284)
		(end 33.523682 -443.3189)
		(width 0.127)
		(layer "In5.Cu")
		(net "T12_BLAD3_RXD")
	)
	(segment
		(start 20.963382 -351.12198)
		(end 20.963382 -372.369588)
		(width 0.127)
		(layer "In5.Cu")
		(net "T12_BLAD3_RXD")
	)
	(segment
		(start 20.567396 -318.244982)
		(end 20.567396 -350.725994)
		(width 0.127)
		(layer "In5.Cu")
		(net "T12_BLAD3_RXD")
	)
	(segment
		(start 5.119878 -311.839864)
		(end 7.117588 -311.839864)
		(width 0.127)
		(layer "In5.Cu")
		(net "T12_BLAD3_RXD")
	)
	(segment
		(start 8.114538 -310.842914)
		(end 13.165328 -310.842914)
		(width 0.127)
		(layer "In5.Cu")
		(net "T12_BLAD3_RXD")
	)
	(segment
		(start 20.567396 -350.725994)
		(end 20.963382 -351.12198)
		(width 0.127)
		(layer "In5.Cu")
		(net "T12_BLAD3_RXD")
	)
	(via
		(at 91.012772 -487.85272)
		(size 0.508)
		(drill 0.254)
		(layers "F.Cu" "B.Cu")
		(net "T12_BLAD2_RXD")
	)
	(segment
		(start 19.906996 -320.438526)
		(end 12.339574 -312.871104)
		(width 0.127)
		(layer "In5.Cu")
		(net "T12_BLAD2_RXD")
	)
	(segment
		(start 32.917384 -444.035434)
		(end 27.453082 -438.571132)
		(width 0.127)
		(layer "In5.Cu")
		(net "T12_BLAD2_RXD")
	)
	(segment
		(start 77.171296 -443.306708)
		(end 76.44257 -444.035434)
		(width 0.127)
		(layer "In5.Cu")
		(net "T12_BLAD2_RXD")
	)
	(segment
		(start 27.453082 -380.18212)
		(end 20.228306 -372.957344)
		(width 0.127)
		(layer "In5.Cu")
		(net "T12_BLAD2_RXD")
	)
	(segment
		(start 84.290916 -494.574576)
		(end 91.012772 -487.85272)
		(width 0.127)
		(layer "In5.Cu")
		(net "T12_BLAD2_RXD")
	)
	(segment
		(start 91.98991 -496.49507)
		(end 91.98991 -497.849652)
		(width 0.127)
		(layer "In5.Cu")
		(net "T12_BLAD2_RXD")
	)
	(segment
		(start 19.906996 -350.999806)
		(end 19.906996 -320.438526)
		(width 0.127)
		(layer "In5.Cu")
		(net "T12_BLAD2_RXD")
	)
	(segment
		(start 91.012772 -487.85272)
		(end 97.0153 -481.850192)
		(width 0.127)
		(layer "In5.Cu")
		(net "T12_BLAD2_RXD")
	)
	(segment
		(start 97.0153 -481.850192)
		(end 97.0153 -451.879716)
		(width 0.127)
		(layer "In5.Cu")
		(net "T12_BLAD2_RXD")
	)
	(segment
		(start 12.339574 -312.871104)
		(end 8.153654 -312.871104)
		(width 0.127)
		(layer "In5.Cu")
		(net "T12_BLAD2_RXD")
	)
	(segment
		(start 20.228306 -351.321116)
		(end 19.906996 -350.999806)
		(width 0.127)
		(layer "In5.Cu")
		(net "T12_BLAD2_RXD")
	)
	(segment
		(start 2.182876 -313.902852)
		(end 1.949958 -313.669934)
		(width 0.127)
		(layer "In5.Cu")
		(net "T12_BLAD2_RXD")
	)
	(segment
		(start 91.98991 -497.849652)
		(end 90.631772 -499.20779)
		(width 0.127)
		(layer "In5.Cu")
		(net "T12_BLAD2_RXD")
	)
	(segment
		(start 84.290916 -498.140228)
		(end 84.290916 -494.574576)
		(width 0.127)
		(layer "In5.Cu")
		(net "T12_BLAD2_RXD")
	)
	(segment
		(start 88.442292 -443.306708)
		(end 77.171296 -443.306708)
		(width 0.127)
		(layer "In5.Cu")
		(net "T12_BLAD2_RXD")
	)
	(segment
		(start 76.44257 -444.035434)
		(end 32.917384 -444.035434)
		(width 0.127)
		(layer "In5.Cu")
		(net "T12_BLAD2_RXD")
	)
	(segment
		(start 8.153654 -312.871104)
		(end 7.121906 -313.902852)
		(width 0.127)
		(layer "In5.Cu")
		(net "T12_BLAD2_RXD")
	)
	(segment
		(start 7.121906 -313.902852)
		(end 2.182876 -313.902852)
		(width 0.127)
		(layer "In5.Cu")
		(net "T12_BLAD2_RXD")
	)
	(segment
		(start 27.453082 -438.571132)
		(end 27.453082 -380.18212)
		(width 0.127)
		(layer "In5.Cu")
		(net "T12_BLAD2_RXD")
	)
	(segment
		(start 90.631772 -499.20779)
		(end 85.358478 -499.20779)
		(width 0.127)
		(layer "In5.Cu")
		(net "T12_BLAD2_RXD")
	)
	(segment
		(start 97.0153 -451.879716)
		(end 88.442292 -443.306708)
		(width 0.127)
		(layer "In5.Cu")
		(net "T12_BLAD2_RXD")
	)
	(segment
		(start 85.358478 -499.20779)
		(end 84.290916 -498.140228)
		(width 0.127)
		(layer "In5.Cu")
		(net "T12_BLAD2_RXD")
	)
	(segment
		(start 20.228306 -372.957344)
		(end 20.228306 -351.321116)
		(width 0.127)
		(layer "In5.Cu")
		(net "T12_BLAD2_RXD")
	)
	(via
		(at 92.293694 -487.251502)
		(size 0.508)
		(drill 0.254)
		(layers "F.Cu" "B.Cu")
		(net "T12_BLAD2_TXD")
	)
	(segment
		(start 97.35693 -482.188266)
		(end 92.293694 -487.251502)
		(width 0.127)
		(layer "In5.Cu")
		(net "T12_BLAD2_TXD")
	)
	(segment
		(start 20.633182 -372.684548)
		(end 27.863546 -379.914912)
		(width 0.127)
		(layer "In5.Cu")
		(net "T12_BLAD2_TXD")
	)
	(segment
		(start 14.135354 -312.524902)
		(end 20.237196 -318.626744)
		(width 0.127)
		(layer "In5.Cu")
		(net "T12_BLAD2_TXD")
	)
	(segment
		(start 7.90956 -312.524902)
		(end 14.135354 -312.524902)
		(width 0.127)
		(layer "In5.Cu")
		(net "T12_BLAD2_TXD")
	)
	(segment
		(start 20.237196 -318.626744)
		(end 20.237196 -350.8629)
		(width 0.127)
		(layer "In5.Cu")
		(net "T12_BLAD2_TXD")
	)
	(segment
		(start 27.863546 -379.914912)
		(end 27.863546 -438.303924)
		(width 0.127)
		(layer "In5.Cu")
		(net "T12_BLAD2_TXD")
	)
	(segment
		(start 76.28509 -443.658498)
		(end 77.128878 -442.81471)
		(width 0.127)
		(layer "In5.Cu")
		(net "T12_BLAD2_TXD")
	)
	(segment
		(start 3.949954 -312.669936)
		(end 4.752848 -313.47283)
		(width 0.127)
		(layer "In5.Cu")
		(net "T12_BLAD2_TXD")
	)
	(segment
		(start 97.35693 -451.75424)
		(end 97.35693 -482.188266)
		(width 0.127)
		(layer "In5.Cu")
		(net "T12_BLAD2_TXD")
	)
	(segment
		(start 90.71991 -497.76507)
		(end 89.762584 -498.722396)
		(width 0.127)
		(layer "In5.Cu")
		(net "T12_BLAD2_TXD")
	)
	(segment
		(start 88.4174 -442.81471)
		(end 97.35693 -451.75424)
		(width 0.127)
		(layer "In5.Cu")
		(net "T12_BLAD2_TXD")
	)
	(segment
		(start 6.961632 -313.47283)
		(end 7.90956 -312.524902)
		(width 0.127)
		(layer "In5.Cu")
		(net "T12_BLAD2_TXD")
	)
	(segment
		(start 20.237196 -350.8629)
		(end 20.633182 -351.258886)
		(width 0.127)
		(layer "In5.Cu")
		(net "T12_BLAD2_TXD")
	)
	(segment
		(start 27.863546 -438.303924)
		(end 33.21812 -443.658498)
		(width 0.127)
		(layer "In5.Cu")
		(net "T12_BLAD2_TXD")
	)
	(segment
		(start 84.69884 -497.946426)
		(end 84.69884 -494.846356)
		(width 0.127)
		(layer "In5.Cu")
		(net "T12_BLAD2_TXD")
	)
	(segment
		(start 4.752848 -313.47283)
		(end 6.961632 -313.47283)
		(width 0.127)
		(layer "In5.Cu")
		(net "T12_BLAD2_TXD")
	)
	(segment
		(start 89.762584 -498.722396)
		(end 85.47481 -498.722396)
		(width 0.127)
		(layer "In5.Cu")
		(net "T12_BLAD2_TXD")
	)
	(segment
		(start 85.47481 -498.722396)
		(end 84.69884 -497.946426)
		(width 0.127)
		(layer "In5.Cu")
		(net "T12_BLAD2_TXD")
	)
	(segment
		(start 20.633182 -351.258886)
		(end 20.633182 -372.684548)
		(width 0.127)
		(layer "In5.Cu")
		(net "T12_BLAD2_TXD")
	)
	(segment
		(start 77.128878 -442.81471)
		(end 88.4174 -442.81471)
		(width 0.127)
		(layer "In5.Cu")
		(net "T12_BLAD2_TXD")
	)
	(segment
		(start 84.69884 -494.846356)
		(end 92.293694 -487.251502)
		(width 0.127)
		(layer "In5.Cu")
		(net "T12_BLAD2_TXD")
	)
	(segment
		(start 33.21812 -443.658498)
		(end 76.28509 -443.658498)
		(width 0.127)
		(layer "In5.Cu")
		(net "T12_BLAD2_TXD")
	)
	(via
		(at 95.19285 -487.487722)
		(size 0.508)
		(drill 0.254)
		(layers "F.Cu" "B.Cu")
		(net "T12_BLAD4_TXD")
	)
	(segment
		(start 6.702552 -309.419244)
		(end 3.699256 -309.419244)
		(width 0.127)
		(layer "In5.Cu")
		(net "T12_BLAD4_TXD")
	)
	(segment
		(start 21.227796 -350.452182)
		(end 21.227796 -316.648338)
		(width 0.127)
		(layer "In5.Cu")
		(net "T12_BLAD4_TXD")
	)
	(segment
		(start 13.461746 -308.882288)
		(end 7.239508 -308.882288)
		(width 0.127)
		(layer "In5.Cu")
		(net "T12_BLAD4_TXD")
	)
	(segment
		(start 28.932632 -437.500776)
		(end 28.932632 -379.135132)
		(width 0.127)
		(layer "In5.Cu")
		(net "T12_BLAD4_TXD")
	)
	(segment
		(start 98.413062 -484.26751)
		(end 98.413062 -451.070472)
		(width 0.127)
		(layer "In5.Cu")
		(net "T12_BLAD4_TXD")
	)
	(segment
		(start 7.239508 -308.882288)
		(end 6.702552 -309.419244)
		(width 0.127)
		(layer "In5.Cu")
		(net "T12_BLAD4_TXD")
	)
	(segment
		(start 21.227796 -316.648338)
		(end 13.461746 -308.882288)
		(width 0.127)
		(layer "In5.Cu")
		(net "T12_BLAD4_TXD")
	)
	(segment
		(start 21.623782 -371.826282)
		(end 21.623782 -350.848168)
		(width 0.127)
		(layer "In5.Cu")
		(net "T12_BLAD4_TXD")
	)
	(segment
		(start 95.19285 -487.487722)
		(end 98.413062 -484.26751)
		(width 0.127)
		(layer "In5.Cu")
		(net "T12_BLAD4_TXD")
	)
	(segment
		(start 88.80983 -441.46724)
		(end 75.973686 -441.46724)
		(width 0.127)
		(layer "In5.Cu")
		(net "T12_BLAD4_TXD")
	)
	(segment
		(start 95.19285 -487.487722)
		(end 90.71991 -491.960662)
		(width 0.127)
		(layer "In5.Cu")
		(net "T12_BLAD4_TXD")
	)
	(segment
		(start 90.71991 -491.960662)
		(end 90.71991 -495.22507)
		(width 0.127)
		(layer "In5.Cu")
		(net "T12_BLAD4_TXD")
	)
	(segment
		(start 28.932632 -379.135132)
		(end 21.623782 -371.826282)
		(width 0.127)
		(layer "In5.Cu")
		(net "T12_BLAD4_TXD")
	)
	(segment
		(start 3.699256 -309.419244)
		(end 1.949958 -307.669946)
		(width 0.127)
		(layer "In5.Cu")
		(net "T12_BLAD4_TXD")
	)
	(segment
		(start 98.413062 -451.070472)
		(end 88.80983 -441.46724)
		(width 0.127)
		(layer "In5.Cu")
		(net "T12_BLAD4_TXD")
	)
	(segment
		(start 33.994598 -442.562742)
		(end 28.932632 -437.500776)
		(width 0.127)
		(layer "In5.Cu")
		(net "T12_BLAD4_TXD")
	)
	(segment
		(start 74.878184 -442.562742)
		(end 33.994598 -442.562742)
		(width 0.127)
		(layer "In5.Cu")
		(net "T12_BLAD4_TXD")
	)
	(segment
		(start 21.623782 -350.848168)
		(end 21.227796 -350.452182)
		(width 0.127)
		(layer "In5.Cu")
		(net "T12_BLAD4_TXD")
	)
	(segment
		(start 75.973686 -441.46724)
		(end 74.878184 -442.562742)
		(width 0.127)
		(layer "In5.Cu")
		(net "T12_BLAD4_TXD")
	)
	(segment
		(start 28.73375 -108.230416)
		(end 28.738068 -108.226098)
		(width 0.508)
		(layer "F.Cu")
		(net "PSU2_REMOTE_N")
	)
	(segment
		(start 29.014928 -108.229908)
		(end 30.45968 -108.229908)
		(width 0.508)
		(layer "F.Cu")
		(net "PSU2_REMOTE_N")
	)
	(segment
		(start 28.738068 -108.226098)
		(end 29.011118 -108.226098)
		(width 0.508)
		(layer "F.Cu")
		(net "PSU2_REMOTE_N")
	)
	(segment
		(start 27.347672 -108.230416)
		(end 28.73375 -108.230416)
		(width 0.508)
		(layer "F.Cu")
		(net "PSU2_REMOTE_N")
	)
	(segment
		(start 29.011118 -108.226098)
		(end 29.014928 -108.229908)
		(width 0.508)
		(layer "F.Cu")
		(net "PSU2_REMOTE_N")
	)
	(via
		(at 84.807806 -14.229334)
		(size 0.508)
		(drill 0.254)
		(layers "F.Cu" "B.Cu")
		(net "T1_BLAD4_TXD")
	)
	(segment
		(start 24.783542 -107.56773)
		(end 24.783542 -105.338118)
		(width 0.127)
		(layer "In2.Cu")
		(net "T1_BLAD4_TXD")
	)
	(segment
		(start 15.959582 -197.370446)
		(end 15.959582 -178.391566)
		(width 0.127)
		(layer "In2.Cu")
		(net "T1_BLAD4_TXD")
	)
	(segment
		(start 84.807806 -15.459964)
		(end 84.807806 -14.229334)
		(width 0.127)
		(layer "In2.Cu")
		(net "T1_BLAD4_TXD")
	)
	(segment
		(start 84.560918 -48.829722)
		(end 84.560918 -15.706852)
		(width 0.127)
		(layer "In2.Cu")
		(net "T1_BLAD4_TXD")
	)
	(segment
		(start 51.73218 -86.704424)
		(end 74.964798 -63.471806)
		(width 0.127)
		(layer "In2.Cu")
		(net "T1_BLAD4_TXD")
	)
	(segment
		(start 89.842086 -4.204462)
		(end 90.71991 -5.082286)
		(width 0.127)
		(layer "In2.Cu")
		(net "T1_BLAD4_TXD")
	)
	(segment
		(start 83.508596 -52.90439)
		(end 83.508596 -49.882044)
		(width 0.127)
		(layer "In2.Cu")
		(net "T1_BLAD4_TXD")
	)
	(segment
		(start 24.783542 -105.338118)
		(end 22.865334 -103.41991)
		(width 0.127)
		(layer "In2.Cu")
		(net "T1_BLAD4_TXD")
	)
	(segment
		(start 80.733392 -54.361588)
		(end 82.051398 -54.361588)
		(width 0.127)
		(layer "In2.Cu")
		(net "T1_BLAD4_TXD")
	)
	(segment
		(start 83.508596 -49.882044)
		(end 84.560918 -48.829722)
		(width 0.127)
		(layer "In2.Cu")
		(net "T1_BLAD4_TXD")
	)
	(segment
		(start 74.964798 -63.471806)
		(end 74.964798 -60.130182)
		(width 0.127)
		(layer "In2.Cu")
		(net "T1_BLAD4_TXD")
	)
	(segment
		(start 84.560918 -15.706852)
		(end 84.807806 -15.459964)
		(width 0.127)
		(layer "In2.Cu")
		(net "T1_BLAD4_TXD")
	)
	(segment
		(start 24.525478 -107.825794)
		(end 24.783542 -107.56773)
		(width 0.127)
		(layer "In2.Cu")
		(net "T1_BLAD4_TXD")
	)
	(segment
		(start 90.71991 -5.082286)
		(end 90.71991 -6.27507)
		(width 0.127)
		(layer "In2.Cu")
		(net "T1_BLAD4_TXD")
	)
	(segment
		(start 15.959582 -178.391566)
		(end 24.525478 -169.82567)
		(width 0.127)
		(layer "In2.Cu")
		(net "T1_BLAD4_TXD")
	)
	(segment
		(start 82.051398 -54.361588)
		(end 83.508596 -52.90439)
		(width 0.127)
		(layer "In2.Cu")
		(net "T1_BLAD4_TXD")
	)
	(segment
		(start 6.448806 -219.984574)
		(end 7.977124 -221.512892)
		(width 0.127)
		(layer "In2.Cu")
		(net "T1_BLAD4_TXD")
	)
	(segment
		(start 22.865334 -92.239084)
		(end 28.399994 -86.704424)
		(width 0.127)
		(layer "In2.Cu")
		(net "T1_BLAD4_TXD")
	)
	(segment
		(start 74.964798 -60.130182)
		(end 80.733392 -54.361588)
		(width 0.127)
		(layer "In2.Cu")
		(net "T1_BLAD4_TXD")
	)
	(segment
		(start 8.793226 -221.512892)
		(end 9.490964 -220.815154)
		(width 0.127)
		(layer "In2.Cu")
		(net "T1_BLAD4_TXD")
	)
	(segment
		(start 28.399994 -86.704424)
		(end 51.73218 -86.704424)
		(width 0.127)
		(layer "In2.Cu")
		(net "T1_BLAD4_TXD")
	)
	(segment
		(start 9.490964 -203.839064)
		(end 15.959582 -197.370446)
		(width 0.127)
		(layer "In2.Cu")
		(net "T1_BLAD4_TXD")
	)
	(segment
		(start 9.490964 -220.815154)
		(end 9.490964 -203.839064)
		(width 0.127)
		(layer "In2.Cu")
		(net "T1_BLAD4_TXD")
	)
	(segment
		(start 84.807806 -14.229334)
		(end 84.807806 -5.754624)
		(width 0.127)
		(layer "In2.Cu")
		(net "T1_BLAD4_TXD")
	)
	(segment
		(start 22.865334 -103.41991)
		(end 22.865334 -92.239084)
		(width 0.127)
		(layer "In2.Cu")
		(net "T1_BLAD4_TXD")
	)
	(segment
		(start 84.807806 -5.754624)
		(end 86.357968 -4.204462)
		(width 0.127)
		(layer "In2.Cu")
		(net "T1_BLAD4_TXD")
	)
	(segment
		(start 7.977124 -221.512892)
		(end 8.793226 -221.512892)
		(width 0.127)
		(layer "In2.Cu")
		(net "T1_BLAD4_TXD")
	)
	(segment
		(start 6.448806 -219.67063)
		(end 6.448806 -219.984574)
		(width 0.127)
		(layer "In2.Cu")
		(net "T1_BLAD4_TXD")
	)
	(segment
		(start 24.525478 -169.82567)
		(end 24.525478 -107.825794)
		(width 0.127)
		(layer "In2.Cu")
		(net "T1_BLAD4_TXD")
	)
	(segment
		(start 86.357968 -4.204462)
		(end 89.842086 -4.204462)
		(width 0.127)
		(layer "In2.Cu")
		(net "T1_BLAD4_TXD")
	)
	(via
		(at 84.176362 -13.057886)
		(size 0.508)
		(drill 0.254)
		(layers "F.Cu" "B.Cu")
		(net "T1_BLAD4_RXD")
	)
	(segment
		(start 74.489818 -59.933332)
		(end 80.451706 -53.971444)
		(width 0.127)
		(layer "In2.Cu")
		(net "T1_BLAD4_RXD")
	)
	(segment
		(start 86.105746 -3.854958)
		(end 90.839798 -3.854958)
		(width 0.127)
		(layer "In2.Cu")
		(net "T1_BLAD4_RXD")
	)
	(segment
		(start 81.974182 -53.971444)
		(end 83.178396 -52.76723)
		(width 0.127)
		(layer "In2.Cu")
		(net "T1_BLAD4_RXD")
	)
	(segment
		(start 28.222956 -86.229444)
		(end 51.53533 -86.229444)
		(width 0.127)
		(layer "In2.Cu")
		(net "T1_BLAD4_RXD")
	)
	(segment
		(start 84.176362 -5.784342)
		(end 86.105746 -3.854958)
		(width 0.127)
		(layer "In2.Cu")
		(net "T1_BLAD4_RXD")
	)
	(segment
		(start 22.535134 -103.556816)
		(end 22.535134 -91.917266)
		(width 0.127)
		(layer "In2.Cu")
		(net "T1_BLAD4_RXD")
	)
	(segment
		(start 24.453342 -107.430824)
		(end 24.453342 -105.475024)
		(width 0.127)
		(layer "In2.Cu")
		(net "T1_BLAD4_RXD")
	)
	(segment
		(start 83.178396 -52.76723)
		(end 83.178396 -49.745138)
		(width 0.127)
		(layer "In2.Cu")
		(net "T1_BLAD4_RXD")
	)
	(segment
		(start 24.453342 -105.475024)
		(end 22.535134 -103.556816)
		(width 0.127)
		(layer "In2.Cu")
		(net "T1_BLAD4_RXD")
	)
	(segment
		(start 22.535134 -91.917266)
		(end 28.222956 -86.229444)
		(width 0.127)
		(layer "In2.Cu")
		(net "T1_BLAD4_RXD")
	)
	(segment
		(start 9.148826 -203.714096)
		(end 15.588234 -197.274688)
		(width 0.127)
		(layer "In2.Cu")
		(net "T1_BLAD4_RXD")
	)
	(segment
		(start 9.148826 -219.970604)
		(end 9.148826 -203.714096)
		(width 0.127)
		(layer "In2.Cu")
		(net "T1_BLAD4_RXD")
	)
	(segment
		(start 90.839798 -3.854958)
		(end 91.98991 -5.00507)
		(width 0.127)
		(layer "In2.Cu")
		(net "T1_BLAD4_RXD")
	)
	(segment
		(start 74.489818 -63.274956)
		(end 74.489818 -59.933332)
		(width 0.127)
		(layer "In2.Cu")
		(net "T1_BLAD4_RXD")
	)
	(segment
		(start 15.588234 -178.27879)
		(end 24.195278 -169.671746)
		(width 0.127)
		(layer "In2.Cu")
		(net "T1_BLAD4_RXD")
	)
	(segment
		(start 80.451706 -53.971444)
		(end 81.974182 -53.971444)
		(width 0.127)
		(layer "In2.Cu")
		(net "T1_BLAD4_RXD")
	)
	(segment
		(start 24.195278 -169.671746)
		(end 24.195278 -107.688888)
		(width 0.127)
		(layer "In2.Cu")
		(net "T1_BLAD4_RXD")
	)
	(segment
		(start 8.448802 -220.670628)
		(end 9.148826 -219.970604)
		(width 0.127)
		(layer "In2.Cu")
		(net "T1_BLAD4_RXD")
	)
	(segment
		(start 84.176362 -48.747172)
		(end 84.176362 -13.057886)
		(width 0.127)
		(layer "In2.Cu")
		(net "T1_BLAD4_RXD")
	)
	(segment
		(start 24.195278 -107.688888)
		(end 24.453342 -107.430824)
		(width 0.127)
		(layer "In2.Cu")
		(net "T1_BLAD4_RXD")
	)
	(segment
		(start 51.53533 -86.229444)
		(end 74.489818 -63.274956)
		(width 0.127)
		(layer "In2.Cu")
		(net "T1_BLAD4_RXD")
	)
	(segment
		(start 15.588234 -197.274688)
		(end 15.588234 -178.27879)
		(width 0.127)
		(layer "In2.Cu")
		(net "T1_BLAD4_RXD")
	)
	(segment
		(start 84.176362 -13.057886)
		(end 84.176362 -5.784342)
		(width 0.127)
		(layer "In2.Cu")
		(net "T1_BLAD4_RXD")
	)
	(segment
		(start 83.178396 -49.745138)
		(end 84.176362 -48.747172)
		(width 0.127)
		(layer "In2.Cu")
		(net "T1_BLAD4_RXD")
	)
	(segment
		(start 27.328368 -196.6214)
		(end 27.329384 -196.622416)
		(width 0.508)
		(layer "F.Cu")
		(net "PSU3_REMOTE_N")
	)
	(segment
		(start 27.329384 -196.622416)
		(end 29.12237 -196.622416)
		(width 0.508)
		(layer "F.Cu")
		(net "PSU3_REMOTE_N")
	)
	(segment
		(start 29.12999 -196.630036)
		(end 30.45968 -196.630036)
		(width 0.508)
		(layer "F.Cu")
		(net "PSU3_REMOTE_N")
	)
	(segment
		(start 29.12237 -196.622416)
		(end 29.12999 -196.630036)
		(width 0.508)
		(layer "F.Cu")
		(net "PSU3_REMOTE_N")
	)
	(segment
		(start 39.5732 -191.432942)
		(end 39.77894 -191.227202)
		(width 0.1524)
		(layer "F.Cu")
		(net "PSU3_RETURN")
	)
	(segment
		(start 39.77894 -191.227202)
		(end 39.77894 -190.770002)
		(width 0.1524)
		(layer "F.Cu")
		(net "PSU3_RETURN")
	)
	(segment
		(start 35.53968 -189.010036)
		(end 38.542214 -189.010036)
		(width 0.1524)
		(layer "F.Cu")
		(net "PSU3_RETURN")
	)
	(segment
		(start 39.77894 -190.246762)
		(end 39.77894 -190.770002)
		(width 0.1524)
		(layer "F.Cu")
		(net "PSU3_RETURN")
	)
	(segment
		(start 38.542214 -189.010036)
		(end 39.77894 -190.246762)
		(width 0.1524)
		(layer "F.Cu")
		(net "PSU3_RETURN")
	)
	(segment
		(start 39.5732 -192.216278)
		(end 39.5732 -191.432942)
		(width 0.1524)
		(layer "F.Cu")
		(net "PSU3_RETURN")
	)
	(via
		(at 39.77894 -190.770002)
		(size 0.508)
		(drill 0.254)
		(layers "F.Cu" "B.Cu")
		(net "PSU3_RETURN")
	)
	(via
		(at 86.454742 -13.101066)
		(size 0.508)
		(drill 0.254)
		(layers "F.Cu" "B.Cu")
		(net "T1_BLAD3_TXD")
	)
	(segment
		(start 25.113742 -107.704636)
		(end 24.855678 -107.9627)
		(width 0.127)
		(layer "In2.Cu")
		(net "T1_BLAD3_TXD")
	)
	(segment
		(start 82.214466 -54.859936)
		(end 80.929988 -54.859936)
		(width 0.127)
		(layer "In2.Cu")
		(net "T1_BLAD3_TXD")
	)
	(segment
		(start 84.891118 -48.966628)
		(end 83.838796 -50.01895)
		(width 0.127)
		(layer "In2.Cu")
		(net "T1_BLAD3_TXD")
	)
	(segment
		(start 23.195534 -103.283004)
		(end 25.113742 -105.201212)
		(width 0.127)
		(layer "In2.Cu")
		(net "T1_BLAD3_TXD")
	)
	(segment
		(start 51.935888 -87.19566)
		(end 28.603702 -87.19566)
		(width 0.127)
		(layer "In2.Cu")
		(net "T1_BLAD3_TXD")
	)
	(segment
		(start 80.929988 -54.859936)
		(end 75.456034 -60.33389)
		(width 0.127)
		(layer "In2.Cu")
		(net "T1_BLAD3_TXD")
	)
	(segment
		(start 86.454742 -14.29766)
		(end 84.891118 -15.861284)
		(width 0.127)
		(layer "In2.Cu")
		(net "T1_BLAD3_TXD")
	)
	(segment
		(start 86.454742 -13.101066)
		(end 86.454742 -14.29766)
		(width 0.127)
		(layer "In2.Cu")
		(net "T1_BLAD3_TXD")
	)
	(segment
		(start 85.63991 -7.649718)
		(end 86.454742 -8.46455)
		(width 0.127)
		(layer "In2.Cu")
		(net "T1_BLAD3_TXD")
	)
	(segment
		(start 75.456034 -63.675514)
		(end 51.935888 -87.19566)
		(width 0.127)
		(layer "In2.Cu")
		(net "T1_BLAD3_TXD")
	)
	(segment
		(start 83.838796 -50.01895)
		(end 83.838796 -53.235606)
		(width 0.127)
		(layer "In2.Cu")
		(net "T1_BLAD3_TXD")
	)
	(segment
		(start 28.603702 -87.19566)
		(end 23.195534 -92.603828)
		(width 0.127)
		(layer "In2.Cu")
		(net "T1_BLAD3_TXD")
	)
	(segment
		(start 83.838796 -53.235606)
		(end 82.214466 -54.859936)
		(width 0.127)
		(layer "In2.Cu")
		(net "T1_BLAD3_TXD")
	)
	(segment
		(start 9.833102 -203.964032)
		(end 9.833102 -221.286324)
		(width 0.127)
		(layer "In2.Cu")
		(net "T1_BLAD3_TXD")
	)
	(segment
		(start 9.833102 -221.286324)
		(end 8.448802 -222.670624)
		(width 0.127)
		(layer "In2.Cu")
		(net "T1_BLAD3_TXD")
	)
	(segment
		(start 84.891118 -15.861284)
		(end 84.891118 -48.966628)
		(width 0.127)
		(layer "In2.Cu")
		(net "T1_BLAD3_TXD")
	)
	(segment
		(start 85.63991 -6.27507)
		(end 85.63991 -7.649718)
		(width 0.127)
		(layer "In2.Cu")
		(net "T1_BLAD3_TXD")
	)
	(segment
		(start 86.454742 -8.46455)
		(end 86.454742 -13.101066)
		(width 0.127)
		(layer "In2.Cu")
		(net "T1_BLAD3_TXD")
	)
	(segment
		(start 16.316452 -197.480682)
		(end 9.833102 -203.964032)
		(width 0.127)
		(layer "In2.Cu")
		(net "T1_BLAD3_TXD")
	)
	(segment
		(start 23.195534 -92.603828)
		(end 23.195534 -103.283004)
		(width 0.127)
		(layer "In2.Cu")
		(net "T1_BLAD3_TXD")
	)
	(segment
		(start 75.456034 -60.33389)
		(end 75.456034 -63.675514)
		(width 0.127)
		(layer "In2.Cu")
		(net "T1_BLAD3_TXD")
	)
	(segment
		(start 24.855678 -107.9627)
		(end 24.855678 -170.000168)
		(width 0.127)
		(layer "In2.Cu")
		(net "T1_BLAD3_TXD")
	)
	(segment
		(start 25.113742 -105.201212)
		(end 25.113742 -107.704636)
		(width 0.127)
		(layer "In2.Cu")
		(net "T1_BLAD3_TXD")
	)
	(segment
		(start 16.316452 -178.539394)
		(end 16.316452 -197.480682)
		(width 0.127)
		(layer "In2.Cu")
		(net "T1_BLAD3_TXD")
	)
	(segment
		(start 24.855678 -170.000168)
		(end 16.316452 -178.539394)
		(width 0.127)
		(layer "In2.Cu")
		(net "T1_BLAD3_TXD")
	)
	(via
		(at 41.467278 -441.355226)
		(size 0.508)
		(drill 0.254)
		(layers "F.Cu" "B.Cu")
		(net "T11_BLAD3_RXD")
	)
	(segment
		(start 46.605952 -446.4939)
		(end 84.61502 -446.4939)
		(width 0.127)
		(layer "In2.Cu")
		(net "T11_BLAD3_RXD")
	)
	(segment
		(start 86.90991 -448.78879)
		(end 86.90991 -449.50507)
		(width 0.127)
		(layer "In2.Cu")
		(net "T11_BLAD3_RXD")
	)
	(segment
		(start 30.642814 -440.300364)
		(end 40.412416 -440.300364)
		(width 0.127)
		(layer "In2.Cu")
		(net "T11_BLAD3_RXD")
	)
	(segment
		(start 27.835352 -379.621796)
		(end 27.835352 -437.492902)
		(width 0.127)
		(layer "In2.Cu")
		(net "T11_BLAD3_RXD")
	)
	(segment
		(start 11.952224 -306.669948)
		(end 20.284694 -315.002418)
		(width 0.127)
		(layer "In2.Cu")
		(net "T11_BLAD3_RXD")
	)
	(segment
		(start 27.835352 -437.492902)
		(end 30.642814 -440.300364)
		(width 0.127)
		(layer "In2.Cu")
		(net "T11_BLAD3_RXD")
	)
	(segment
		(start 84.61502 -446.4939)
		(end 86.90991 -448.78879)
		(width 0.127)
		(layer "In2.Cu")
		(net "T11_BLAD3_RXD")
	)
	(segment
		(start 20.284694 -372.071138)
		(end 27.835352 -379.621796)
		(width 0.127)
		(layer "In2.Cu")
		(net "T11_BLAD3_RXD")
	)
	(segment
		(start 40.412416 -440.300364)
		(end 41.467278 -441.355226)
		(width 0.127)
		(layer "In2.Cu")
		(net "T11_BLAD3_RXD")
	)
	(segment
		(start 41.467278 -441.355226)
		(end 46.605952 -446.4939)
		(width 0.127)
		(layer "In2.Cu")
		(net "T11_BLAD3_RXD")
	)
	(segment
		(start 6.449822 -306.669948)
		(end 11.952224 -306.669948)
		(width 0.127)
		(layer "In2.Cu")
		(net "T11_BLAD3_RXD")
	)
	(segment
		(start 20.284694 -315.002418)
		(end 20.284694 -372.071138)
		(width 0.127)
		(layer "In2.Cu")
		(net "T11_BLAD3_RXD")
	)
	(via
		(at 85.909658 -15.635986)
		(size 0.508)
		(drill 0.254)
		(layers "F.Cu" "B.Cu")
		(net "T1_BLAD3_RXD")
	)
	(segment
		(start 23.525734 -102.945692)
		(end 25.443942 -104.8639)
		(width 0.127)
		(layer "In2.Cu")
		(net "T1_BLAD3_RXD")
	)
	(segment
		(start 16.709136 -178.70805)
		(end 16.709136 -197.555358)
		(width 0.127)
		(layer "In2.Cu")
		(net "T1_BLAD3_RXD")
	)
	(segment
		(start 25.443942 -104.8639)
		(end 25.443942 -107.85856)
		(width 0.127)
		(layer "In2.Cu")
		(net "T1_BLAD3_RXD")
	)
	(segment
		(start 10.18667 -204.077824)
		(end 10.18667 -222.315278)
		(width 0.127)
		(layer "In2.Cu")
		(net "T1_BLAD3_RXD")
	)
	(segment
		(start 16.709136 -197.555358)
		(end 10.18667 -204.077824)
		(width 0.127)
		(layer "In2.Cu")
		(net "T1_BLAD3_RXD")
	)
	(segment
		(start 87.053674 -14.49197)
		(end 85.909658 -15.635986)
		(width 0.127)
		(layer "In2.Cu")
		(net "T1_BLAD3_RXD")
	)
	(segment
		(start 25.200864 -170.216322)
		(end 16.709136 -178.70805)
		(width 0.127)
		(layer "In2.Cu")
		(net "T1_BLAD3_RXD")
	)
	(segment
		(start 85.221318 -16.324326)
		(end 85.221318 -49.103534)
		(width 0.127)
		(layer "In2.Cu")
		(net "T1_BLAD3_RXD")
	)
	(segment
		(start 82.532728 -55.221886)
		(end 81.116678 -55.221886)
		(width 0.127)
		(layer "In2.Cu")
		(net "T1_BLAD3_RXD")
	)
	(segment
		(start 75.843892 -60.494672)
		(end 75.843892 -63.836296)
		(width 0.127)
		(layer "In2.Cu")
		(net "T1_BLAD3_RXD")
	)
	(segment
		(start 6.576314 -223.543114)
		(end 6.448806 -223.670622)
		(width 0.127)
		(layer "In2.Cu")
		(net "T1_BLAD3_RXD")
	)
	(segment
		(start 81.116678 -55.221886)
		(end 75.843892 -60.494672)
		(width 0.127)
		(layer "In2.Cu")
		(net "T1_BLAD3_RXD")
	)
	(segment
		(start 87.80399 -7.2517)
		(end 87.80399 -8.018526)
		(width 0.127)
		(layer "In2.Cu")
		(net "T1_BLAD3_RXD")
	)
	(segment
		(start 52.09667 -87.583518)
		(end 29.119322 -87.583518)
		(width 0.127)
		(layer "In2.Cu")
		(net "T1_BLAD3_RXD")
	)
	(segment
		(start 85.221318 -49.103534)
		(end 84.168996 -50.155856)
		(width 0.127)
		(layer "In2.Cu")
		(net "T1_BLAD3_RXD")
	)
	(segment
		(start 25.443942 -107.85856)
		(end 25.200864 -108.101638)
		(width 0.127)
		(layer "In2.Cu")
		(net "T1_BLAD3_RXD")
	)
	(segment
		(start 25.200864 -108.101638)
		(end 25.200864 -170.216322)
		(width 0.127)
		(layer "In2.Cu")
		(net "T1_BLAD3_RXD")
	)
	(segment
		(start 86.90991 -6.35762)
		(end 87.80399 -7.2517)
		(width 0.127)
		(layer "In2.Cu")
		(net "T1_BLAD3_RXD")
	)
	(segment
		(start 87.80399 -8.018526)
		(end 87.053674 -8.768842)
		(width 0.127)
		(layer "In2.Cu")
		(net "T1_BLAD3_RXD")
	)
	(segment
		(start 75.843892 -63.836296)
		(end 52.09667 -87.583518)
		(width 0.127)
		(layer "In2.Cu")
		(net "T1_BLAD3_RXD")
	)
	(segment
		(start 85.909658 -15.635986)
		(end 85.221318 -16.324326)
		(width 0.127)
		(layer "In2.Cu")
		(net "T1_BLAD3_RXD")
	)
	(segment
		(start 10.18667 -222.315278)
		(end 8.958834 -223.543114)
		(width 0.127)
		(layer "In2.Cu")
		(net "T1_BLAD3_RXD")
	)
	(segment
		(start 8.958834 -223.543114)
		(end 6.576314 -223.543114)
		(width 0.127)
		(layer "In2.Cu")
		(net "T1_BLAD3_RXD")
	)
	(segment
		(start 23.525734 -93.177106)
		(end 23.525734 -102.945692)
		(width 0.127)
		(layer "In2.Cu")
		(net "T1_BLAD3_RXD")
	)
	(segment
		(start 84.168996 -53.585618)
		(end 82.532728 -55.221886)
		(width 0.127)
		(layer "In2.Cu")
		(net "T1_BLAD3_RXD")
	)
	(segment
		(start 84.168996 -50.155856)
		(end 84.168996 -53.585618)
		(width 0.127)
		(layer "In2.Cu")
		(net "T1_BLAD3_RXD")
	)
	(segment
		(start 86.90991 -5.00507)
		(end 86.90991 -6.35762)
		(width 0.127)
		(layer "In2.Cu")
		(net "T1_BLAD3_RXD")
	)
	(segment
		(start 87.053674 -8.768842)
		(end 87.053674 -14.49197)
		(width 0.127)
		(layer "In2.Cu")
		(net "T1_BLAD3_RXD")
	)
	(segment
		(start 29.119322 -87.583518)
		(end 23.525734 -93.177106)
		(width 0.127)
		(layer "In2.Cu")
		(net "T1_BLAD3_RXD")
	)
	(via
		(at 42.108628 -440.157362)
		(size 0.508)
		(drill 0.254)
		(layers "F.Cu" "B.Cu")
		(net "T11_BLAD4_RXD")
	)
	(segment
		(start 42.108628 -440.157108)
		(end 46.027594 -444.076074)
		(width 0.127)
		(layer "In2.Cu")
		(net "T11_BLAD4_RXD")
	)
	(segment
		(start 41.521888 -439.570368)
		(end 42.108628 -440.157108)
		(width 0.127)
		(layer "In2.Cu")
		(net "T11_BLAD4_RXD")
	)
	(segment
		(start 28.595828 -437.223154)
		(end 30.943042 -439.570368)
		(width 0.127)
		(layer "In2.Cu")
		(net "T11_BLAD4_RXD")
	)
	(segment
		(start 46.027594 -444.076074)
		(end 86.560914 -444.076074)
		(width 0.127)
		(layer "In2.Cu")
		(net "T11_BLAD4_RXD")
	)
	(segment
		(start 20.945094 -314.329318)
		(end 20.945094 -371.695218)
		(width 0.127)
		(layer "In2.Cu")
		(net "T11_BLAD4_RXD")
	)
	(segment
		(start 28.595828 -379.345952)
		(end 28.595828 -437.223154)
		(width 0.127)
		(layer "In2.Cu")
		(net "T11_BLAD4_RXD")
	)
	(segment
		(start 30.943042 -439.570368)
		(end 41.521888 -439.570368)
		(width 0.127)
		(layer "In2.Cu")
		(net "T11_BLAD4_RXD")
	)
	(segment
		(start 86.560914 -444.076074)
		(end 91.98991 -449.50507)
		(width 0.127)
		(layer "In2.Cu")
		(net "T11_BLAD4_RXD")
	)
	(segment
		(start 20.945094 -371.695218)
		(end 28.595828 -379.345952)
		(width 0.127)
		(layer "In2.Cu")
		(net "T11_BLAD4_RXD")
	)
	(segment
		(start 11.285728 -304.669952)
		(end 20.945094 -314.329318)
		(width 0.127)
		(layer "In2.Cu")
		(net "T11_BLAD4_RXD")
	)
	(segment
		(start 6.449822 -304.669952)
		(end 11.285728 -304.669952)
		(width 0.127)
		(layer "In2.Cu")
		(net "T11_BLAD4_RXD")
	)
	(segment
		(start 42.108628 -440.157108)
		(end 42.108628 -440.157362)
		(width 0.127)
		(layer "In2.Cu")
		(net "T11_BLAD4_RXD")
	)
	(via
		(at 39.670482 -440.75096)
		(size 0.508)
		(drill 0.254)
		(layers "F.Cu" "B.Cu")
		(net "T11_BLAD2_RXD")
	)
	(segment
		(start 30.625288 -440.75096)
		(end 39.670482 -440.75096)
		(width 0.127)
		(layer "In2.Cu")
		(net "T11_BLAD2_RXD")
	)
	(segment
		(start 27.465274 -437.590946)
		(end 30.625288 -440.75096)
		(width 0.127)
		(layer "In2.Cu")
		(net "T11_BLAD2_RXD")
	)
	(segment
		(start 90.817192 -452.04507)
		(end 89.929462 -451.15734)
		(width 0.127)
		(layer "In2.Cu")
		(net "T11_BLAD2_RXD")
	)
	(segment
		(start 89.036652 -451.15734)
		(end 88.45423 -451.739762)
		(width 0.127)
		(layer "In2.Cu")
		(net "T11_BLAD2_RXD")
	)
	(segment
		(start 91.98991 -452.04507)
		(end 90.817192 -452.04507)
		(width 0.127)
		(layer "In2.Cu")
		(net "T11_BLAD2_RXD")
	)
	(segment
		(start 19.954494 -372.220236)
		(end 27.465274 -379.731016)
		(width 0.127)
		(layer "In2.Cu")
		(net "T11_BLAD2_RXD")
	)
	(segment
		(start 19.954494 -316.584584)
		(end 19.954494 -372.220236)
		(width 0.127)
		(layer "In2.Cu")
		(net "T11_BLAD2_RXD")
	)
	(segment
		(start 84.596478 -450.875146)
		(end 84.596478 -449.0847)
		(width 0.127)
		(layer "In2.Cu")
		(net "T11_BLAD2_RXD")
	)
	(segment
		(start 85.363304 -451.641972)
		(end 84.596478 -450.875146)
		(width 0.127)
		(layer "In2.Cu")
		(net "T11_BLAD2_RXD")
	)
	(segment
		(start 46.009306 -446.836038)
		(end 39.924228 -440.75096)
		(width 0.127)
		(layer "In2.Cu")
		(net "T11_BLAD2_RXD")
	)
	(segment
		(start 27.465274 -379.731016)
		(end 27.465274 -437.590946)
		(width 0.127)
		(layer "In2.Cu")
		(net "T11_BLAD2_RXD")
	)
	(segment
		(start 86.597744 -450.96049)
		(end 85.916262 -451.641972)
		(width 0.127)
		(layer "In2.Cu")
		(net "T11_BLAD2_RXD")
	)
	(segment
		(start 85.916262 -451.641972)
		(end 85.363304 -451.641972)
		(width 0.127)
		(layer "In2.Cu")
		(net "T11_BLAD2_RXD")
	)
	(segment
		(start 87.891366 -451.739762)
		(end 87.112094 -450.96049)
		(width 0.127)
		(layer "In2.Cu")
		(net "T11_BLAD2_RXD")
	)
	(segment
		(start 87.112094 -450.96049)
		(end 86.597744 -450.96049)
		(width 0.127)
		(layer "In2.Cu")
		(net "T11_BLAD2_RXD")
	)
	(segment
		(start 89.929462 -451.15734)
		(end 89.036652 -451.15734)
		(width 0.127)
		(layer "In2.Cu")
		(net "T11_BLAD2_RXD")
	)
	(segment
		(start 39.924228 -440.75096)
		(end 39.670482 -440.75096)
		(width 0.127)
		(layer "In2.Cu")
		(net "T11_BLAD2_RXD")
	)
	(segment
		(start 84.596478 -449.0847)
		(end 82.347816 -446.836038)
		(width 0.127)
		(layer "In2.Cu")
		(net "T11_BLAD2_RXD")
	)
	(segment
		(start 88.45423 -451.739762)
		(end 87.891366 -451.739762)
		(width 0.127)
		(layer "In2.Cu")
		(net "T11_BLAD2_RXD")
	)
	(segment
		(start 82.347816 -446.836038)
		(end 46.009306 -446.836038)
		(width 0.127)
		(layer "In2.Cu")
		(net "T11_BLAD2_RXD")
	)
	(segment
		(start 13.039852 -309.669942)
		(end 19.954494 -316.584584)
		(width 0.127)
		(layer "In2.Cu")
		(net "T11_BLAD2_RXD")
	)
	(segment
		(start 8.449818 -309.669942)
		(end 13.039852 -309.669942)
		(width 0.127)
		(layer "In2.Cu")
		(net "T11_BLAD2_RXD")
	)
	(segment
		(start 24.735536 -251.895356)
		(end 24.927306 -251.703586)
		(width 0.1524)
		(layer "F.Cu")
		(net "I2C_PSU2_SDA")
	)
	(segment
		(start 7.18312 -252.481842)
		(end 7.769606 -251.895356)
		(width 0.1524)
		(layer "F.Cu")
		(net "I2C_PSU2_SDA")
	)
	(segment
		(start 3.948938 -251.670566)
		(end 4.760214 -252.481842)
		(width 0.1524)
		(layer "F.Cu")
		(net "I2C_PSU2_SDA")
	)
	(segment
		(start 7.769606 -251.895356)
		(end 24.735536 -251.895356)
		(width 0.1524)
		(layer "F.Cu")
		(net "I2C_PSU2_SDA")
	)
	(segment
		(start 4.760214 -252.481842)
		(end 7.18312 -252.481842)
		(width 0.1524)
		(layer "F.Cu")
		(net "I2C_PSU2_SDA")
	)
	(via
		(at 24.927306 -251.703586)
		(size 0.508)
		(drill 0.254)
		(layers "F.Cu" "B.Cu")
		(net "I2C_PSU2_SDA")
	)
	(segment
		(start 24.927306 -251.703586)
		(end 24.61006 -251.38634)
		(width 0.1524)
		(layer "B.Cu")
		(net "I2C_PSU2_SDA")
	)
	(segment
		(start 33.576768 -198.414386)
		(end 33.576768 -183.352948)
		(width 0.1524)
		(layer "B.Cu")
		(net "I2C_PSU2_SDA")
	)
	(segment
		(start 28.886912 -200.186036)
		(end 31.805118 -200.186036)
		(width 0.1524)
		(layer "B.Cu")
		(net "I2C_PSU2_SDA")
	)
	(segment
		(start 24.927306 -251.703586)
		(end 24.927306 -259.177536)
		(width 0.1524)
		(layer "B.Cu")
		(net "I2C_PSU2_SDA")
	)
	(segment
		(start 33.576768 -183.352948)
		(end 35.53968 -181.390036)
		(width 0.1524)
		(layer "B.Cu")
		(net "I2C_PSU2_SDA")
	)
	(segment
		(start 24.61006 -251.38634)
		(end 24.61006 -204.462888)
		(width 0.1524)
		(layer "B.Cu")
		(net "I2C_PSU2_SDA")
	)
	(segment
		(start 24.927306 -259.177536)
		(end 35.53968 -269.78991)
		(width 0.1524)
		(layer "B.Cu")
		(net "I2C_PSU2_SDA")
	)
	(segment
		(start 31.805118 -200.186036)
		(end 33.576768 -198.414386)
		(width 0.1524)
		(layer "B.Cu")
		(net "I2C_PSU2_SDA")
	)
	(segment
		(start 24.61006 -204.462888)
		(end 28.886912 -200.186036)
		(width 0.1524)
		(layer "B.Cu")
		(net "I2C_PSU2_SDA")
	)
	(via
		(at 85.27542 -445.33058)
		(size 0.508)
		(drill 0.254)
		(layers "F.Cu" "B.Cu")
		(net "T11_BLAD4_EN")
	)
	(segment
		(start 8.449818 -313.669934)
		(end 11.797284 -317.0174)
		(width 0.127)
		(layer "In5.Cu")
		(net "T11_BLAD4_EN")
	)
	(segment
		(start 18.72615 -333.902812)
		(end 18.72615 -334.271112)
		(width 0.127)
		(layer "In5.Cu")
		(net "T11_BLAD4_EN")
	)
	(segment
		(start 19.576796 -324.971918)
		(end 19.576796 -333.052166)
		(width 0.127)
		(layer "In5.Cu")
		(net "T11_BLAD4_EN")
	)
	(segment
		(start 27.099514 -438.71769)
		(end 32.754316 -444.372492)
		(width 0.127)
		(layer "In5.Cu")
		(net "T11_BLAD4_EN")
	)
	(segment
		(start 83.583272 -443.638432)
		(end 85.27542 -445.33058)
		(width 0.127)
		(layer "In5.Cu")
		(net "T11_BLAD4_EN")
	)
	(segment
		(start 19.898106 -351.458022)
		(end 19.898106 -373.12727)
		(width 0.127)
		(layer "In5.Cu")
		(net "T11_BLAD4_EN")
	)
	(segment
		(start 77.524356 -443.638432)
		(end 83.583272 -443.638432)
		(width 0.127)
		(layer "In5.Cu")
		(net "T11_BLAD4_EN")
	)
	(segment
		(start 27.099514 -380.328678)
		(end 27.099514 -438.71769)
		(width 0.127)
		(layer "In5.Cu")
		(net "T11_BLAD4_EN")
	)
	(segment
		(start 85.27542 -445.33058)
		(end 89.44991 -449.50507)
		(width 0.127)
		(layer "In5.Cu")
		(net "T11_BLAD4_EN")
	)
	(segment
		(start 19.898106 -373.12727)
		(end 27.099514 -380.328678)
		(width 0.127)
		(layer "In5.Cu")
		(net "T11_BLAD4_EN")
	)
	(segment
		(start 11.797284 -317.192406)
		(end 19.576796 -324.971918)
		(width 0.127)
		(layer "In5.Cu")
		(net "T11_BLAD4_EN")
	)
	(segment
		(start 19.576796 -335.121758)
		(end 19.576796 -351.136712)
		(width 0.127)
		(layer "In5.Cu")
		(net "T11_BLAD4_EN")
	)
	(segment
		(start 76.790296 -444.372492)
		(end 77.524356 -443.638432)
		(width 0.127)
		(layer "In5.Cu")
		(net "T11_BLAD4_EN")
	)
	(segment
		(start 19.576796 -351.136712)
		(end 19.898106 -351.458022)
		(width 0.127)
		(layer "In5.Cu")
		(net "T11_BLAD4_EN")
	)
	(segment
		(start 32.754316 -444.372492)
		(end 76.790296 -444.372492)
		(width 0.127)
		(layer "In5.Cu")
		(net "T11_BLAD4_EN")
	)
	(segment
		(start 18.72615 -334.271112)
		(end 19.576796 -335.121758)
		(width 0.127)
		(layer "In5.Cu")
		(net "T11_BLAD4_EN")
	)
	(segment
		(start 19.576796 -333.052166)
		(end 18.72615 -333.902812)
		(width 0.127)
		(layer "In5.Cu")
		(net "T11_BLAD4_EN")
	)
	(segment
		(start 11.797284 -317.0174)
		(end 11.797284 -317.192406)
		(width 0.127)
		(layer "In5.Cu")
		(net "T11_BLAD4_EN")
	)
	(via
		(at 87.652606 -14.27226)
		(size 0.508)
		(drill 0.254)
		(layers "F.Cu" "B.Cu")
		(net "T1_BLAD2_RXD")
	)
	(segment
		(start 81.355946 -55.571898)
		(end 76.260452 -60.667392)
		(width 0.127)
		(layer "In2.Cu")
		(net "T1_BLAD2_RXD")
	)
	(segment
		(start 17.094454 -178.90236)
		(end 17.094454 -197.637146)
		(width 0.127)
		(layer "In2.Cu")
		(net "T1_BLAD2_RXD")
	)
	(segment
		(start 82.800698 -55.571898)
		(end 81.355946 -55.571898)
		(width 0.127)
		(layer "In2.Cu")
		(net "T1_BLAD2_RXD")
	)
	(segment
		(start 87.652606 -14.27226)
		(end 87.652606 -14.73962)
		(width 0.127)
		(layer "In2.Cu")
		(net "T1_BLAD2_RXD")
	)
	(segment
		(start 29.379672 -88.000078)
		(end 23.898352 -93.481398)
		(width 0.127)
		(layer "In2.Cu")
		(net "T1_BLAD2_RXD")
	)
	(segment
		(start 25.608026 -170.388788)
		(end 17.094454 -178.90236)
		(width 0.127)
		(layer "In2.Cu")
		(net "T1_BLAD2_RXD")
	)
	(segment
		(start 84.499196 -53.8734)
		(end 82.800698 -55.571898)
		(width 0.127)
		(layer "In2.Cu")
		(net "T1_BLAD2_RXD")
	)
	(segment
		(start 25.774142 -104.5591)
		(end 25.774142 -107.366562)
		(width 0.127)
		(layer "In2.Cu")
		(net "T1_BLAD2_RXD")
	)
	(segment
		(start 87.652606 -14.73962)
		(end 85.551518 -16.840708)
		(width 0.127)
		(layer "In2.Cu")
		(net "T1_BLAD2_RXD")
	)
	(segment
		(start 90.772234 -7.54507)
		(end 87.652606 -10.664698)
		(width 0.127)
		(layer "In2.Cu")
		(net "T1_BLAD2_RXD")
	)
	(segment
		(start 25.774142 -107.366562)
		(end 26.34996 -107.94238)
		(width 0.127)
		(layer "In2.Cu")
		(net "T1_BLAD2_RXD")
	)
	(segment
		(start 84.499196 -50.292762)
		(end 84.499196 -53.8734)
		(width 0.127)
		(layer "In2.Cu")
		(net "T1_BLAD2_RXD")
	)
	(segment
		(start 85.551518 -49.24044)
		(end 84.499196 -50.292762)
		(width 0.127)
		(layer "In2.Cu")
		(net "T1_BLAD2_RXD")
	)
	(segment
		(start 23.898352 -93.481398)
		(end 23.898352 -102.68331)
		(width 0.127)
		(layer "In2.Cu")
		(net "T1_BLAD2_RXD")
	)
	(segment
		(start 91.98991 -7.54507)
		(end 90.772234 -7.54507)
		(width 0.127)
		(layer "In2.Cu")
		(net "T1_BLAD2_RXD")
	)
	(segment
		(start 76.260452 -60.667392)
		(end 76.260452 -64.009016)
		(width 0.127)
		(layer "In2.Cu")
		(net "T1_BLAD2_RXD")
	)
	(segment
		(start 8.2169 -223.902524)
		(end 6.448806 -225.670618)
		(width 0.127)
		(layer "In2.Cu")
		(net "T1_BLAD2_RXD")
	)
	(segment
		(start 87.652606 -10.664698)
		(end 87.652606 -14.27226)
		(width 0.127)
		(layer "In2.Cu")
		(net "T1_BLAD2_RXD")
	)
	(segment
		(start 26.34996 -108.469938)
		(end 25.608026 -109.211872)
		(width 0.127)
		(layer "In2.Cu")
		(net "T1_BLAD2_RXD")
	)
	(segment
		(start 25.608026 -109.211872)
		(end 25.608026 -170.388788)
		(width 0.127)
		(layer "In2.Cu")
		(net "T1_BLAD2_RXD")
	)
	(segment
		(start 76.260452 -64.009016)
		(end 52.26939 -88.000078)
		(width 0.127)
		(layer "In2.Cu")
		(net "T1_BLAD2_RXD")
	)
	(segment
		(start 26.34996 -107.94238)
		(end 26.34996 -108.469938)
		(width 0.127)
		(layer "In2.Cu")
		(net "T1_BLAD2_RXD")
	)
	(segment
		(start 85.551518 -16.840708)
		(end 85.551518 -49.24044)
		(width 0.127)
		(layer "In2.Cu")
		(net "T1_BLAD2_RXD")
	)
	(segment
		(start 52.26939 -88.000078)
		(end 29.379672 -88.000078)
		(width 0.127)
		(layer "In2.Cu")
		(net "T1_BLAD2_RXD")
	)
	(segment
		(start 17.094454 -197.637146)
		(end 10.529062 -204.202538)
		(width 0.127)
		(layer "In2.Cu")
		(net "T1_BLAD2_RXD")
	)
	(segment
		(start 10.529062 -204.202538)
		(end 10.529062 -222.507048)
		(width 0.127)
		(layer "In2.Cu")
		(net "T1_BLAD2_RXD")
	)
	(segment
		(start 23.898352 -102.68331)
		(end 25.774142 -104.5591)
		(width 0.127)
		(layer "In2.Cu")
		(net "T1_BLAD2_RXD")
	)
	(segment
		(start 9.133586 -223.902524)
		(end 8.2169 -223.902524)
		(width 0.127)
		(layer "In2.Cu")
		(net "T1_BLAD2_RXD")
	)
	(segment
		(start 10.529062 -222.507048)
		(end 9.133586 -223.902524)
		(width 0.127)
		(layer "In2.Cu")
		(net "T1_BLAD2_RXD")
	)
	(segment
		(start 39.090854 -370.890038)
		(end 39.71417 -371.513354)
		(width 0.1524)
		(layer "F.Cu")
		(net "PSU5_AD0")
	)
	(segment
		(start 35.53968 -370.890038)
		(end 39.090854 -370.890038)
		(width 0.1524)
		(layer "F.Cu")
		(net "PSU5_AD0")
	)
	(via
		(at 42.710354 -441.758832)
		(size 0.508)
		(drill 0.254)
		(layers "F.Cu" "B.Cu")
		(net "T11_BLAD3_TXD")
	)
	(segment
		(start 87.823802 -449.827904)
		(end 87.329772 -450.321934)
		(width 0.127)
		(layer "In2.Cu")
		(net "T11_BLAD3_TXD")
	)
	(segment
		(start 8.449818 -305.66995)
		(end 11.499342 -305.66995)
		(width 0.127)
		(layer "In2.Cu")
		(net "T11_BLAD3_TXD")
	)
	(segment
		(start 40.921686 -439.970164)
		(end 42.710354 -441.758832)
		(width 0.127)
		(layer "In2.Cu")
		(net "T11_BLAD3_TXD")
	)
	(segment
		(start 11.499342 -305.66995)
		(end 20.614894 -314.785502)
		(width 0.127)
		(layer "In2.Cu")
		(net "T11_BLAD3_TXD")
	)
	(segment
		(start 47.017686 -446.066164)
		(end 84.80425 -446.066164)
		(width 0.127)
		(layer "In2.Cu")
		(net "T11_BLAD3_TXD")
	)
	(segment
		(start 30.85973 -439.970164)
		(end 40.921686 -439.970164)
		(width 0.127)
		(layer "In2.Cu")
		(net "T11_BLAD3_TXD")
	)
	(segment
		(start 20.614894 -371.854222)
		(end 28.222194 -379.461522)
		(width 0.127)
		(layer "In2.Cu")
		(net "T11_BLAD3_TXD")
	)
	(segment
		(start 28.222194 -379.461522)
		(end 28.222194 -437.332628)
		(width 0.127)
		(layer "In2.Cu")
		(net "T11_BLAD3_TXD")
	)
	(segment
		(start 42.710354 -441.758832)
		(end 47.017686 -446.066164)
		(width 0.127)
		(layer "In2.Cu")
		(net "T11_BLAD3_TXD")
	)
	(segment
		(start 20.614894 -314.785502)
		(end 20.614894 -371.854222)
		(width 0.127)
		(layer "In2.Cu")
		(net "T11_BLAD3_TXD")
	)
	(segment
		(start 86.093046 -450.321934)
		(end 85.63991 -450.77507)
		(width 0.127)
		(layer "In2.Cu")
		(net "T11_BLAD3_TXD")
	)
	(segment
		(start 87.823802 -449.085716)
		(end 87.823802 -449.827904)
		(width 0.127)
		(layer "In2.Cu")
		(net "T11_BLAD3_TXD")
	)
	(segment
		(start 84.80425 -446.066164)
		(end 87.823802 -449.085716)
		(width 0.127)
		(layer "In2.Cu")
		(net "T11_BLAD3_TXD")
	)
	(segment
		(start 28.222194 -437.332628)
		(end 30.85973 -439.970164)
		(width 0.127)
		(layer "In2.Cu")
		(net "T11_BLAD3_TXD")
	)
	(segment
		(start 87.329772 -450.321934)
		(end 86.093046 -450.321934)
		(width 0.127)
		(layer "In2.Cu")
		(net "T11_BLAD3_TXD")
	)
	(via
		(at 88.465406 -12.919202)
		(size 0.508)
		(drill 0.254)
		(layers "F.Cu" "B.Cu")
		(net "T1_BLAD2_TXD")
	)
	(segment
		(start 8.448802 -224.67062)
		(end 8.928862 -224.67062)
		(width 0.127)
		(layer "In2.Cu")
		(net "T1_BLAD2_TXD")
	)
	(segment
		(start 85.881718 -17.049496)
		(end 88.465406 -14.465808)
		(width 0.127)
		(layer "In2.Cu")
		(net "T1_BLAD2_TXD")
	)
	(segment
		(start 29.559504 -88.433656)
		(end 52.449222 -88.433656)
		(width 0.127)
		(layer "In2.Cu")
		(net "T1_BLAD2_TXD")
	)
	(segment
		(start 84.829396 -50.429668)
		(end 85.881718 -49.377346)
		(width 0.127)
		(layer "In2.Cu")
		(net "T1_BLAD2_TXD")
	)
	(segment
		(start 85.881718 -49.377346)
		(end 85.881718 -17.049496)
		(width 0.127)
		(layer "In2.Cu")
		(net "T1_BLAD2_TXD")
	)
	(segment
		(start 26.68016 -108.627672)
		(end 26.68016 -107.805474)
		(width 0.127)
		(layer "In2.Cu")
		(net "T1_BLAD2_TXD")
	)
	(segment
		(start 88.465406 -12.919202)
		(end 88.465406 -11.069574)
		(width 0.127)
		(layer "In2.Cu")
		(net "T1_BLAD2_TXD")
	)
	(segment
		(start 17.528032 -197.670928)
		(end 17.528032 -178.969924)
		(width 0.127)
		(layer "In2.Cu")
		(net "T1_BLAD2_TXD")
	)
	(segment
		(start 26.104342 -107.229656)
		(end 26.104342 -104.422194)
		(width 0.127)
		(layer "In2.Cu")
		(net "T1_BLAD2_TXD")
	)
	(segment
		(start 24.273002 -93.720158)
		(end 29.559504 -88.433656)
		(width 0.127)
		(layer "In2.Cu")
		(net "T1_BLAD2_TXD")
	)
	(segment
		(start 17.528032 -178.969924)
		(end 25.961594 -170.536362)
		(width 0.127)
		(layer "In2.Cu")
		(net "T1_BLAD2_TXD")
	)
	(segment
		(start 82.907632 -55.93207)
		(end 84.829396 -54.010306)
		(width 0.127)
		(layer "In2.Cu")
		(net "T1_BLAD2_TXD")
	)
	(segment
		(start 84.829396 -54.010306)
		(end 84.829396 -50.429668)
		(width 0.127)
		(layer "In2.Cu")
		(net "T1_BLAD2_TXD")
	)
	(segment
		(start 81.609184 -55.93207)
		(end 82.907632 -55.93207)
		(width 0.127)
		(layer "In2.Cu")
		(net "T1_BLAD2_TXD")
	)
	(segment
		(start 52.449222 -88.433656)
		(end 76.69403 -64.188848)
		(width 0.127)
		(layer "In2.Cu")
		(net "T1_BLAD2_TXD")
	)
	(segment
		(start 25.961594 -170.536362)
		(end 25.961594 -109.346238)
		(width 0.127)
		(layer "In2.Cu")
		(net "T1_BLAD2_TXD")
	)
	(segment
		(start 76.69403 -64.188848)
		(end 76.69403 -60.847224)
		(width 0.127)
		(layer "In2.Cu")
		(net "T1_BLAD2_TXD")
	)
	(segment
		(start 88.465406 -11.069574)
		(end 90.71991 -8.81507)
		(width 0.127)
		(layer "In2.Cu")
		(net "T1_BLAD2_TXD")
	)
	(segment
		(start 76.69403 -60.847224)
		(end 81.609184 -55.93207)
		(width 0.127)
		(layer "In2.Cu")
		(net "T1_BLAD2_TXD")
	)
	(segment
		(start 24.273002 -102.590854)
		(end 24.273002 -93.720158)
		(width 0.127)
		(layer "In2.Cu")
		(net "T1_BLAD2_TXD")
	)
	(segment
		(start 26.68016 -107.805474)
		(end 26.104342 -107.229656)
		(width 0.127)
		(layer "In2.Cu")
		(net "T1_BLAD2_TXD")
	)
	(segment
		(start 25.961594 -109.346238)
		(end 26.68016 -108.627672)
		(width 0.127)
		(layer "In2.Cu")
		(net "T1_BLAD2_TXD")
	)
	(segment
		(start 8.928862 -224.67062)
		(end 10.85977 -222.739712)
		(width 0.127)
		(layer "In2.Cu")
		(net "T1_BLAD2_TXD")
	)
	(segment
		(start 88.465406 -14.465808)
		(end 88.465406 -12.919202)
		(width 0.127)
		(layer "In2.Cu")
		(net "T1_BLAD2_TXD")
	)
	(segment
		(start 10.85977 -222.739712)
		(end 10.85977 -204.33919)
		(width 0.127)
		(layer "In2.Cu")
		(net "T1_BLAD2_TXD")
	)
	(segment
		(start 26.104342 -104.422194)
		(end 24.273002 -102.590854)
		(width 0.127)
		(layer "In2.Cu")
		(net "T1_BLAD2_TXD")
	)
	(segment
		(start 10.85977 -204.33919)
		(end 17.528032 -197.670928)
		(width 0.127)
		(layer "In2.Cu")
		(net "T1_BLAD2_TXD")
	)
	(via
		(at 12.558014 -314.696348)
		(size 0.508)
		(drill 0.254)
		(layers "F.Cu" "B.Cu")
		(net "T11_BLAD2_TXD")
	)
	(segment
		(start 12.558014 -314.696348)
		(end 10.721594 -312.859928)
		(width 0.127)
		(layer "In2.Cu")
		(net "T11_BLAD2_TXD")
	)
	(segment
		(start 10.721594 -312.859928)
		(end 7.64794 -312.859928)
		(width 0.127)
		(layer "In2.Cu")
		(net "T11_BLAD2_TXD")
	)
	(segment
		(start 26.360628 -380.421896)
		(end 26.360628 -438.19318)
		(width 0.127)
		(layer "In2.Cu")
		(net "T11_BLAD2_TXD")
	)
	(segment
		(start 17.670272 -323.248274)
		(end 17.670272 -371.73154)
		(width 0.127)
		(layer "In2.Cu")
		(net "T11_BLAD2_TXD")
	)
	(segment
		(start 85.416136 -454.500234)
		(end 88.521794 -454.500234)
		(width 0.127)
		(layer "In2.Cu")
		(net "T11_BLAD2_TXD")
	)
	(segment
		(start 44.816014 -448.25158)
		(end 81.857342 -448.25158)
		(width 0.127)
		(layer "In2.Cu")
		(net "T11_BLAD2_TXD")
	)
	(segment
		(start 15.673832 -321.251834)
		(end 17.670272 -323.248274)
		(width 0.127)
		(layer "In2.Cu")
		(net "T11_BLAD2_TXD")
	)
	(segment
		(start 5.708142 -310.92013)
		(end 5.708142 -309.411624)
		(width 0.127)
		(layer "In2.Cu")
		(net "T11_BLAD2_TXD")
	)
	(segment
		(start 7.64794 -312.859928)
		(end 5.708142 -310.92013)
		(width 0.127)
		(layer "In2.Cu")
		(net "T11_BLAD2_TXD")
	)
	(segment
		(start 12.558014 -314.696348)
		(end 15.673832 -317.812166)
		(width 0.127)
		(layer "In2.Cu")
		(net "T11_BLAD2_TXD")
	)
	(segment
		(start 89.706958 -453.31507)
		(end 90.71991 -453.31507)
		(width 0.127)
		(layer "In2.Cu")
		(net "T11_BLAD2_TXD")
	)
	(segment
		(start 39.308786 -442.744352)
		(end 44.816014 -448.25158)
		(width 0.127)
		(layer "In2.Cu")
		(net "T11_BLAD2_TXD")
	)
	(segment
		(start 81.857342 -448.25158)
		(end 83.330288 -449.724526)
		(width 0.127)
		(layer "In2.Cu")
		(net "T11_BLAD2_TXD")
	)
	(segment
		(start 83.330288 -449.724526)
		(end 83.330288 -452.414386)
		(width 0.127)
		(layer "In2.Cu")
		(net "T11_BLAD2_TXD")
	)
	(segment
		(start 5.708142 -309.411624)
		(end 6.449822 -308.669944)
		(width 0.127)
		(layer "In2.Cu")
		(net "T11_BLAD2_TXD")
	)
	(segment
		(start 88.521794 -454.500234)
		(end 89.706958 -453.31507)
		(width 0.127)
		(layer "In2.Cu")
		(net "T11_BLAD2_TXD")
	)
	(segment
		(start 26.360628 -438.19318)
		(end 30.9118 -442.744352)
		(width 0.127)
		(layer "In2.Cu")
		(net "T11_BLAD2_TXD")
	)
	(segment
		(start 15.673832 -317.812166)
		(end 15.673832 -321.251834)
		(width 0.127)
		(layer "In2.Cu")
		(net "T11_BLAD2_TXD")
	)
	(segment
		(start 83.330288 -452.414386)
		(end 85.416136 -454.500234)
		(width 0.127)
		(layer "In2.Cu")
		(net "T11_BLAD2_TXD")
	)
	(segment
		(start 30.9118 -442.744352)
		(end 39.308786 -442.744352)
		(width 0.127)
		(layer "In2.Cu")
		(net "T11_BLAD2_TXD")
	)
	(segment
		(start 17.670272 -371.73154)
		(end 26.360628 -380.421896)
		(width 0.127)
		(layer "In2.Cu")
		(net "T11_BLAD2_TXD")
	)
	(via
		(at 81.605882 -445.380364)
		(size 0.508)
		(drill 0.254)
		(layers "F.Cu" "B.Cu")
		(net "T11_BLAD2_EN")
	)
	(segment
		(start 77.9272 -445.117728)
		(end 78.326488 -444.71844)
		(width 0.127)
		(layer "In5.Cu")
		(net "T11_BLAD2_EN")
	)
	(segment
		(start 81.605882 -445.380364)
		(end 88.270588 -452.04507)
		(width 0.127)
		(layer "In5.Cu")
		(net "T11_BLAD2_EN")
	)
	(segment
		(start 9.015984 -316.236096)
		(end 9.260332 -316.236096)
		(width 0.127)
		(layer "In5.Cu")
		(net "T11_BLAD2_EN")
	)
	(segment
		(start 88.270588 -452.04507)
		(end 89.44991 -452.04507)
		(width 0.127)
		(layer "In5.Cu")
		(net "T11_BLAD2_EN")
	)
	(segment
		(start 26.300938 -380.647956)
		(end 26.300938 -439.048652)
		(width 0.127)
		(layer "In5.Cu")
		(net "T11_BLAD2_EN")
	)
	(segment
		(start 16.16456 -370.511578)
		(end 26.300938 -380.647956)
		(width 0.127)
		(layer "In5.Cu")
		(net "T11_BLAD2_EN")
	)
	(segment
		(start 15.367508 -329.855576)
		(end 16.16456 -330.652628)
		(width 0.127)
		(layer "In5.Cu")
		(net "T11_BLAD2_EN")
	)
	(segment
		(start 80.943958 -444.71844)
		(end 81.605882 -445.380364)
		(width 0.127)
		(layer "In5.Cu")
		(net "T11_BLAD2_EN")
	)
	(segment
		(start 9.260332 -316.236096)
		(end 15.367508 -322.343272)
		(width 0.127)
		(layer "In5.Cu")
		(net "T11_BLAD2_EN")
	)
	(segment
		(start 8.449818 -315.66993)
		(end 9.015984 -316.236096)
		(width 0.127)
		(layer "In5.Cu")
		(net "T11_BLAD2_EN")
	)
	(segment
		(start 26.300938 -439.048652)
		(end 32.370014 -445.117728)
		(width 0.127)
		(layer "In5.Cu")
		(net "T11_BLAD2_EN")
	)
	(segment
		(start 78.326488 -444.71844)
		(end 80.943958 -444.71844)
		(width 0.127)
		(layer "In5.Cu")
		(net "T11_BLAD2_EN")
	)
	(segment
		(start 16.16456 -330.652628)
		(end 16.16456 -370.511578)
		(width 0.127)
		(layer "In5.Cu")
		(net "T11_BLAD2_EN")
	)
	(segment
		(start 32.370014 -445.117728)
		(end 77.9272 -445.117728)
		(width 0.127)
		(layer "In5.Cu")
		(net "T11_BLAD2_EN")
	)
	(segment
		(start 15.367508 -322.343272)
		(end 15.367508 -329.855576)
		(width 0.127)
		(layer "In5.Cu")
		(net "T11_BLAD2_EN")
	)
	(via
		(at 36.799012 -441.670694)
		(size 0.508)
		(drill 0.254)
		(layers "F.Cu" "B.Cu")
		(net "T11_BLAD1_TXD")
	)
	(segment
		(start 30.403038 -441.670694)
		(end 36.799012 -441.670694)
		(width 0.127)
		(layer "In2.Cu")
		(net "T11_BLAD1_TXD")
	)
	(segment
		(start 45.124116 -447.683128)
		(end 39.111682 -441.670694)
		(width 0.127)
		(layer "In2.Cu")
		(net "T11_BLAD1_TXD")
	)
	(segment
		(start 18.72615 -323.547232)
		(end 18.72615 -372.296436)
		(width 0.127)
		(layer "In2.Cu")
		(net "T11_BLAD1_TXD")
	)
	(segment
		(start 83.688682 -451.363842)
		(end 83.688682 -449.435982)
		(width 0.127)
		(layer "In2.Cu")
		(net "T11_BLAD1_TXD")
	)
	(segment
		(start 26.759916 -380.330202)
		(end 26.759916 -438.027572)
		(width 0.127)
		(layer "In2.Cu")
		(net "T11_BLAD1_TXD")
	)
	(segment
		(start 83.688682 -449.435982)
		(end 81.935828 -447.683128)
		(width 0.127)
		(layer "In2.Cu")
		(net "T11_BLAD1_TXD")
	)
	(segment
		(start 18.72615 -372.296436)
		(end 26.759916 -380.330202)
		(width 0.127)
		(layer "In2.Cu")
		(net "T11_BLAD1_TXD")
	)
	(segment
		(start 85.63991 -453.31507)
		(end 83.688682 -451.363842)
		(width 0.127)
		(layer "In2.Cu")
		(net "T11_BLAD1_TXD")
	)
	(segment
		(start 6.449822 -310.66994)
		(end 8.26135 -312.481468)
		(width 0.127)
		(layer "In2.Cu")
		(net "T11_BLAD1_TXD")
	)
	(segment
		(start 16.20901 -317.718694)
		(end 16.20901 -321.030092)
		(width 0.127)
		(layer "In2.Cu")
		(net "T11_BLAD1_TXD")
	)
	(segment
		(start 8.26135 -312.481468)
		(end 10.971784 -312.481468)
		(width 0.127)
		(layer "In2.Cu")
		(net "T11_BLAD1_TXD")
	)
	(segment
		(start 26.759916 -438.027572)
		(end 30.403038 -441.670694)
		(width 0.127)
		(layer "In2.Cu")
		(net "T11_BLAD1_TXD")
	)
	(segment
		(start 81.935828 -447.683128)
		(end 45.124116 -447.683128)
		(width 0.127)
		(layer "In2.Cu")
		(net "T11_BLAD1_TXD")
	)
	(segment
		(start 39.111682 -441.670694)
		(end 36.799012 -441.670694)
		(width 0.127)
		(layer "In2.Cu")
		(net "T11_BLAD1_TXD")
	)
	(segment
		(start 16.20901 -321.030092)
		(end 18.72615 -323.547232)
		(width 0.127)
		(layer "In2.Cu")
		(net "T11_BLAD1_TXD")
	)
	(segment
		(start 10.971784 -312.481468)
		(end 16.20901 -317.718694)
		(width 0.127)
		(layer "In2.Cu")
		(net "T11_BLAD1_TXD")
	)
	(segment
		(start 8.448802 -218.670632)
		(end 10.184638 -218.670632)
		(width 0.1524)
		(layer "F.Cu")
		(net "T1_BLAD1_RXD")
	)
	(segment
		(start 10.184638 -218.670632)
		(end 12.310618 -220.796612)
		(width 0.1524)
		(layer "F.Cu")
		(net "T1_BLAD1_RXD")
	)
	(via
		(at 12.310618 -220.796612)
		(size 0.508)
		(drill 0.254)
		(layers "F.Cu" "B.Cu")
		(net "T1_BLAD1_RXD")
	)
	(via
		(at 98.431096 -19.519138)
		(size 0.508)
		(drill 0.254)
		(layers "F.Cu" "B.Cu")
		(net "T1_BLAD1_RXD")
	)
	(segment
		(start 12.310618 -220.796612)
		(end 12.82065 -220.796612)
		(width 0.127)
		(layer "In5.Cu")
		(net "T1_BLAD1_RXD")
	)
	(segment
		(start 77.00518 -67.477894)
		(end 79.368142 -67.477894)
		(width 0.127)
		(layer "In5.Cu")
		(net "T1_BLAD1_RXD")
	)
	(segment
		(start 93.601032 -57.953148)
		(end 99.991672 -51.562508)
		(width 0.127)
		(layer "In5.Cu")
		(net "T1_BLAD1_RXD")
	)
	(segment
		(start 54.953408 -89.529666)
		(end 77.00518 -67.477894)
		(width 0.127)
		(layer "In5.Cu")
		(net "T1_BLAD1_RXD")
	)
	(segment
		(start 21.7043 -108.770674)
		(end 21.7043 -94.45371)
		(width 0.127)
		(layer "In5.Cu")
		(net "T1_BLAD1_RXD")
	)
	(segment
		(start 17.830546 -178.567842)
		(end 27.180794 -169.217594)
		(width 0.127)
		(layer "In5.Cu")
		(net "T1_BLAD1_RXD")
	)
	(segment
		(start 27.180794 -114.247168)
		(end 21.7043 -108.770674)
		(width 0.127)
		(layer "In5.Cu")
		(net "T1_BLAD1_RXD")
	)
	(segment
		(start 88.242394 -10.708132)
		(end 89.62009 -10.708132)
		(width 0.127)
		(layer "In5.Cu")
		(net "T1_BLAD1_RXD")
	)
	(segment
		(start 27.180794 -169.217594)
		(end 27.180794 -114.247168)
		(width 0.127)
		(layer "In5.Cu")
		(net "T1_BLAD1_RXD")
	)
	(segment
		(start 21.7043 -94.45371)
		(end 26.628344 -89.529666)
		(width 0.127)
		(layer "In5.Cu")
		(net "T1_BLAD1_RXD")
	)
	(segment
		(start 99.991672 -21.079714)
		(end 98.431096 -19.519138)
		(width 0.127)
		(layer "In5.Cu")
		(net "T1_BLAD1_RXD")
	)
	(segment
		(start 86.90991 -9.375648)
		(end 88.242394 -10.708132)
		(width 0.127)
		(layer "In5.Cu")
		(net "T1_BLAD1_RXD")
	)
	(segment
		(start 12.82065 -220.796612)
		(end 22.36978 -211.247482)
		(width 0.127)
		(layer "In5.Cu")
		(net "T1_BLAD1_RXD")
	)
	(segment
		(start 88.892888 -57.953148)
		(end 93.601032 -57.953148)
		(width 0.127)
		(layer "In5.Cu")
		(net "T1_BLAD1_RXD")
	)
	(segment
		(start 22.36978 -211.247482)
		(end 22.36978 -203.198984)
		(width 0.127)
		(layer "In5.Cu")
		(net "T1_BLAD1_RXD")
	)
	(segment
		(start 26.628344 -89.529666)
		(end 54.953408 -89.529666)
		(width 0.127)
		(layer "In5.Cu")
		(net "T1_BLAD1_RXD")
	)
	(segment
		(start 99.991672 -51.562508)
		(end 99.991672 -21.079714)
		(width 0.127)
		(layer "In5.Cu")
		(net "T1_BLAD1_RXD")
	)
	(segment
		(start 79.368142 -67.477894)
		(end 88.892888 -57.953148)
		(width 0.127)
		(layer "In5.Cu")
		(net "T1_BLAD1_RXD")
	)
	(segment
		(start 17.830546 -198.65975)
		(end 17.830546 -178.567842)
		(width 0.127)
		(layer "In5.Cu")
		(net "T1_BLAD1_RXD")
	)
	(segment
		(start 89.62009 -10.708132)
		(end 98.431096 -19.519138)
		(width 0.127)
		(layer "In5.Cu")
		(net "T1_BLAD1_RXD")
	)
	(segment
		(start 22.36978 -203.198984)
		(end 17.830546 -198.65975)
		(width 0.127)
		(layer "In5.Cu")
		(net "T1_BLAD1_RXD")
	)
	(segment
		(start 86.90991 -7.54507)
		(end 86.90991 -9.375648)
		(width 0.127)
		(layer "In5.Cu")
		(net "T1_BLAD1_RXD")
	)
	(via
		(at 44.042076 -440.956954)
		(size 0.508)
		(drill 0.254)
		(layers "F.Cu" "B.Cu")
		(net "T11_BLAD4_TXD")
	)
	(segment
		(start 28.936442 -379.138942)
		(end 28.936442 -437.013096)
		(width 0.127)
		(layer "In2.Cu")
		(net "T11_BLAD4_TXD")
	)
	(segment
		(start 8.449818 -303.669954)
		(end 11.028426 -303.669954)
		(width 0.127)
		(layer "In2.Cu")
		(net "T11_BLAD4_TXD")
	)
	(segment
		(start 91.95562 -450.77507)
		(end 92.938346 -449.792344)
		(width 0.127)
		(layer "In2.Cu")
		(net "T11_BLAD4_TXD")
	)
	(segment
		(start 90.71991 -450.77507)
		(end 91.95562 -450.77507)
		(width 0.127)
		(layer "In2.Cu")
		(net "T11_BLAD4_TXD")
	)
	(segment
		(start 92.938346 -449.792344)
		(end 92.938346 -449.313554)
		(width 0.127)
		(layer "In2.Cu")
		(net "T11_BLAD4_TXD")
	)
	(segment
		(start 87.241634 -443.616842)
		(end 46.701964 -443.616842)
		(width 0.127)
		(layer "In2.Cu")
		(net "T11_BLAD4_TXD")
	)
	(segment
		(start 92.938346 -449.313554)
		(end 87.241634 -443.616842)
		(width 0.127)
		(layer "In2.Cu")
		(net "T11_BLAD4_TXD")
	)
	(segment
		(start 21.275294 -313.916822)
		(end 21.275294 -371.477794)
		(width 0.127)
		(layer "In2.Cu")
		(net "T11_BLAD4_TXD")
	)
	(segment
		(start 31.163514 -439.240168)
		(end 42.32529 -439.240168)
		(width 0.127)
		(layer "In2.Cu")
		(net "T11_BLAD4_TXD")
	)
	(segment
		(start 46.701964 -443.616842)
		(end 44.042076 -440.956954)
		(width 0.127)
		(layer "In2.Cu")
		(net "T11_BLAD4_TXD")
	)
	(segment
		(start 28.936442 -437.013096)
		(end 31.163514 -439.240168)
		(width 0.127)
		(layer "In2.Cu")
		(net "T11_BLAD4_TXD")
	)
	(segment
		(start 11.028426 -303.669954)
		(end 21.275294 -313.916822)
		(width 0.127)
		(layer "In2.Cu")
		(net "T11_BLAD4_TXD")
	)
	(segment
		(start 42.32529 -439.240168)
		(end 44.042076 -440.956954)
		(width 0.127)
		(layer "In2.Cu")
		(net "T11_BLAD4_TXD")
	)
	(segment
		(start 21.275294 -371.477794)
		(end 28.936442 -379.138942)
		(width 0.127)
		(layer "In2.Cu")
		(net "T11_BLAD4_TXD")
	)
	(segment
		(start 12.301982 -220.009466)
		(end 10.106914 -217.814398)
		(width 0.1524)
		(layer "F.Cu")
		(net "T1_BLAD1_TXD")
	)
	(segment
		(start 10.106914 -217.814398)
		(end 6.59257 -217.814398)
		(width 0.1524)
		(layer "F.Cu")
		(net "T1_BLAD1_TXD")
	)
	(segment
		(start 6.59257 -217.814398)
		(end 6.448806 -217.670634)
		(width 0.1524)
		(layer "F.Cu")
		(net "T1_BLAD1_TXD")
	)
	(via
		(at 12.301982 -220.009466)
		(size 0.508)
		(drill 0.254)
		(layers "F.Cu" "B.Cu")
		(net "T1_BLAD1_TXD")
	)
	(via
		(at 91.422474 -13.256006)
		(size 0.508)
		(drill 0.254)
		(layers "F.Cu" "B.Cu")
		(net "T1_BLAD1_TXD")
	)
	(segment
		(start 21.364956 -94.230444)
		(end 26.429716 -89.165684)
		(width 0.127)
		(layer "In5.Cu")
		(net "T1_BLAD1_TXD")
	)
	(segment
		(start 76.762864 -67.140836)
		(end 78.925928 -67.140836)
		(width 0.127)
		(layer "In5.Cu")
		(net "T1_BLAD1_TXD")
	)
	(segment
		(start 21.364956 -109.084872)
		(end 21.364956 -94.230444)
		(width 0.127)
		(layer "In5.Cu")
		(net "T1_BLAD1_TXD")
	)
	(segment
		(start 87.950294 -11.125454)
		(end 89.291922 -11.125454)
		(width 0.127)
		(layer "In5.Cu")
		(net "T1_BLAD1_TXD")
	)
	(segment
		(start 26.82494 -114.544856)
		(end 21.364956 -109.084872)
		(width 0.127)
		(layer "In5.Cu")
		(net "T1_BLAD1_TXD")
	)
	(segment
		(start 82.743548 -63.323216)
		(end 82.743548 -62.464442)
		(width 0.127)
		(layer "In5.Cu")
		(net "T1_BLAD1_TXD")
	)
	(segment
		(start 21.990558 -211.08035)
		(end 21.990558 -203.445872)
		(width 0.127)
		(layer "In5.Cu")
		(net "T1_BLAD1_TXD")
	)
	(segment
		(start 89.291922 -11.125454)
		(end 91.422474 -13.256006)
		(width 0.127)
		(layer "In5.Cu")
		(net "T1_BLAD1_TXD")
	)
	(segment
		(start 93.485462 -57.472834)
		(end 99.62769 -51.330606)
		(width 0.127)
		(layer "In5.Cu")
		(net "T1_BLAD1_TXD")
	)
	(segment
		(start 13.061442 -220.009466)
		(end 21.990558 -211.08035)
		(width 0.127)
		(layer "In5.Cu")
		(net "T1_BLAD1_TXD")
	)
	(segment
		(start 17.441418 -178.311302)
		(end 26.82494 -168.92778)
		(width 0.127)
		(layer "In5.Cu")
		(net "T1_BLAD1_TXD")
	)
	(segment
		(start 26.82494 -168.92778)
		(end 26.82494 -114.544856)
		(width 0.127)
		(layer "In5.Cu")
		(net "T1_BLAD1_TXD")
	)
	(segment
		(start 99.62769 -51.330606)
		(end 99.62769 -21.461222)
		(width 0.127)
		(layer "In5.Cu")
		(net "T1_BLAD1_TXD")
	)
	(segment
		(start 87.735156 -57.472834)
		(end 93.485462 -57.472834)
		(width 0.127)
		(layer "In5.Cu")
		(net "T1_BLAD1_TXD")
	)
	(segment
		(start 12.301982 -220.009466)
		(end 13.061442 -220.009466)
		(width 0.127)
		(layer "In5.Cu")
		(net "T1_BLAD1_TXD")
	)
	(segment
		(start 99.62769 -21.461222)
		(end 91.422474 -13.256006)
		(width 0.127)
		(layer "In5.Cu")
		(net "T1_BLAD1_TXD")
	)
	(segment
		(start 17.441418 -198.896732)
		(end 17.441418 -178.311302)
		(width 0.127)
		(layer "In5.Cu")
		(net "T1_BLAD1_TXD")
	)
	(segment
		(start 85.63991 -8.81507)
		(end 87.950294 -11.125454)
		(width 0.127)
		(layer "In5.Cu")
		(net "T1_BLAD1_TXD")
	)
	(segment
		(start 54.738016 -89.165684)
		(end 76.762864 -67.140836)
		(width 0.127)
		(layer "In5.Cu")
		(net "T1_BLAD1_TXD")
	)
	(segment
		(start 26.429716 -89.165684)
		(end 54.738016 -89.165684)
		(width 0.127)
		(layer "In5.Cu")
		(net "T1_BLAD1_TXD")
	)
	(segment
		(start 78.925928 -67.140836)
		(end 82.743548 -63.323216)
		(width 0.127)
		(layer "In5.Cu")
		(net "T1_BLAD1_TXD")
	)
	(segment
		(start 82.743548 -62.464442)
		(end 87.735156 -57.472834)
		(width 0.127)
		(layer "In5.Cu")
		(net "T1_BLAD1_TXD")
	)
	(segment
		(start 21.990558 -203.445872)
		(end 17.441418 -198.896732)
		(width 0.127)
		(layer "In5.Cu")
		(net "T1_BLAD1_TXD")
	)
	(via
		(at 83.791298 -445.028574)
		(size 0.508)
		(drill 0.254)
		(layers "F.Cu" "B.Cu")
		(net "T11_BLAD3_EN")
	)
	(segment
		(start 32.58185 -444.77051)
		(end 77.290676 -444.77051)
		(width 0.127)
		(layer "In5.Cu")
		(net "T11_BLAD3_EN")
	)
	(segment
		(start 16.49476 -322.56984)
		(end 16.49476 -370.294408)
		(width 0.127)
		(layer "In5.Cu")
		(net "T11_BLAD3_EN")
	)
	(segment
		(start 8.855964 -314.669932)
		(end 11.016996 -316.830964)
		(width 0.127)
		(layer "In5.Cu")
		(net "T11_BLAD3_EN")
	)
	(segment
		(start 88.17991 -449.417186)
		(end 88.17991 -450.77507)
		(width 0.127)
		(layer "In5.Cu")
		(net "T11_BLAD3_EN")
	)
	(segment
		(start 6.449822 -314.669932)
		(end 8.855964 -314.669932)
		(width 0.127)
		(layer "In5.Cu")
		(net "T11_BLAD3_EN")
	)
	(segment
		(start 82.775298 -444.012574)
		(end 83.791298 -445.028574)
		(width 0.127)
		(layer "In5.Cu")
		(net "T11_BLAD3_EN")
	)
	(segment
		(start 78.048612 -444.012574)
		(end 82.775298 -444.012574)
		(width 0.127)
		(layer "In5.Cu")
		(net "T11_BLAD3_EN")
	)
	(segment
		(start 83.791298 -445.028574)
		(end 88.17991 -449.417186)
		(width 0.127)
		(layer "In5.Cu")
		(net "T11_BLAD3_EN")
	)
	(segment
		(start 11.016996 -317.092076)
		(end 16.49476 -322.56984)
		(width 0.127)
		(layer "In5.Cu")
		(net "T11_BLAD3_EN")
	)
	(segment
		(start 77.290676 -444.77051)
		(end 78.048612 -444.012574)
		(width 0.127)
		(layer "In5.Cu")
		(net "T11_BLAD3_EN")
	)
	(segment
		(start 11.016996 -316.830964)
		(end 11.016996 -317.092076)
		(width 0.127)
		(layer "In5.Cu")
		(net "T11_BLAD3_EN")
	)
	(segment
		(start 26.696162 -380.49581)
		(end 26.696162 -438.884822)
		(width 0.127)
		(layer "In5.Cu")
		(net "T11_BLAD3_EN")
	)
	(segment
		(start 26.696162 -438.884822)
		(end 32.58185 -444.77051)
		(width 0.127)
		(layer "In5.Cu")
		(net "T11_BLAD3_EN")
	)
	(segment
		(start 16.49476 -370.294408)
		(end 26.696162 -380.49581)
		(width 0.127)
		(layer "In5.Cu")
		(net "T11_BLAD3_EN")
	)
	(via
		(at 79.130906 -445.388746)
		(size 0.508)
		(drill 0.254)
		(layers "F.Cu" "B.Cu")
		(net "T11_BLAD1_EN")
	)
	(segment
		(start 14.735302 -369.626388)
		(end 25.92451 -380.815596)
		(width 0.127)
		(layer "In5.Cu")
		(net "T11_BLAD1_EN")
	)
	(segment
		(start 14.958822 -331.601318)
		(end 14.958822 -332.942692)
		(width 0.127)
		(layer "In5.Cu")
		(net "T11_BLAD1_EN")
	)
	(segment
		(start 14.958822 -332.942692)
		(end 14.735302 -333.166212)
		(width 0.127)
		(layer "In5.Cu")
		(net "T11_BLAD1_EN")
	)
	(segment
		(start 78.966822 -445.55283)
		(end 79.130906 -445.388746)
		(width 0.127)
		(layer "In5.Cu")
		(net "T11_BLAD1_EN")
	)
	(segment
		(start 87.05723 -453.31507)
		(end 88.17991 -453.31507)
		(width 0.127)
		(layer "In5.Cu")
		(net "T11_BLAD1_EN")
	)
	(segment
		(start 9.129522 -316.669928)
		(end 14.298422 -321.838828)
		(width 0.127)
		(layer "In5.Cu")
		(net "T11_BLAD1_EN")
	)
	(segment
		(start 25.92451 -380.815596)
		(end 25.92451 -439.204608)
		(width 0.127)
		(layer "In5.Cu")
		(net "T11_BLAD1_EN")
	)
	(segment
		(start 14.735302 -333.166212)
		(end 14.735302 -369.626388)
		(width 0.127)
		(layer "In5.Cu")
		(net "T11_BLAD1_EN")
	)
	(segment
		(start 14.298422 -330.940918)
		(end 14.958822 -331.601318)
		(width 0.127)
		(layer "In5.Cu")
		(net "T11_BLAD1_EN")
	)
	(segment
		(start 6.449822 -316.669928)
		(end 9.129522 -316.669928)
		(width 0.127)
		(layer "In5.Cu")
		(net "T11_BLAD1_EN")
	)
	(segment
		(start 25.92451 -439.204608)
		(end 32.272732 -445.55283)
		(width 0.127)
		(layer "In5.Cu")
		(net "T11_BLAD1_EN")
	)
	(segment
		(start 14.298422 -321.838828)
		(end 14.298422 -330.940918)
		(width 0.127)
		(layer "In5.Cu")
		(net "T11_BLAD1_EN")
	)
	(segment
		(start 32.272732 -445.55283)
		(end 78.966822 -445.55283)
		(width 0.127)
		(layer "In5.Cu")
		(net "T11_BLAD1_EN")
	)
	(segment
		(start 79.130906 -445.388746)
		(end 87.05723 -453.31507)
		(width 0.127)
		(layer "In5.Cu")
		(net "T11_BLAD1_EN")
	)
	(via
		(at 38.178486 -441.200286)
		(size 0.508)
		(drill 0.254)
		(layers "F.Cu" "B.Cu")
		(net "T11_BLAD1_RXD")
	)
	(segment
		(start 30.557216 -441.200286)
		(end 38.178486 -441.200286)
		(width 0.127)
		(layer "In2.Cu")
		(net "T11_BLAD1_RXD")
	)
	(segment
		(start 82.138012 -447.18224)
		(end 45.72889 -447.18224)
		(width 0.127)
		(layer "In2.Cu")
		(net "T11_BLAD1_RXD")
	)
	(segment
		(start 9.449816 -310.66994)
		(end 13.349732 -310.66994)
		(width 0.127)
		(layer "In2.Cu")
		(net "T11_BLAD1_RXD")
	)
	(segment
		(start 27.090116 -437.733186)
		(end 30.557216 -441.200286)
		(width 0.127)
		(layer "In2.Cu")
		(net "T11_BLAD1_RXD")
	)
	(segment
		(start 84.03844 -450.899276)
		(end 84.03844 -449.082668)
		(width 0.127)
		(layer "In2.Cu")
		(net "T11_BLAD1_RXD")
	)
	(segment
		(start 45.72889 -447.18224)
		(end 39.746936 -441.200286)
		(width 0.127)
		(layer "In2.Cu")
		(net "T11_BLAD1_RXD")
	)
	(segment
		(start 39.746936 -441.200286)
		(end 38.178486 -441.200286)
		(width 0.127)
		(layer "In2.Cu")
		(net "T11_BLAD1_RXD")
	)
	(segment
		(start 86.90991 -452.04507)
		(end 85.184234 -452.04507)
		(width 0.127)
		(layer "In2.Cu")
		(net "T11_BLAD1_RXD")
	)
	(segment
		(start 84.03844 -449.082668)
		(end 82.138012 -447.18224)
		(width 0.127)
		(layer "In2.Cu")
		(net "T11_BLAD1_RXD")
	)
	(segment
		(start 85.184234 -452.04507)
		(end 84.03844 -450.899276)
		(width 0.127)
		(layer "In2.Cu")
		(net "T11_BLAD1_RXD")
	)
	(segment
		(start 8.449818 -311.669938)
		(end 9.449816 -310.66994)
		(width 0.127)
		(layer "In2.Cu")
		(net "T11_BLAD1_RXD")
	)
	(segment
		(start 27.090116 -379.903228)
		(end 27.090116 -437.733186)
		(width 0.127)
		(layer "In2.Cu")
		(net "T11_BLAD1_RXD")
	)
	(segment
		(start 13.349732 -310.66994)
		(end 19.624294 -316.944502)
		(width 0.127)
		(layer "In2.Cu")
		(net "T11_BLAD1_RXD")
	)
	(segment
		(start 19.624294 -316.944502)
		(end 19.624294 -372.437406)
		(width 0.127)
		(layer "In2.Cu")
		(net "T11_BLAD1_RXD")
	)
	(segment
		(start 19.624294 -372.437406)
		(end 27.090116 -379.903228)
		(width 0.127)
		(layer "In2.Cu")
		(net "T11_BLAD1_RXD")
	)
	(via
		(at 96.331278 -13.248132)
		(size 0.508)
		(drill 0.254)
		(layers "F.Cu" "B.Cu")
		(net "T1_BLAD3_EN")
	)
	(segment
		(start 96.331278 -13.245592)
		(end 89.360756 -6.27507)
		(width 0.127)
		(layer "In5.Cu")
		(net "T1_BLAD3_EN")
	)
	(segment
		(start 23.234142 -108.366052)
		(end 23.234142 -94.866206)
		(width 0.127)
		(layer "In5.Cu")
		(net "T1_BLAD3_EN")
	)
	(segment
		(start 94.350586 -59.715654)
		(end 101.493066 -52.573174)
		(width 0.127)
		(layer "In5.Cu")
		(net "T1_BLAD3_EN")
	)
	(segment
		(start 23.234142 -94.866206)
		(end 26.797254 -91.303094)
		(width 0.127)
		(layer "In5.Cu")
		(net "T1_BLAD3_EN")
	)
	(segment
		(start 76.853796 -70.274942)
		(end 78.711298 -70.274942)
		(width 0.127)
		(layer "In5.Cu")
		(net "T1_BLAD3_EN")
	)
	(segment
		(start 16.065246 -222.711264)
		(end 23.82901 -214.9475)
		(width 0.127)
		(layer "In5.Cu")
		(net "T1_BLAD3_EN")
	)
	(segment
		(start 96.331278 -13.248132)
		(end 96.331278 -13.245592)
		(width 0.127)
		(layer "In5.Cu")
		(net "T1_BLAD3_EN")
	)
	(segment
		(start 9.949434 -228.670612)
		(end 15.908782 -222.711264)
		(width 0.127)
		(layer "In5.Cu")
		(net "T1_BLAD3_EN")
	)
	(segment
		(start 55.825644 -91.303094)
		(end 76.853796 -70.274942)
		(width 0.127)
		(layer "In5.Cu")
		(net "T1_BLAD3_EN")
	)
	(segment
		(start 101.493066 -18.40738)
		(end 96.331278 -13.245592)
		(width 0.127)
		(layer "In5.Cu")
		(net "T1_BLAD3_EN")
	)
	(segment
		(start 78.711298 -70.274942)
		(end 89.270586 -59.715654)
		(width 0.127)
		(layer "In5.Cu")
		(net "T1_BLAD3_EN")
	)
	(segment
		(start 23.82901 -214.9475)
		(end 23.82901 -201.972164)
		(width 0.127)
		(layer "In5.Cu")
		(net "T1_BLAD3_EN")
	)
	(segment
		(start 28.566618 -170.641772)
		(end 28.566618 -113.698528)
		(width 0.127)
		(layer "In5.Cu")
		(net "T1_BLAD3_EN")
	)
	(segment
		(start 89.360756 -6.27507)
		(end 88.17991 -6.27507)
		(width 0.127)
		(layer "In5.Cu")
		(net "T1_BLAD3_EN")
	)
	(segment
		(start 15.908782 -222.711264)
		(end 16.065246 -222.711264)
		(width 0.127)
		(layer "In5.Cu")
		(net "T1_BLAD3_EN")
	)
	(segment
		(start 26.797254 -91.303094)
		(end 55.825644 -91.303094)
		(width 0.127)
		(layer "In5.Cu")
		(net "T1_BLAD3_EN")
	)
	(segment
		(start 101.493066 -52.573174)
		(end 101.493066 -18.40738)
		(width 0.127)
		(layer "In5.Cu")
		(net "T1_BLAD3_EN")
	)
	(segment
		(start 28.566618 -113.698528)
		(end 23.234142 -108.366052)
		(width 0.127)
		(layer "In5.Cu")
		(net "T1_BLAD3_EN")
	)
	(segment
		(start 19.604228 -197.747382)
		(end 19.604228 -179.604162)
		(width 0.127)
		(layer "In5.Cu")
		(net "T1_BLAD3_EN")
	)
	(segment
		(start 89.270586 -59.715654)
		(end 94.350586 -59.715654)
		(width 0.127)
		(layer "In5.Cu")
		(net "T1_BLAD3_EN")
	)
	(segment
		(start 19.604228 -179.604162)
		(end 28.566618 -170.641772)
		(width 0.127)
		(layer "In5.Cu")
		(net "T1_BLAD3_EN")
	)
	(segment
		(start 8.448802 -228.670612)
		(end 9.949434 -228.670612)
		(width 0.127)
		(layer "In5.Cu")
		(net "T1_BLAD3_EN")
	)
	(segment
		(start 23.82901 -201.972164)
		(end 19.604228 -197.747382)
		(width 0.127)
		(layer "In5.Cu")
		(net "T1_BLAD3_EN")
	)
	(via
		(at 92.89288 -13.293344)
		(size 0.508)
		(drill 0.254)
		(layers "F.Cu" "B.Cu")
		(net "T1_BLAD4_EN")
	)
	(segment
		(start 6.448806 -227.670614)
		(end 8.195056 -225.924364)
		(width 0.127)
		(layer "In5.Cu")
		(net "T1_BLAD4_EN")
	)
	(segment
		(start 87.260684 -6.621018)
		(end 87.260684 -5.98043)
		(width 0.127)
		(layer "In5.Cu")
		(net "T1_BLAD4_EN")
	)
	(segment
		(start 18.199862 -198.442326)
		(end 18.199862 -179.022248)
		(width 0.127)
		(layer "In5.Cu")
		(net "T1_BLAD4_EN")
	)
	(segment
		(start 87.260684 -5.98043)
		(end 88.236044 -5.00507)
		(width 0.127)
		(layer "In5.Cu")
		(net "T1_BLAD4_EN")
	)
	(segment
		(start 14.66088 -219.644722)
		(end 22.745446 -211.560156)
		(width 0.127)
		(layer "In5.Cu")
		(net "T1_BLAD4_EN")
	)
	(segment
		(start 92.89288 -13.293344)
		(end 89.821512 -10.221976)
		(width 0.127)
		(layer "In5.Cu")
		(net "T1_BLAD4_EN")
	)
	(segment
		(start 8.195056 -225.924364)
		(end 10.196576 -225.924364)
		(width 0.127)
		(layer "In5.Cu")
		(net "T1_BLAD4_EN")
	)
	(segment
		(start 26.735024 -89.898728)
		(end 55.24373 -89.898728)
		(width 0.127)
		(layer "In5.Cu")
		(net "T1_BLAD4_EN")
	)
	(segment
		(start 88.338406 -10.221976)
		(end 87.357712 -9.241282)
		(width 0.127)
		(layer "In5.Cu")
		(net "T1_BLAD4_EN")
	)
	(segment
		(start 79.478378 -67.83959)
		(end 89.00668 -58.311288)
		(width 0.127)
		(layer "In5.Cu")
		(net "T1_BLAD4_EN")
	)
	(segment
		(start 100.339398 -51.740562)
		(end 100.339398 -20.739862)
		(width 0.127)
		(layer "In5.Cu")
		(net "T1_BLAD4_EN")
	)
	(segment
		(start 22.745446 -202.98791)
		(end 18.199862 -198.442326)
		(width 0.127)
		(layer "In5.Cu")
		(net "T1_BLAD4_EN")
	)
	(segment
		(start 18.199862 -179.022248)
		(end 27.515566 -169.706544)
		(width 0.127)
		(layer "In5.Cu")
		(net "T1_BLAD4_EN")
	)
	(segment
		(start 14.66088 -221.46006)
		(end 14.66088 -219.644722)
		(width 0.127)
		(layer "In5.Cu")
		(net "T1_BLAD4_EN")
	)
	(segment
		(start 87.357712 -9.241282)
		(end 87.357712 -8.33882)
		(width 0.127)
		(layer "In5.Cu")
		(net "T1_BLAD4_EN")
	)
	(segment
		(start 89.821512 -10.221976)
		(end 88.338406 -10.221976)
		(width 0.127)
		(layer "In5.Cu")
		(net "T1_BLAD4_EN")
	)
	(segment
		(start 55.24373 -89.898728)
		(end 77.302868 -67.83959)
		(width 0.127)
		(layer "In5.Cu")
		(net "T1_BLAD4_EN")
	)
	(segment
		(start 93.768672 -58.311288)
		(end 100.339398 -51.740562)
		(width 0.127)
		(layer "In5.Cu")
		(net "T1_BLAD4_EN")
	)
	(segment
		(start 27.515566 -114.0587)
		(end 22.098762 -108.641896)
		(width 0.127)
		(layer "In5.Cu")
		(net "T1_BLAD4_EN")
	)
	(segment
		(start 27.515566 -169.706544)
		(end 27.515566 -114.0587)
		(width 0.127)
		(layer "In5.Cu")
		(net "T1_BLAD4_EN")
	)
	(segment
		(start 22.745446 -211.560156)
		(end 22.745446 -202.98791)
		(width 0.127)
		(layer "In5.Cu")
		(net "T1_BLAD4_EN")
	)
	(segment
		(start 77.302868 -67.83959)
		(end 79.478378 -67.83959)
		(width 0.127)
		(layer "In5.Cu")
		(net "T1_BLAD4_EN")
	)
	(segment
		(start 87.843106 -7.853426)
		(end 87.843106 -7.20344)
		(width 0.127)
		(layer "In5.Cu")
		(net "T1_BLAD4_EN")
	)
	(segment
		(start 100.339398 -20.739862)
		(end 92.89288 -13.293344)
		(width 0.127)
		(layer "In5.Cu")
		(net "T1_BLAD4_EN")
	)
	(segment
		(start 87.357712 -8.33882)
		(end 87.843106 -7.853426)
		(width 0.127)
		(layer "In5.Cu")
		(net "T1_BLAD4_EN")
	)
	(segment
		(start 87.843106 -7.20344)
		(end 87.260684 -6.621018)
		(width 0.127)
		(layer "In5.Cu")
		(net "T1_BLAD4_EN")
	)
	(segment
		(start 88.236044 -5.00507)
		(end 89.44991 -5.00507)
		(width 0.127)
		(layer "In5.Cu")
		(net "T1_BLAD4_EN")
	)
	(segment
		(start 22.098762 -94.53499)
		(end 26.735024 -89.898728)
		(width 0.127)
		(layer "In5.Cu")
		(net "T1_BLAD4_EN")
	)
	(segment
		(start 89.00668 -58.311288)
		(end 93.768672 -58.311288)
		(width 0.127)
		(layer "In5.Cu")
		(net "T1_BLAD4_EN")
	)
	(segment
		(start 22.098762 -108.641896)
		(end 22.098762 -94.53499)
		(width 0.127)
		(layer "In5.Cu")
		(net "T1_BLAD4_EN")
	)
	(segment
		(start 10.196576 -225.924364)
		(end 14.66088 -221.46006)
		(width 0.127)
		(layer "In5.Cu")
		(net "T1_BLAD4_EN")
	)
	(via
		(at 96.411288 -14.844014)
		(size 0.508)
		(drill 0.254)
		(layers "F.Cu" "B.Cu")
		(net "T1_BLAD2_EN")
	)
	(segment
		(start 8.347202 -227.772214)
		(end 10.258298 -227.772214)
		(width 0.127)
		(layer "In5.Cu")
		(net "T1_BLAD2_EN")
	)
	(segment
		(start 55.652924 -90.88628)
		(end 77.359256 -69.179948)
		(width 0.127)
		(layer "In5.Cu")
		(net "T1_BLAD2_EN")
	)
	(segment
		(start 6.448806 -229.67061)
		(end 8.347202 -227.772214)
		(width 0.127)
		(layer "In5.Cu")
		(net "T1_BLAD2_EN")
	)
	(segment
		(start 101.076252 -52.400454)
		(end 101.076252 -19.508978)
		(width 0.127)
		(layer "In5.Cu")
		(net "T1_BLAD2_EN")
	)
	(segment
		(start 96.411288 -14.844014)
		(end 91.7702 -10.202926)
		(width 0.127)
		(layer "In5.Cu")
		(net "T1_BLAD2_EN")
	)
	(segment
		(start 28.22956 -113.831624)
		(end 22.886924 -108.488988)
		(width 0.127)
		(layer "In5.Cu")
		(net "T1_BLAD2_EN")
	)
	(segment
		(start 19.187414 -197.8914)
		(end 19.187414 -179.431442)
		(width 0.127)
		(layer "In5.Cu")
		(net "T1_BLAD2_EN")
	)
	(segment
		(start 77.359256 -69.179948)
		(end 79.186024 -69.179948)
		(width 0.127)
		(layer "In5.Cu")
		(net "T1_BLAD2_EN")
	)
	(segment
		(start 22.886924 -94.715584)
		(end 26.716228 -90.88628)
		(width 0.127)
		(layer "In5.Cu")
		(net "T1_BLAD2_EN")
	)
	(segment
		(start 94.177866 -59.29884)
		(end 101.076252 -52.400454)
		(width 0.127)
		(layer "In5.Cu")
		(net "T1_BLAD2_EN")
	)
	(segment
		(start 91.7702 -10.202926)
		(end 90.956638 -10.202926)
		(width 0.127)
		(layer "In5.Cu")
		(net "T1_BLAD2_EN")
	)
	(segment
		(start 15.648432 -222.38208)
		(end 15.648432 -221.750636)
		(width 0.127)
		(layer "In5.Cu")
		(net "T1_BLAD2_EN")
	)
	(segment
		(start 10.258298 -227.772214)
		(end 15.648432 -222.38208)
		(width 0.127)
		(layer "In5.Cu")
		(net "T1_BLAD2_EN")
	)
	(segment
		(start 89.067132 -59.29884)
		(end 94.177866 -59.29884)
		(width 0.127)
		(layer "In5.Cu")
		(net "T1_BLAD2_EN")
	)
	(segment
		(start 26.716228 -90.88628)
		(end 55.652924 -90.88628)
		(width 0.127)
		(layer "In5.Cu")
		(net "T1_BLAD2_EN")
	)
	(segment
		(start 101.076252 -19.508978)
		(end 96.411288 -14.844014)
		(width 0.127)
		(layer "In5.Cu")
		(net "T1_BLAD2_EN")
	)
	(segment
		(start 19.187414 -179.431442)
		(end 28.22956 -170.389296)
		(width 0.127)
		(layer "In5.Cu")
		(net "T1_BLAD2_EN")
	)
	(segment
		(start 23.486872 -202.190858)
		(end 19.187414 -197.8914)
		(width 0.127)
		(layer "In5.Cu")
		(net "T1_BLAD2_EN")
	)
	(segment
		(start 15.648432 -221.750636)
		(end 23.486872 -213.912196)
		(width 0.127)
		(layer "In5.Cu")
		(net "T1_BLAD2_EN")
	)
	(segment
		(start 23.486872 -213.912196)
		(end 23.486872 -202.190858)
		(width 0.127)
		(layer "In5.Cu")
		(net "T1_BLAD2_EN")
	)
	(segment
		(start 22.886924 -108.488988)
		(end 22.886924 -94.715584)
		(width 0.127)
		(layer "In5.Cu")
		(net "T1_BLAD2_EN")
	)
	(segment
		(start 28.22956 -170.389296)
		(end 28.22956 -113.831624)
		(width 0.127)
		(layer "In5.Cu")
		(net "T1_BLAD2_EN")
	)
	(segment
		(start 90.956638 -10.202926)
		(end 89.44991 -8.696198)
		(width 0.127)
		(layer "In5.Cu")
		(net "T1_BLAD2_EN")
	)
	(segment
		(start 79.186024 -69.179948)
		(end 89.067132 -59.29884)
		(width 0.127)
		(layer "In5.Cu")
		(net "T1_BLAD2_EN")
	)
	(segment
		(start 89.44991 -8.696198)
		(end 89.44991 -7.54507)
		(width 0.127)
		(layer "In5.Cu")
		(net "T1_BLAD2_EN")
	)
	(via
		(at 94.539816 -14.256004)
		(size 0.508)
		(drill 0.254)
		(layers "F.Cu" "B.Cu")
		(net "T1_BLAD1_EN")
	)
	(segment
		(start 79.010764 -68.777612)
		(end 89.024206 -58.76417)
		(width 0.127)
		(layer "In5.Cu")
		(net "T1_BLAD1_EN")
	)
	(segment
		(start 18.652744 -198.096632)
		(end 18.652744 -179.209954)
		(width 0.127)
		(layer "In5.Cu")
		(net "T1_BLAD1_EN")
	)
	(segment
		(start 94.539816 -14.256004)
		(end 89.098882 -8.81507)
		(width 0.127)
		(layer "In5.Cu")
		(net "T1_BLAD1_EN")
	)
	(segment
		(start 15.113762 -220.69933)
		(end 23.076154 -212.736938)
		(width 0.127)
		(layer "In5.Cu")
		(net "T1_BLAD1_EN")
	)
	(segment
		(start 93.956378 -58.76417)
		(end 100.698046 -52.022502)
		(width 0.127)
		(layer "In5.Cu")
		(net "T1_BLAD1_EN")
	)
	(segment
		(start 100.698046 -52.022502)
		(end 100.698046 -20.414234)
		(width 0.127)
		(layer "In5.Cu")
		(net "T1_BLAD1_EN")
	)
	(segment
		(start 15.113762 -221.647512)
		(end 15.113762 -220.69933)
		(width 0.127)
		(layer "In5.Cu")
		(net "T1_BLAD1_EN")
	)
	(segment
		(start 6.88213 -228.384354)
		(end 7.862316 -227.404168)
		(width 0.127)
		(layer "In5.Cu")
		(net "T1_BLAD1_EN")
	)
	(segment
		(start 5.678424 -229.034594)
		(end 6.328664 -228.384354)
		(width 0.127)
		(layer "In5.Cu")
		(net "T1_BLAD1_EN")
	)
	(segment
		(start 89.024206 -58.76417)
		(end 93.956378 -58.76417)
		(width 0.127)
		(layer "In5.Cu")
		(net "T1_BLAD1_EN")
	)
	(segment
		(start 6.328664 -228.384354)
		(end 6.88213 -228.384354)
		(width 0.127)
		(layer "In5.Cu")
		(net "T1_BLAD1_EN")
	)
	(segment
		(start 5.678424 -230.0732)
		(end 5.678424 -229.034594)
		(width 0.127)
		(layer "In5.Cu")
		(net "T1_BLAD1_EN")
	)
	(segment
		(start 77.005434 -68.777612)
		(end 79.010764 -68.777612)
		(width 0.127)
		(layer "In5.Cu")
		(net "T1_BLAD1_EN")
	)
	(segment
		(start 22.53234 -108.60278)
		(end 22.53234 -94.603062)
		(width 0.127)
		(layer "In5.Cu")
		(net "T1_BLAD1_EN")
	)
	(segment
		(start 27.854402 -113.924842)
		(end 22.53234 -108.60278)
		(width 0.127)
		(layer "In5.Cu")
		(net "T1_BLAD1_EN")
	)
	(segment
		(start 26.783792 -90.35161)
		(end 55.431436 -90.35161)
		(width 0.127)
		(layer "In5.Cu")
		(net "T1_BLAD1_EN")
	)
	(segment
		(start 100.698046 -20.414234)
		(end 94.539816 -14.256004)
		(width 0.127)
		(layer "In5.Cu")
		(net "T1_BLAD1_EN")
	)
	(segment
		(start 23.076154 -212.736938)
		(end 23.076154 -202.520042)
		(width 0.127)
		(layer "In5.Cu")
		(net "T1_BLAD1_EN")
	)
	(segment
		(start 9.357106 -227.404168)
		(end 15.113762 -221.647512)
		(width 0.127)
		(layer "In5.Cu")
		(net "T1_BLAD1_EN")
	)
	(segment
		(start 8.448802 -230.670608)
		(end 6.275832 -230.670608)
		(width 0.127)
		(layer "In5.Cu")
		(net "T1_BLAD1_EN")
	)
	(segment
		(start 6.275832 -230.670608)
		(end 5.678424 -230.0732)
		(width 0.127)
		(layer "In5.Cu")
		(net "T1_BLAD1_EN")
	)
	(segment
		(start 89.098882 -8.81507)
		(end 88.17991 -8.81507)
		(width 0.127)
		(layer "In5.Cu")
		(net "T1_BLAD1_EN")
	)
	(segment
		(start 22.53234 -94.603062)
		(end 26.783792 -90.35161)
		(width 0.127)
		(layer "In5.Cu")
		(net "T1_BLAD1_EN")
	)
	(segment
		(start 7.862316 -227.404168)
		(end 9.357106 -227.404168)
		(width 0.127)
		(layer "In5.Cu")
		(net "T1_BLAD1_EN")
	)
	(segment
		(start 55.431436 -90.35161)
		(end 77.005434 -68.777612)
		(width 0.127)
		(layer "In5.Cu")
		(net "T1_BLAD1_EN")
	)
	(segment
		(start 27.854402 -170.008296)
		(end 27.854402 -113.924842)
		(width 0.127)
		(layer "In5.Cu")
		(net "T1_BLAD1_EN")
	)
	(segment
		(start 18.652744 -179.209954)
		(end 27.854402 -170.008296)
		(width 0.127)
		(layer "In5.Cu")
		(net "T1_BLAD1_EN")
	)
	(segment
		(start 23.076154 -202.520042)
		(end 18.652744 -198.096632)
		(width 0.127)
		(layer "In5.Cu")
		(net "T1_BLAD1_EN")
	)
	(via
		(at 93.428566 -397.791432)
		(size 0.508)
		(drill 0.254)
		(layers "F.Cu" "B.Cu")
		(net "T10_BLAD4_RXD")
	)
	(segment
		(start 100.973636 -390.246362)
		(end 93.428566 -397.791432)
		(width 0.127)
		(layer "In5.Cu")
		(net "T10_BLAD4_RXD")
	)
	(segment
		(start 4.163314 -291.456364)
		(end 6.946138 -291.456364)
		(width 0.127)
		(layer "In5.Cu")
		(net "T10_BLAD4_RXD")
	)
	(segment
		(start 27.253184 -291.206428)
		(end 27.253184 -349.930974)
		(width 0.127)
		(layer "In5.Cu")
		(net "T10_BLAD4_RXD")
	)
	(segment
		(start 9.16178 -290.41852)
		(end 12.268962 -287.311338)
		(width 0.127)
		(layer "In5.Cu")
		(net "T10_BLAD4_RXD")
	)
	(segment
		(start 91.98991 -399.230088)
		(end 93.428566 -397.791432)
		(width 0.127)
		(layer "In5.Cu")
		(net "T10_BLAD4_RXD")
	)
	(segment
		(start 66.186812 -351.185734)
		(end 75.15225 -351.185734)
		(width 0.127)
		(layer "In5.Cu")
		(net "T10_BLAD4_RXD")
	)
	(segment
		(start 76.258166 -352.29165)
		(end 95.464122 -352.29165)
		(width 0.127)
		(layer "In5.Cu")
		(net "T10_BLAD4_RXD")
	)
	(segment
		(start 1.949958 -293.66972)
		(end 4.163314 -291.456364)
		(width 0.127)
		(layer "In5.Cu")
		(net "T10_BLAD4_RXD")
	)
	(segment
		(start 95.464122 -352.29165)
		(end 100.973636 -357.801164)
		(width 0.127)
		(layer "In5.Cu")
		(net "T10_BLAD4_RXD")
	)
	(segment
		(start 7.983982 -290.41852)
		(end 9.16178 -290.41852)
		(width 0.127)
		(layer "In5.Cu")
		(net "T10_BLAD4_RXD")
	)
	(segment
		(start 91.98991 -405.05507)
		(end 91.98991 -399.230088)
		(width 0.127)
		(layer "In5.Cu")
		(net "T10_BLAD4_RXD")
	)
	(segment
		(start 6.946138 -291.456364)
		(end 7.983982 -290.41852)
		(width 0.127)
		(layer "In5.Cu")
		(net "T10_BLAD4_RXD")
	)
	(segment
		(start 29.61386 -352.29165)
		(end 65.080896 -352.29165)
		(width 0.127)
		(layer "In5.Cu")
		(net "T10_BLAD4_RXD")
	)
	(segment
		(start 75.15225 -351.185734)
		(end 76.258166 -352.29165)
		(width 0.127)
		(layer "In5.Cu")
		(net "T10_BLAD4_RXD")
	)
	(segment
		(start 12.268962 -287.311338)
		(end 23.358094 -287.311338)
		(width 0.127)
		(layer "In5.Cu")
		(net "T10_BLAD4_RXD")
	)
	(segment
		(start 27.253184 -349.930974)
		(end 29.61386 -352.29165)
		(width 0.127)
		(layer "In5.Cu")
		(net "T10_BLAD4_RXD")
	)
	(segment
		(start 65.080896 -352.29165)
		(end 66.186812 -351.185734)
		(width 0.127)
		(layer "In5.Cu")
		(net "T10_BLAD4_RXD")
	)
	(segment
		(start 100.973636 -357.801164)
		(end 100.973636 -390.246362)
		(width 0.127)
		(layer "In5.Cu")
		(net "T10_BLAD4_RXD")
	)
	(segment
		(start 23.358094 -287.311338)
		(end 27.253184 -291.206428)
		(width 0.127)
		(layer "In5.Cu")
		(net "T10_BLAD4_RXD")
	)
	(via
		(at 85.334602 -399.744438)
		(size 0.508)
		(drill 0.254)
		(layers "F.Cu" "B.Cu")
		(net "T10_BLAD1_RXD")
	)
	(segment
		(start 87.371428 -408.056588)
		(end 86.90991 -407.59507)
		(width 0.127)
		(layer "In2.Cu")
		(net "T10_BLAD1_RXD")
	)
	(segment
		(start 45.62094 -370.231162)
		(end 39.181024 -363.791246)
		(width 0.127)
		(layer "In2.Cu")
		(net "T10_BLAD1_RXD")
	)
	(segment
		(start 23.032466 -350.897698)
		(end 23.032466 -310.715914)
		(width 0.127)
		(layer "In2.Cu")
		(net "T10_BLAD1_RXD")
	)
	(segment
		(start 85.334602 -399.744438)
		(end 82.34172 -396.751556)
		(width 0.127)
		(layer "In2.Cu")
		(net "T10_BLAD1_RXD")
	)
	(segment
		(start 45.62094 -375.459498)
		(end 45.62094 -370.231162)
		(width 0.127)
		(layer "In2.Cu")
		(net "T10_BLAD1_RXD")
	)
	(segment
		(start 90.29827 -404.708106)
		(end 90.29827 -405.562562)
		(width 0.127)
		(layer "In2.Cu")
		(net "T10_BLAD1_RXD")
	)
	(segment
		(start 90.29827 -405.562562)
		(end 89.8906 -405.970232)
		(width 0.127)
		(layer "In2.Cu")
		(net "T10_BLAD1_RXD")
	)
	(segment
		(start 11.240516 -298.923964)
		(end 7.75589 -298.923964)
		(width 0.127)
		(layer "In2.Cu")
		(net "T10_BLAD1_RXD")
	)
	(segment
		(start 37.971222 -355.26853)
		(end 27.403298 -355.26853)
		(width 0.127)
		(layer "In2.Cu")
		(net "T10_BLAD1_RXD")
	)
	(segment
		(start 4.855464 -299.76445)
		(end 3.949954 -300.66996)
		(width 0.127)
		(layer "In2.Cu")
		(net "T10_BLAD1_RXD")
	)
	(segment
		(start 90.46337 -407.309574)
		(end 90.46337 -407.891742)
		(width 0.127)
		(layer "In2.Cu")
		(net "T10_BLAD1_RXD")
	)
	(segment
		(start 89.10447 -408.425396)
		(end 88.735662 -408.056588)
		(width 0.127)
		(layer "In2.Cu")
		(net "T10_BLAD1_RXD")
	)
	(segment
		(start 90.46337 -407.891742)
		(end 89.929716 -408.425396)
		(width 0.127)
		(layer "In2.Cu")
		(net "T10_BLAD1_RXD")
	)
	(segment
		(start 88.735662 -408.056588)
		(end 87.371428 -408.056588)
		(width 0.127)
		(layer "In2.Cu")
		(net "T10_BLAD1_RXD")
	)
	(segment
		(start 89.929716 -408.425396)
		(end 89.10447 -408.425396)
		(width 0.127)
		(layer "In2.Cu")
		(net "T10_BLAD1_RXD")
	)
	(segment
		(start 82.34172 -396.751556)
		(end 66.912998 -396.751556)
		(width 0.127)
		(layer "In2.Cu")
		(net "T10_BLAD1_RXD")
	)
	(segment
		(start 23.032466 -310.715914)
		(end 11.240516 -298.923964)
		(width 0.127)
		(layer "In2.Cu")
		(net "T10_BLAD1_RXD")
	)
	(segment
		(start 6.915404 -299.76445)
		(end 4.855464 -299.76445)
		(width 0.127)
		(layer "In2.Cu")
		(net "T10_BLAD1_RXD")
	)
	(segment
		(start 89.8906 -406.736804)
		(end 90.46337 -407.309574)
		(width 0.127)
		(layer "In2.Cu")
		(net "T10_BLAD1_RXD")
	)
	(segment
		(start 39.181024 -356.478332)
		(end 37.971222 -355.26853)
		(width 0.127)
		(layer "In2.Cu")
		(net "T10_BLAD1_RXD")
	)
	(segment
		(start 27.403298 -355.26853)
		(end 23.032466 -350.897698)
		(width 0.127)
		(layer "In2.Cu")
		(net "T10_BLAD1_RXD")
	)
	(segment
		(start 39.181024 -363.791246)
		(end 39.181024 -356.478332)
		(width 0.127)
		(layer "In2.Cu")
		(net "T10_BLAD1_RXD")
	)
	(segment
		(start 85.334602 -399.744438)
		(end 90.29827 -404.708106)
		(width 0.127)
		(layer "In2.Cu")
		(net "T10_BLAD1_RXD")
	)
	(segment
		(start 7.75589 -298.923964)
		(end 6.915404 -299.76445)
		(width 0.127)
		(layer "In2.Cu")
		(net "T10_BLAD1_RXD")
	)
	(segment
		(start 66.912998 -396.751556)
		(end 45.62094 -375.459498)
		(width 0.127)
		(layer "In2.Cu")
		(net "T10_BLAD1_RXD")
	)
	(segment
		(start 89.8906 -405.970232)
		(end 89.8906 -406.736804)
		(width 0.127)
		(layer "In2.Cu")
		(net "T10_BLAD1_RXD")
	)
	(via
		(at 84.702396 -397.938244)
		(size 0.508)
		(drill 0.254)
		(layers "F.Cu" "B.Cu")
		(net "T10_BLAD1_TXD")
	)
	(segment
		(start 39.518336 -356.302564)
		(end 39.518336 -363.490002)
		(width 0.127)
		(layer "In2.Cu")
		(net "T10_BLAD1_TXD")
	)
	(segment
		(start 27.671268 -354.931218)
		(end 38.14699 -354.931218)
		(width 0.127)
		(layer "In2.Cu")
		(net "T10_BLAD1_TXD")
	)
	(segment
		(start 84.702396 -397.938244)
		(end 91.094306 -404.330154)
		(width 0.127)
		(layer "In2.Cu")
		(net "T10_BLAD1_TXD")
	)
	(segment
		(start 46.072298 -375.2723)
		(end 67.05854 -396.258542)
		(width 0.127)
		(layer "In2.Cu")
		(net "T10_BLAD1_TXD")
	)
	(segment
		(start 38.14699 -354.931218)
		(end 39.518336 -356.302564)
		(width 0.127)
		(layer "In2.Cu")
		(net "T10_BLAD1_TXD")
	)
	(segment
		(start 91.094306 -405.348948)
		(end 91.511628 -405.76627)
		(width 0.127)
		(layer "In2.Cu")
		(net "T10_BLAD1_TXD")
	)
	(segment
		(start 91.496896 -408.381454)
		(end 91.496896 -409.391104)
		(width 0.127)
		(layer "In2.Cu")
		(net "T10_BLAD1_TXD")
	)
	(segment
		(start 91.496896 -409.391104)
		(end 91.110054 -409.777946)
		(width 0.127)
		(layer "In2.Cu")
		(net "T10_BLAD1_TXD")
	)
	(segment
		(start 83.022694 -396.258542)
		(end 84.702396 -397.938244)
		(width 0.127)
		(layer "In2.Cu")
		(net "T10_BLAD1_TXD")
	)
	(segment
		(start 6.749796 -299.433742)
		(end 7.618476 -298.565062)
		(width 0.127)
		(layer "In2.Cu")
		(net "T10_BLAD1_TXD")
	)
	(segment
		(start 46.072298 -370.043964)
		(end 46.072298 -375.2723)
		(width 0.127)
		(layer "In2.Cu")
		(net "T10_BLAD1_TXD")
	)
	(segment
		(start 3.50647 -299.669962)
		(end 3.74269 -299.433742)
		(width 0.127)
		(layer "In2.Cu")
		(net "T10_BLAD1_TXD")
	)
	(segment
		(start 67.05854 -396.258542)
		(end 83.022694 -396.258542)
		(width 0.127)
		(layer "In2.Cu")
		(net "T10_BLAD1_TXD")
	)
	(segment
		(start 1.949958 -299.669962)
		(end 3.50647 -299.669962)
		(width 0.127)
		(layer "In2.Cu")
		(net "T10_BLAD1_TXD")
	)
	(segment
		(start 91.094306 -404.330154)
		(end 91.094306 -405.348948)
		(width 0.127)
		(layer "In2.Cu")
		(net "T10_BLAD1_TXD")
	)
	(segment
		(start 91.511628 -406.814274)
		(end 91.016836 -407.309066)
		(width 0.127)
		(layer "In2.Cu")
		(net "T10_BLAD1_TXD")
	)
	(segment
		(start 23.362666 -350.622616)
		(end 27.671268 -354.931218)
		(width 0.127)
		(layer "In2.Cu")
		(net "T10_BLAD1_TXD")
	)
	(segment
		(start 86.552786 -409.777946)
		(end 85.63991 -408.86507)
		(width 0.127)
		(layer "In2.Cu")
		(net "T10_BLAD1_TXD")
	)
	(segment
		(start 11.52017 -298.565062)
		(end 23.362666 -310.407558)
		(width 0.127)
		(layer "In2.Cu")
		(net "T10_BLAD1_TXD")
	)
	(segment
		(start 91.016836 -407.309066)
		(end 91.016836 -407.901394)
		(width 0.127)
		(layer "In2.Cu")
		(net "T10_BLAD1_TXD")
	)
	(segment
		(start 91.016836 -407.901394)
		(end 91.496896 -408.381454)
		(width 0.127)
		(layer "In2.Cu")
		(net "T10_BLAD1_TXD")
	)
	(segment
		(start 39.518336 -363.490002)
		(end 46.072298 -370.043964)
		(width 0.127)
		(layer "In2.Cu")
		(net "T10_BLAD1_TXD")
	)
	(segment
		(start 3.74269 -299.433742)
		(end 6.749796 -299.433742)
		(width 0.127)
		(layer "In2.Cu")
		(net "T10_BLAD1_TXD")
	)
	(segment
		(start 91.110054 -409.777946)
		(end 86.552786 -409.777946)
		(width 0.127)
		(layer "In2.Cu")
		(net "T10_BLAD1_TXD")
	)
	(segment
		(start 23.362666 -310.407558)
		(end 23.362666 -350.622616)
		(width 0.127)
		(layer "In2.Cu")
		(net "T10_BLAD1_TXD")
	)
	(segment
		(start 91.511628 -405.76627)
		(end 91.511628 -406.814274)
		(width 0.127)
		(layer "In2.Cu")
		(net "T10_BLAD1_TXD")
	)
	(segment
		(start 7.618476 -298.565062)
		(end 11.52017 -298.565062)
		(width 0.127)
		(layer "In2.Cu")
		(net "T10_BLAD1_TXD")
	)
	(via
		(at 90.262456 -399.03146)
		(size 0.508)
		(drill 0.254)
		(layers "F.Cu" "B.Cu")
		(net "T10_BLAD3_RXD")
	)
	(segment
		(start 26.478992 -292.84295)
		(end 26.478992 -350.172274)
		(width 0.127)
		(layer "In5.Cu")
		(net "T10_BLAD3_RXD")
	)
	(segment
		(start 29.37256 -353.065842)
		(end 65.926462 -353.065842)
		(width 0.127)
		(layer "In5.Cu")
		(net "T10_BLAD3_RXD")
	)
	(segment
		(start 86.90991 -405.05507)
		(end 86.90991 -402.384006)
		(width 0.127)
		(layer "In5.Cu")
		(net "T10_BLAD3_RXD")
	)
	(segment
		(start 86.90991 -402.384006)
		(end 90.262456 -399.03146)
		(width 0.127)
		(layer "In5.Cu")
		(net "T10_BLAD3_RXD")
	)
	(segment
		(start 100.199444 -389.094472)
		(end 90.262456 -399.03146)
		(width 0.127)
		(layer "In5.Cu")
		(net "T10_BLAD3_RXD")
	)
	(segment
		(start 100.199444 -358.12222)
		(end 100.199444 -389.094472)
		(width 0.127)
		(layer "In5.Cu")
		(net "T10_BLAD3_RXD")
	)
	(segment
		(start 67.030854 -351.96145)
		(end 74.718926 -351.96145)
		(width 0.127)
		(layer "In5.Cu")
		(net "T10_BLAD3_RXD")
	)
	(segment
		(start 1.949958 -295.66997)
		(end 4.25069 -293.369238)
		(width 0.127)
		(layer "In5.Cu")
		(net "T10_BLAD3_RXD")
	)
	(segment
		(start 75.823318 -353.065842)
		(end 95.143066 -353.065842)
		(width 0.127)
		(layer "In5.Cu")
		(net "T10_BLAD3_RXD")
	)
	(segment
		(start 26.478992 -350.172274)
		(end 29.37256 -353.065842)
		(width 0.127)
		(layer "In5.Cu")
		(net "T10_BLAD3_RXD")
	)
	(segment
		(start 4.25069 -293.369238)
		(end 7.202424 -293.369238)
		(width 0.127)
		(layer "In5.Cu")
		(net "T10_BLAD3_RXD")
	)
	(segment
		(start 22.4409 -288.804858)
		(end 26.478992 -292.84295)
		(width 0.127)
		(layer "In5.Cu")
		(net "T10_BLAD3_RXD")
	)
	(segment
		(start 12.614656 -288.804858)
		(end 22.4409 -288.804858)
		(width 0.127)
		(layer "In5.Cu")
		(net "T10_BLAD3_RXD")
	)
	(segment
		(start 74.718926 -351.96145)
		(end 75.823318 -353.065842)
		(width 0.127)
		(layer "In5.Cu")
		(net "T10_BLAD3_RXD")
	)
	(segment
		(start 95.143066 -353.065842)
		(end 100.199444 -358.12222)
		(width 0.127)
		(layer "In5.Cu")
		(net "T10_BLAD3_RXD")
	)
	(segment
		(start 7.202424 -293.369238)
		(end 7.973314 -292.598348)
		(width 0.127)
		(layer "In5.Cu")
		(net "T10_BLAD3_RXD")
	)
	(segment
		(start 8.821166 -292.598348)
		(end 12.614656 -288.804858)
		(width 0.127)
		(layer "In5.Cu")
		(net "T10_BLAD3_RXD")
	)
	(segment
		(start 7.973314 -292.598348)
		(end 8.821166 -292.598348)
		(width 0.127)
		(layer "In5.Cu")
		(net "T10_BLAD3_RXD")
	)
	(segment
		(start 65.926462 -353.065842)
		(end 67.030854 -351.96145)
		(width 0.127)
		(layer "In5.Cu")
		(net "T10_BLAD3_RXD")
	)
	(via
		(at 80.579722 -400.007328)
		(size 0.508)
		(drill 0.254)
		(layers "F.Cu" "B.Cu")
		(net "T10_BLAD2_EN")
	)
	(segment
		(start 21.935694 -353.062286)
		(end 25.1714 -356.297992)
		(width 0.127)
		(layer "In2.Cu")
		(net "T10_BLAD2_EN")
	)
	(segment
		(start 13.13942 -302.489108)
		(end 21.935694 -311.285382)
		(width 0.127)
		(layer "In2.Cu")
		(net "T10_BLAD2_EN")
	)
	(segment
		(start 79.577946 -399.005552)
		(end 80.579722 -400.007328)
		(width 0.127)
		(layer "In2.Cu")
		(net "T10_BLAD2_EN")
	)
	(segment
		(start 7.799324 -302.489108)
		(end 13.13942 -302.489108)
		(width 0.127)
		(layer "In2.Cu")
		(net "T10_BLAD2_EN")
	)
	(segment
		(start 89.44991 -407.59507)
		(end 88.167464 -407.59507)
		(width 0.127)
		(layer "In2.Cu")
		(net "T10_BLAD2_EN")
	)
	(segment
		(start 44.443142 -375.94794)
		(end 67.500754 -399.005552)
		(width 0.127)
		(layer "In2.Cu")
		(net "T10_BLAD2_EN")
	)
	(segment
		(start 44.443142 -370.719604)
		(end 44.443142 -375.94794)
		(width 0.127)
		(layer "In2.Cu")
		(net "T10_BLAD2_EN")
	)
	(segment
		(start 25.1714 -356.297992)
		(end 37.425884 -356.297992)
		(width 0.127)
		(layer "In2.Cu")
		(net "T10_BLAD2_EN")
	)
	(segment
		(start 37.425884 -356.297992)
		(end 38.163246 -357.035354)
		(width 0.127)
		(layer "In2.Cu")
		(net "T10_BLAD2_EN")
	)
	(segment
		(start 38.163246 -357.035354)
		(end 38.163246 -364.439708)
		(width 0.127)
		(layer "In2.Cu")
		(net "T10_BLAD2_EN")
	)
	(segment
		(start 21.935694 -311.285382)
		(end 21.935694 -353.062286)
		(width 0.127)
		(layer "In2.Cu")
		(net "T10_BLAD2_EN")
	)
	(segment
		(start 67.500754 -399.005552)
		(end 79.577946 -399.005552)
		(width 0.127)
		(layer "In2.Cu")
		(net "T10_BLAD2_EN")
	)
	(segment
		(start 38.163246 -364.439708)
		(end 44.443142 -370.719604)
		(width 0.127)
		(layer "In2.Cu")
		(net "T10_BLAD2_EN")
	)
	(segment
		(start 88.167464 -407.59507)
		(end 80.579722 -400.007328)
		(width 0.127)
		(layer "In2.Cu")
		(net "T10_BLAD2_EN")
	)
	(segment
		(start 6.861302 -303.42713)
		(end 7.799324 -302.489108)
		(width 0.127)
		(layer "In2.Cu")
		(net "T10_BLAD2_EN")
	)
	(segment
		(start 5.192776 -303.42713)
		(end 6.861302 -303.42713)
		(width 0.127)
		(layer "In2.Cu")
		(net "T10_BLAD2_EN")
	)
	(segment
		(start 3.949954 -304.669952)
		(end 5.192776 -303.42713)
		(width 0.127)
		(layer "In2.Cu")
		(net "T10_BLAD2_EN")
	)
	(via
		(at 83.667346 -399.272506)
		(size 0.508)
		(drill 0.254)
		(layers "F.Cu" "B.Cu")
		(net "T10_BLAD4_EN")
	)
	(segment
		(start 7.862316 -300.515782)
		(end 6.902196 -301.475902)
		(width 0.127)
		(layer "In2.Cu")
		(net "T10_BLAD4_EN")
	)
	(segment
		(start 45.255434 -370.3828)
		(end 38.845236 -363.972602)
		(width 0.127)
		(layer "In2.Cu")
		(net "T10_BLAD4_EN")
	)
	(segment
		(start 22.66696 -310.867552)
		(end 12.31519 -300.515782)
		(width 0.127)
		(layer "In2.Cu")
		(net "T10_BLAD4_EN")
	)
	(segment
		(start 38.845236 -356.659688)
		(end 37.819584 -355.634036)
		(width 0.127)
		(layer "In2.Cu")
		(net "T10_BLAD4_EN")
	)
	(segment
		(start 27.201622 -355.634036)
		(end 22.66696 -351.099374)
		(width 0.127)
		(layer "In2.Cu")
		(net "T10_BLAD4_EN")
	)
	(segment
		(start 5.144008 -301.475902)
		(end 3.949954 -302.669956)
		(width 0.127)
		(layer "In2.Cu")
		(net "T10_BLAD4_EN")
	)
	(segment
		(start 45.255434 -375.611136)
		(end 45.255434 -370.3828)
		(width 0.127)
		(layer "In2.Cu")
		(net "T10_BLAD4_EN")
	)
	(segment
		(start 37.819584 -355.634036)
		(end 27.201622 -355.634036)
		(width 0.127)
		(layer "In2.Cu")
		(net "T10_BLAD4_EN")
	)
	(segment
		(start 6.902196 -301.475902)
		(end 5.144008 -301.475902)
		(width 0.127)
		(layer "In2.Cu")
		(net "T10_BLAD4_EN")
	)
	(segment
		(start 38.845236 -363.972602)
		(end 38.845236 -356.659688)
		(width 0.127)
		(layer "In2.Cu")
		(net "T10_BLAD4_EN")
	)
	(segment
		(start 83.667346 -399.272506)
		(end 81.947766 -397.552926)
		(width 0.127)
		(layer "In2.Cu")
		(net "T10_BLAD4_EN")
	)
	(segment
		(start 67.197224 -397.552926)
		(end 45.255434 -375.611136)
		(width 0.127)
		(layer "In2.Cu")
		(net "T10_BLAD4_EN")
	)
	(segment
		(start 22.66696 -351.099374)
		(end 22.66696 -310.867552)
		(width 0.127)
		(layer "In2.Cu")
		(net "T10_BLAD4_EN")
	)
	(segment
		(start 81.947766 -397.552926)
		(end 67.197224 -397.552926)
		(width 0.127)
		(layer "In2.Cu")
		(net "T10_BLAD4_EN")
	)
	(segment
		(start 12.31519 -300.515782)
		(end 7.862316 -300.515782)
		(width 0.127)
		(layer "In2.Cu")
		(net "T10_BLAD4_EN")
	)
	(segment
		(start 83.667346 -399.272506)
		(end 89.44991 -405.05507)
		(width 0.127)
		(layer "In2.Cu")
		(net "T10_BLAD4_EN")
	)
	(via
		(at 79.267558 -400.271234)
		(size 0.508)
		(drill 0.254)
		(layers "F.Cu" "B.Cu")
		(net "T10_BLAD1_EN")
	)
	(segment
		(start 37.830506 -357.173276)
		(end 37.287962 -356.630732)
		(width 0.127)
		(layer "In2.Cu")
		(net "T10_BLAD1_EN")
	)
	(segment
		(start 4.373626 -305.66995)
		(end 1.949958 -305.66995)
		(width 0.127)
		(layer "In2.Cu")
		(net "T10_BLAD1_EN")
	)
	(segment
		(start 7.987538 -302.821848)
		(end 6.974586 -303.8348)
		(width 0.127)
		(layer "In2.Cu")
		(net "T10_BLAD1_EN")
	)
	(segment
		(start 6.974586 -303.8348)
		(end 6.208776 -303.8348)
		(width 0.127)
		(layer "In2.Cu")
		(net "T10_BLAD1_EN")
	)
	(segment
		(start 25.033478 -356.630732)
		(end 21.605494 -353.202748)
		(width 0.127)
		(layer "In2.Cu")
		(net "T10_BLAD1_EN")
	)
	(segment
		(start 84.174076 -405.177752)
		(end 79.267558 -400.271234)
		(width 0.127)
		(layer "In2.Cu")
		(net "T10_BLAD1_EN")
	)
	(segment
		(start 37.830506 -364.57763)
		(end 37.830506 -357.173276)
		(width 0.127)
		(layer "In2.Cu")
		(net "T10_BLAD1_EN")
	)
	(segment
		(start 44.110402 -376.085862)
		(end 44.110402 -370.857526)
		(width 0.127)
		(layer "In2.Cu")
		(net "T10_BLAD1_EN")
	)
	(segment
		(start 67.712082 -399.687542)
		(end 44.110402 -376.085862)
		(width 0.127)
		(layer "In2.Cu")
		(net "T10_BLAD1_EN")
	)
	(segment
		(start 37.287962 -356.630732)
		(end 25.033478 -356.630732)
		(width 0.127)
		(layer "In2.Cu")
		(net "T10_BLAD1_EN")
	)
	(segment
		(start 13.001244 -302.821848)
		(end 7.987538 -302.821848)
		(width 0.127)
		(layer "In2.Cu")
		(net "T10_BLAD1_EN")
	)
	(segment
		(start 78.683866 -399.687542)
		(end 67.712082 -399.687542)
		(width 0.127)
		(layer "In2.Cu")
		(net "T10_BLAD1_EN")
	)
	(segment
		(start 21.605494 -353.202748)
		(end 21.605494 -311.426098)
		(width 0.127)
		(layer "In2.Cu")
		(net "T10_BLAD1_EN")
	)
	(segment
		(start 44.110402 -370.857526)
		(end 37.830506 -364.57763)
		(width 0.127)
		(layer "In2.Cu")
		(net "T10_BLAD1_EN")
	)
	(segment
		(start 86.83244 -408.86507)
		(end 84.174076 -406.206706)
		(width 0.127)
		(layer "In2.Cu")
		(net "T10_BLAD1_EN")
	)
	(segment
		(start 88.17991 -408.86507)
		(end 86.83244 -408.86507)
		(width 0.127)
		(layer "In2.Cu")
		(net "T10_BLAD1_EN")
	)
	(segment
		(start 84.174076 -406.206706)
		(end 84.174076 -405.177752)
		(width 0.127)
		(layer "In2.Cu")
		(net "T10_BLAD1_EN")
	)
	(segment
		(start 21.605494 -311.426098)
		(end 13.001244 -302.821848)
		(width 0.127)
		(layer "In2.Cu")
		(net "T10_BLAD1_EN")
	)
	(segment
		(start 79.267558 -400.271234)
		(end 78.683866 -399.687542)
		(width 0.127)
		(layer "In2.Cu")
		(net "T10_BLAD1_EN")
	)
	(segment
		(start 6.208776 -303.8348)
		(end 4.373626 -305.66995)
		(width 0.127)
		(layer "In2.Cu")
		(net "T10_BLAD1_EN")
	)
	(via
		(at 88.45423 -400.111214)
		(size 0.508)
		(drill 0.254)
		(layers "F.Cu" "B.Cu")
		(net "T10_BLAD3_TXD")
	)
	(segment
		(start 75.654154 -353.411282)
		(end 94.99981 -353.411282)
		(width 0.127)
		(layer "In5.Cu")
		(net "T10_BLAD3_TXD")
	)
	(segment
		(start 26.133552 -350.294448)
		(end 29.250386 -353.411282)
		(width 0.127)
		(layer "In5.Cu")
		(net "T10_BLAD3_TXD")
	)
	(segment
		(start 88.45423 -400.111214)
		(end 85.63991 -402.925534)
		(width 0.127)
		(layer "In5.Cu")
		(net "T10_BLAD3_TXD")
	)
	(segment
		(start 94.99981 -353.411282)
		(end 99.854004 -358.265476)
		(width 0.127)
		(layer "In5.Cu")
		(net "T10_BLAD3_TXD")
	)
	(segment
		(start 66.242438 -353.411282)
		(end 67.327272 -352.326448)
		(width 0.127)
		(layer "In5.Cu")
		(net "T10_BLAD3_TXD")
	)
	(segment
		(start 99.854004 -388.71144)
		(end 88.45423 -400.111214)
		(width 0.127)
		(layer "In5.Cu")
		(net "T10_BLAD3_TXD")
	)
	(segment
		(start 8.11784 -292.930072)
		(end 9.749282 -292.930072)
		(width 0.127)
		(layer "In5.Cu")
		(net "T10_BLAD3_TXD")
	)
	(segment
		(start 4.858258 -293.761668)
		(end 7.286244 -293.761668)
		(width 0.127)
		(layer "In5.Cu")
		(net "T10_BLAD3_TXD")
	)
	(segment
		(start 85.63991 -402.925534)
		(end 85.63991 -406.32507)
		(width 0.127)
		(layer "In5.Cu")
		(net "T10_BLAD3_TXD")
	)
	(segment
		(start 99.854004 -358.265476)
		(end 99.854004 -388.71144)
		(width 0.127)
		(layer "In5.Cu")
		(net "T10_BLAD3_TXD")
	)
	(segment
		(start 13.529056 -289.150298)
		(end 22.297644 -289.150298)
		(width 0.127)
		(layer "In5.Cu")
		(net "T10_BLAD3_TXD")
	)
	(segment
		(start 26.133552 -292.986206)
		(end 26.133552 -350.294448)
		(width 0.127)
		(layer "In5.Cu")
		(net "T10_BLAD3_TXD")
	)
	(segment
		(start 74.56932 -352.326448)
		(end 75.654154 -353.411282)
		(width 0.127)
		(layer "In5.Cu")
		(net "T10_BLAD3_TXD")
	)
	(segment
		(start 9.749282 -292.930072)
		(end 13.529056 -289.150298)
		(width 0.127)
		(layer "In5.Cu")
		(net "T10_BLAD3_TXD")
	)
	(segment
		(start 29.250386 -353.411282)
		(end 66.242438 -353.411282)
		(width 0.127)
		(layer "In5.Cu")
		(net "T10_BLAD3_TXD")
	)
	(segment
		(start 22.297644 -289.150298)
		(end 26.133552 -292.986206)
		(width 0.127)
		(layer "In5.Cu")
		(net "T10_BLAD3_TXD")
	)
	(segment
		(start 7.286244 -293.761668)
		(end 8.11784 -292.930072)
		(width 0.127)
		(layer "In5.Cu")
		(net "T10_BLAD3_TXD")
	)
	(segment
		(start 67.327272 -352.326448)
		(end 74.56932 -352.326448)
		(width 0.127)
		(layer "In5.Cu")
		(net "T10_BLAD3_TXD")
	)
	(segment
		(start 3.949954 -294.669972)
		(end 4.858258 -293.761668)
		(width 0.127)
		(layer "In5.Cu")
		(net "T10_BLAD3_TXD")
	)
	(via
		(at 87.224108 -399.30832)
		(size 0.508)
		(drill 0.254)
		(layers "F.Cu" "B.Cu")
		(net "T10_BLAD2_RXD")
	)
	(segment
		(start 91.98991 -407.59507)
		(end 91.98991 -408.800808)
		(width 0.127)
		(layer "In5.Cu")
		(net "T10_BLAD2_RXD")
	)
	(segment
		(start 21.47443 -290.519866)
		(end 23.978362 -293.023798)
		(width 0.127)
		(layer "In5.Cu")
		(net "T10_BLAD2_RXD")
	)
	(segment
		(start 99.079558 -358.586532)
		(end 99.079558 -387.45287)
		(width 0.127)
		(layer "In5.Cu")
		(net "T10_BLAD2_RXD")
	)
	(segment
		(start 28.786836 -354.185728)
		(end 94.678754 -354.185728)
		(width 0.127)
		(layer "In5.Cu")
		(net "T10_BLAD2_RXD")
	)
	(segment
		(start 6.280404 -295.790112)
		(end 7.037324 -295.790112)
		(width 0.127)
		(layer "In5.Cu")
		(net "T10_BLAD2_RXD")
	)
	(segment
		(start 94.678754 -354.185728)
		(end 99.079558 -358.586532)
		(width 0.127)
		(layer "In5.Cu")
		(net "T10_BLAD2_RXD")
	)
	(segment
		(start 3.949954 -298.120562)
		(end 6.280404 -295.790112)
		(width 0.127)
		(layer "In5.Cu")
		(net "T10_BLAD2_RXD")
	)
	(segment
		(start 23.978362 -349.377254)
		(end 28.786836 -354.185728)
		(width 0.127)
		(layer "In5.Cu")
		(net "T10_BLAD2_RXD")
	)
	(segment
		(start 7.920482 -294.906954)
		(end 9.648444 -294.906954)
		(width 0.127)
		(layer "In5.Cu")
		(net "T10_BLAD2_RXD")
	)
	(segment
		(start 83.902296 -409.405836)
		(end 83.902296 -402.630132)
		(width 0.127)
		(layer "In5.Cu")
		(net "T10_BLAD2_RXD")
	)
	(segment
		(start 14.035532 -290.519866)
		(end 21.47443 -290.519866)
		(width 0.127)
		(layer "In5.Cu")
		(net "T10_BLAD2_RXD")
	)
	(segment
		(start 83.902296 -402.630132)
		(end 87.224108 -399.30832)
		(width 0.127)
		(layer "In5.Cu")
		(net "T10_BLAD2_RXD")
	)
	(segment
		(start 85.047328 -410.550868)
		(end 83.902296 -409.405836)
		(width 0.127)
		(layer "In5.Cu")
		(net "T10_BLAD2_RXD")
	)
	(segment
		(start 91.98991 -408.800808)
		(end 90.23985 -410.550868)
		(width 0.127)
		(layer "In5.Cu")
		(net "T10_BLAD2_RXD")
	)
	(segment
		(start 99.079558 -387.45287)
		(end 87.224108 -399.30832)
		(width 0.127)
		(layer "In5.Cu")
		(net "T10_BLAD2_RXD")
	)
	(segment
		(start 9.648444 -294.906954)
		(end 14.035532 -290.519866)
		(width 0.127)
		(layer "In5.Cu")
		(net "T10_BLAD2_RXD")
	)
	(segment
		(start 3.949954 -298.669964)
		(end 3.949954 -298.120562)
		(width 0.127)
		(layer "In5.Cu")
		(net "T10_BLAD2_RXD")
	)
	(segment
		(start 23.978362 -293.023798)
		(end 23.978362 -349.377254)
		(width 0.127)
		(layer "In5.Cu")
		(net "T10_BLAD2_RXD")
	)
	(segment
		(start 90.23985 -410.550868)
		(end 85.047328 -410.550868)
		(width 0.127)
		(layer "In5.Cu")
		(net "T10_BLAD2_RXD")
	)
	(segment
		(start 7.037324 -295.790112)
		(end 7.920482 -294.906954)
		(width 0.127)
		(layer "In5.Cu")
		(net "T10_BLAD2_RXD")
	)
	(via
		(at 91.696794 -398.49806)
		(size 0.508)
		(drill 0.254)
		(layers "F.Cu" "B.Cu")
		(net "T10_BLAD4_TXD")
	)
	(segment
		(start 90.71991 -406.32507)
		(end 90.71991 -399.474944)
		(width 0.127)
		(layer "In5.Cu")
		(net "T10_BLAD4_TXD")
	)
	(segment
		(start 74.878692 -351.573592)
		(end 75.950064 -352.644964)
		(width 0.127)
		(layer "In5.Cu")
		(net "T10_BLAD4_TXD")
	)
	(segment
		(start 90.71991 -399.474944)
		(end 91.696794 -398.49806)
		(width 0.127)
		(layer "In5.Cu")
		(net "T10_BLAD4_TXD")
	)
	(segment
		(start 26.89987 -350.09074)
		(end 29.454094 -352.644964)
		(width 0.127)
		(layer "In5.Cu")
		(net "T10_BLAD4_TXD")
	)
	(segment
		(start 100.620322 -389.574532)
		(end 91.696794 -398.49806)
		(width 0.127)
		(layer "In5.Cu")
		(net "T10_BLAD4_TXD")
	)
	(segment
		(start 7.098284 -291.80409)
		(end 8.13054 -290.771834)
		(width 0.127)
		(layer "In5.Cu")
		(net "T10_BLAD4_TXD")
	)
	(segment
		(start 8.13054 -290.771834)
		(end 9.372092 -290.771834)
		(width 0.127)
		(layer "In5.Cu")
		(net "T10_BLAD4_TXD")
	)
	(segment
		(start 26.89987 -291.352986)
		(end 26.89987 -350.09074)
		(width 0.127)
		(layer "In5.Cu")
		(net "T10_BLAD4_TXD")
	)
	(segment
		(start 23.248366 -287.701482)
		(end 26.89987 -291.352986)
		(width 0.127)
		(layer "In5.Cu")
		(net "T10_BLAD4_TXD")
	)
	(segment
		(start 66.642996 -351.573592)
		(end 74.878692 -351.573592)
		(width 0.127)
		(layer "In5.Cu")
		(net "T10_BLAD4_TXD")
	)
	(segment
		(start 29.454094 -352.644964)
		(end 65.571624 -352.644964)
		(width 0.127)
		(layer "In5.Cu")
		(net "T10_BLAD4_TXD")
	)
	(segment
		(start 12.442444 -287.701482)
		(end 23.248366 -287.701482)
		(width 0.127)
		(layer "In5.Cu")
		(net "T10_BLAD4_TXD")
	)
	(segment
		(start 75.950064 -352.644964)
		(end 95.317564 -352.644964)
		(width 0.127)
		(layer "In5.Cu")
		(net "T10_BLAD4_TXD")
	)
	(segment
		(start 95.317564 -352.644964)
		(end 100.620322 -357.947722)
		(width 0.127)
		(layer "In5.Cu")
		(net "T10_BLAD4_TXD")
	)
	(segment
		(start 4.81584 -291.80409)
		(end 7.098284 -291.80409)
		(width 0.127)
		(layer "In5.Cu")
		(net "T10_BLAD4_TXD")
	)
	(segment
		(start 100.620322 -357.947722)
		(end 100.620322 -389.574532)
		(width 0.127)
		(layer "In5.Cu")
		(net "T10_BLAD4_TXD")
	)
	(segment
		(start 65.571624 -352.644964)
		(end 66.642996 -351.573592)
		(width 0.127)
		(layer "In5.Cu")
		(net "T10_BLAD4_TXD")
	)
	(segment
		(start 9.372092 -290.771834)
		(end 12.442444 -287.701482)
		(width 0.127)
		(layer "In5.Cu")
		(net "T10_BLAD4_TXD")
	)
	(segment
		(start 3.949954 -292.669976)
		(end 4.81584 -291.80409)
		(width 0.127)
		(layer "In5.Cu")
		(net "T10_BLAD4_TXD")
	)
	(via
		(at 82.22488 -399.014696)
		(size 0.508)
		(drill 0.254)
		(layers "F.Cu" "B.Cu")
		(net "T10_BLAD3_EN")
	)
	(segment
		(start 25.421844 -355.966776)
		(end 37.584888 -355.966776)
		(width 0.127)
		(layer "In2.Cu")
		(net "T10_BLAD3_EN")
	)
	(segment
		(start 1.949958 -303.669954)
		(end 4.318 -303.669954)
		(width 0.127)
		(layer "In2.Cu")
		(net "T10_BLAD3_EN")
	)
	(segment
		(start 4.952238 -303.035716)
		(end 4.952238 -302.683926)
		(width 0.127)
		(layer "In2.Cu")
		(net "T10_BLAD3_EN")
	)
	(segment
		(start 44.854368 -370.54917)
		(end 44.854368 -375.777506)
		(width 0.127)
		(layer "In2.Cu")
		(net "T10_BLAD3_EN")
	)
	(segment
		(start 4.318 -303.669954)
		(end 4.952238 -303.035716)
		(width 0.127)
		(layer "In2.Cu")
		(net "T10_BLAD3_EN")
	)
	(segment
		(start 7.108444 -301.823628)
		(end 8.03783 -300.894242)
		(width 0.127)
		(layer "In2.Cu")
		(net "T10_BLAD3_EN")
	)
	(segment
		(start 37.584888 -355.966776)
		(end 38.503098 -356.884986)
		(width 0.127)
		(layer "In2.Cu")
		(net "T10_BLAD3_EN")
	)
	(segment
		(start 44.854368 -375.777506)
		(end 67.366642 -398.28978)
		(width 0.127)
		(layer "In2.Cu")
		(net "T10_BLAD3_EN")
	)
	(segment
		(start 4.952238 -302.683926)
		(end 5.812536 -301.823628)
		(width 0.127)
		(layer "In2.Cu")
		(net "T10_BLAD3_EN")
	)
	(segment
		(start 67.366642 -398.28978)
		(end 81.499964 -398.28978)
		(width 0.127)
		(layer "In2.Cu")
		(net "T10_BLAD3_EN")
	)
	(segment
		(start 22.265894 -311.033922)
		(end 22.265894 -352.810826)
		(width 0.127)
		(layer "In2.Cu")
		(net "T10_BLAD3_EN")
	)
	(segment
		(start 12.126214 -300.894242)
		(end 22.265894 -311.033922)
		(width 0.127)
		(layer "In2.Cu")
		(net "T10_BLAD3_EN")
	)
	(segment
		(start 5.812536 -301.823628)
		(end 7.108444 -301.823628)
		(width 0.127)
		(layer "In2.Cu")
		(net "T10_BLAD3_EN")
	)
	(segment
		(start 82.22488 -399.014696)
		(end 88.17991 -404.969726)
		(width 0.127)
		(layer "In2.Cu")
		(net "T10_BLAD3_EN")
	)
	(segment
		(start 88.17991 -404.969726)
		(end 88.17991 -406.32507)
		(width 0.127)
		(layer "In2.Cu")
		(net "T10_BLAD3_EN")
	)
	(segment
		(start 38.503098 -364.1979)
		(end 44.854368 -370.54917)
		(width 0.127)
		(layer "In2.Cu")
		(net "T10_BLAD3_EN")
	)
	(segment
		(start 38.503098 -356.884986)
		(end 38.503098 -364.1979)
		(width 0.127)
		(layer "In2.Cu")
		(net "T10_BLAD3_EN")
	)
	(segment
		(start 22.265894 -352.810826)
		(end 25.421844 -355.966776)
		(width 0.127)
		(layer "In2.Cu")
		(net "T10_BLAD3_EN")
	)
	(segment
		(start 8.03783 -300.894242)
		(end 12.126214 -300.894242)
		(width 0.127)
		(layer "In2.Cu")
		(net "T10_BLAD3_EN")
	)
	(segment
		(start 81.499964 -398.28978)
		(end 82.22488 -399.014696)
		(width 0.127)
		(layer "In2.Cu")
		(net "T10_BLAD3_EN")
	)
	(via
		(at 88.57234 -398.827498)
		(size 0.508)
		(drill 0.254)
		(layers "F.Cu" "B.Cu")
		(net "T10_BLAD2_TXD")
	)
	(segment
		(start 9.02462 -294.47998)
		(end 13.525754 -289.978846)
		(width 0.127)
		(layer "In5.Cu")
		(net "T10_BLAD2_TXD")
	)
	(segment
		(start 2.69748 -296.915078)
		(end 2.999994 -296.612564)
		(width 0.127)
		(layer "In5.Cu")
		(net "T10_BLAD2_TXD")
	)
	(segment
		(start 24.976582 -349.88119)
		(end 28.886404 -353.791012)
		(width 0.127)
		(layer "In5.Cu")
		(net "T10_BLAD2_TXD")
	)
	(segment
		(start 84.505038 -409.156154)
		(end 85.29701 -409.948126)
		(width 0.127)
		(layer "In5.Cu")
		(net "T10_BLAD2_TXD")
	)
	(segment
		(start 7.629144 -294.47998)
		(end 9.02462 -294.47998)
		(width 0.127)
		(layer "In5.Cu")
		(net "T10_BLAD2_TXD")
	)
	(segment
		(start 94.808294 -353.791012)
		(end 99.450144 -358.432862)
		(width 0.127)
		(layer "In5.Cu")
		(net "T10_BLAD2_TXD")
	)
	(segment
		(start 13.525754 -289.978846)
		(end 21.489924 -289.978846)
		(width 0.127)
		(layer "In5.Cu")
		(net "T10_BLAD2_TXD")
	)
	(segment
		(start 99.450144 -387.949694)
		(end 88.57234 -398.827498)
		(width 0.127)
		(layer "In5.Cu")
		(net "T10_BLAD2_TXD")
	)
	(segment
		(start 28.886404 -353.791012)
		(end 94.808294 -353.791012)
		(width 0.127)
		(layer "In5.Cu")
		(net "T10_BLAD2_TXD")
	)
	(segment
		(start 21.489924 -289.978846)
		(end 24.976582 -293.465504)
		(width 0.127)
		(layer "In5.Cu")
		(net "T10_BLAD2_TXD")
	)
	(segment
		(start 3.93319 -295.449244)
		(end 6.65988 -295.449244)
		(width 0.127)
		(layer "In5.Cu")
		(net "T10_BLAD2_TXD")
	)
	(segment
		(start 24.976582 -293.465504)
		(end 24.976582 -349.88119)
		(width 0.127)
		(layer "In5.Cu")
		(net "T10_BLAD2_TXD")
	)
	(segment
		(start 89.636854 -409.948126)
		(end 90.71991 -408.86507)
		(width 0.127)
		(layer "In5.Cu")
		(net "T10_BLAD2_TXD")
	)
	(segment
		(start 2.69748 -296.922444)
		(end 2.69748 -296.915078)
		(width 0.127)
		(layer "In5.Cu")
		(net "T10_BLAD2_TXD")
	)
	(segment
		(start 2.999994 -296.38244)
		(end 3.93319 -295.449244)
		(width 0.127)
		(layer "In5.Cu")
		(net "T10_BLAD2_TXD")
	)
	(segment
		(start 85.29701 -409.948126)
		(end 89.636854 -409.948126)
		(width 0.127)
		(layer "In5.Cu")
		(net "T10_BLAD2_TXD")
	)
	(segment
		(start 2.999994 -296.612564)
		(end 2.999994 -296.38244)
		(width 0.127)
		(layer "In5.Cu")
		(net "T10_BLAD2_TXD")
	)
	(segment
		(start 1.949958 -297.669966)
		(end 2.69748 -296.922444)
		(width 0.127)
		(layer "In5.Cu")
		(net "T10_BLAD2_TXD")
	)
	(segment
		(start 99.450144 -358.432862)
		(end 99.450144 -387.949694)
		(width 0.127)
		(layer "In5.Cu")
		(net "T10_BLAD2_TXD")
	)
	(segment
		(start 88.57234 -398.827498)
		(end 84.505038 -402.8948)
		(width 0.127)
		(layer "In5.Cu")
		(net "T10_BLAD2_TXD")
	)
	(segment
		(start 6.65988 -295.449244)
		(end 7.629144 -294.47998)
		(width 0.127)
		(layer "In5.Cu")
		(net "T10_BLAD2_TXD")
	)
	(segment
		(start 84.505038 -402.8948)
		(end 84.505038 -409.156154)
		(width 0.127)
		(layer "In5.Cu")
		(net "T10_BLAD2_TXD")
	)
	(via
		(at 24.51354 -354.427028)
		(size 0.508)
		(drill 0.254)
		(layers "F.Cu" "B.Cu")
		(net "T9_BLAD1_EN")
	)
	(segment
		(start 9.978136 -303.198276)
		(end 9.978136 -303.329848)
		(width 0.127)
		(layer "In5.Cu")
		(net "T9_BLAD1_EN")
	)
	(segment
		(start 21.888196 -350.17837)
		(end 22.284182 -350.574356)
		(width 0.127)
		(layer "In5.Cu")
		(net "T9_BLAD1_EN")
	)
	(segment
		(start 86.846664 -364.41507)
		(end 88.17991 -364.41507)
		(width 0.127)
		(layer "In5.Cu")
		(net "T9_BLAD1_EN")
	)
	(segment
		(start 22.284182 -352.19767)
		(end 24.51354 -354.427028)
		(width 0.127)
		(layer "In5.Cu")
		(net "T9_BLAD1_EN")
	)
	(segment
		(start 84.524088 -362.092494)
		(end 86.846664 -364.41507)
		(width 0.127)
		(layer "In5.Cu")
		(net "T9_BLAD1_EN")
	)
	(segment
		(start 9.978136 -303.329848)
		(end 21.888196 -315.239908)
		(width 0.127)
		(layer "In5.Cu")
		(net "T9_BLAD1_EN")
	)
	(segment
		(start 21.888196 -315.239908)
		(end 21.888196 -350.17837)
		(width 0.127)
		(layer "In5.Cu")
		(net "T9_BLAD1_EN")
	)
	(segment
		(start 39.654988 -358.75468)
		(end 81.962498 -358.75468)
		(width 0.127)
		(layer "In5.Cu")
		(net "T9_BLAD1_EN")
	)
	(segment
		(start 81.962498 -358.75468)
		(end 84.524088 -361.31627)
		(width 0.127)
		(layer "In5.Cu")
		(net "T9_BLAD1_EN")
	)
	(segment
		(start 22.284182 -350.574356)
		(end 22.284182 -352.19767)
		(width 0.127)
		(layer "In5.Cu")
		(net "T9_BLAD1_EN")
	)
	(segment
		(start 24.51354 -354.427028)
		(end 27.228546 -357.142034)
		(width 0.127)
		(layer "In5.Cu")
		(net "T9_BLAD1_EN")
	)
	(segment
		(start 38.042342 -357.142034)
		(end 39.654988 -358.75468)
		(width 0.127)
		(layer "In5.Cu")
		(net "T9_BLAD1_EN")
	)
	(segment
		(start 8.449818 -301.669958)
		(end 9.978136 -303.198276)
		(width 0.127)
		(layer "In5.Cu")
		(net "T9_BLAD1_EN")
	)
	(segment
		(start 27.228546 -357.142034)
		(end 38.042342 -357.142034)
		(width 0.127)
		(layer "In5.Cu")
		(net "T9_BLAD1_EN")
	)
	(segment
		(start 84.524088 -361.31627)
		(end 84.524088 -362.092494)
		(width 0.127)
		(layer "In5.Cu")
		(net "T9_BLAD1_EN")
	)
	(via
		(at 89.07526 -356.423722)
		(size 0.508)
		(drill 0.254)
		(layers "F.Cu" "B.Cu")
		(net "T9_BLAD1_TXD")
	)
	(segment
		(start 92.89034 -363.625892)
		(end 90.949018 -365.567214)
		(width 0.127)
		(layer "In5.Cu")
		(net "T9_BLAD1_TXD")
	)
	(segment
		(start 23.573994 -313.327034)
		(end 23.573994 -349.46717)
		(width 0.127)
		(layer "In5.Cu")
		(net "T9_BLAD1_TXD")
	)
	(segment
		(start 43.236896 -354.754688)
		(end 87.41537 -354.754688)
		(width 0.127)
		(layer "In5.Cu")
		(net "T9_BLAD1_TXD")
	)
	(segment
		(start 86.792054 -365.567214)
		(end 85.63991 -364.41507)
		(width 0.127)
		(layer "In5.Cu")
		(net "T9_BLAD1_TXD")
	)
	(segment
		(start 89.07526 -356.414578)
		(end 92.89034 -360.229658)
		(width 0.127)
		(layer "In5.Cu")
		(net "T9_BLAD1_TXD")
	)
	(segment
		(start 13.433298 -301.58055)
		(end 13.433298 -303.186338)
		(width 0.127)
		(layer "In5.Cu")
		(net "T9_BLAD1_TXD")
	)
	(segment
		(start 8.449818 -295.66997)
		(end 10.577068 -297.79722)
		(width 0.127)
		(layer "In5.Cu")
		(net "T9_BLAD1_TXD")
	)
	(segment
		(start 87.41537 -354.754688)
		(end 89.07526 -356.414578)
		(width 0.127)
		(layer "In5.Cu")
		(net "T9_BLAD1_TXD")
	)
	(segment
		(start 41.74998 -356.241604)
		(end 43.236896 -354.754688)
		(width 0.127)
		(layer "In5.Cu")
		(net "T9_BLAD1_TXD")
	)
	(segment
		(start 10.577068 -297.79722)
		(end 10.577068 -298.72432)
		(width 0.127)
		(layer "In5.Cu")
		(net "T9_BLAD1_TXD")
	)
	(segment
		(start 23.573994 -349.46717)
		(end 29.424122 -355.317298)
		(width 0.127)
		(layer "In5.Cu")
		(net "T9_BLAD1_TXD")
	)
	(segment
		(start 90.949018 -365.567214)
		(end 86.792054 -365.567214)
		(width 0.127)
		(layer "In5.Cu")
		(net "T9_BLAD1_TXD")
	)
	(segment
		(start 89.07526 -356.423722)
		(end 89.07526 -356.414578)
		(width 0.127)
		(layer "In5.Cu")
		(net "T9_BLAD1_TXD")
	)
	(segment
		(start 40.275002 -356.241604)
		(end 41.74998 -356.241604)
		(width 0.127)
		(layer "In5.Cu")
		(net "T9_BLAD1_TXD")
	)
	(segment
		(start 29.424122 -355.317298)
		(end 39.350696 -355.317298)
		(width 0.127)
		(layer "In5.Cu")
		(net "T9_BLAD1_TXD")
	)
	(segment
		(start 10.577068 -298.72432)
		(end 13.433298 -301.58055)
		(width 0.127)
		(layer "In5.Cu")
		(net "T9_BLAD1_TXD")
	)
	(segment
		(start 92.89034 -360.229658)
		(end 92.89034 -363.625892)
		(width 0.127)
		(layer "In5.Cu")
		(net "T9_BLAD1_TXD")
	)
	(segment
		(start 13.433298 -303.186338)
		(end 23.573994 -313.327034)
		(width 0.127)
		(layer "In5.Cu")
		(net "T9_BLAD1_TXD")
	)
	(segment
		(start 39.350696 -355.317298)
		(end 40.275002 -356.241604)
		(width 0.127)
		(layer "In5.Cu")
		(net "T9_BLAD1_TXD")
	)
	(via
		(at 87.40902 -356.02418)
		(size 0.508)
		(drill 0.254)
		(layers "F.Cu" "B.Cu")
		(net "T9_BLAD4_RXD")
	)
	(segment
		(start 82.20837 -355.836728)
		(end 83.250278 -355.836728)
		(width 0.127)
		(layer "In2.Cu")
		(net "T9_BLAD4_RXD")
	)
	(segment
		(start 87.40902 -356.02418)
		(end 91.98991 -360.60507)
		(width 0.127)
		(layer "In2.Cu")
		(net "T9_BLAD4_RXD")
	)
	(segment
		(start 81.549748 -355.178106)
		(end 82.20837 -355.836728)
		(width 0.127)
		(layer "In2.Cu")
		(net "T9_BLAD4_RXD")
	)
	(segment
		(start 26.5049 -349.761556)
		(end 29.606494 -352.86315)
		(width 0.127)
		(layer "In2.Cu")
		(net "T9_BLAD4_RXD")
	)
	(segment
		(start 21.196808 -288.411412)
		(end 26.5049 -293.719504)
		(width 0.127)
		(layer "In2.Cu")
		(net "T9_BLAD4_RXD")
	)
	(segment
		(start 29.606494 -352.86315)
		(end 43.584876 -352.86315)
		(width 0.127)
		(layer "In2.Cu")
		(net "T9_BLAD4_RXD")
	)
	(segment
		(start 43.584876 -352.86315)
		(end 45.899832 -355.178106)
		(width 0.127)
		(layer "In2.Cu")
		(net "T9_BLAD4_RXD")
	)
	(segment
		(start 83.250278 -355.836728)
		(end 83.9089 -355.178106)
		(width 0.127)
		(layer "In2.Cu")
		(net "T9_BLAD4_RXD")
	)
	(segment
		(start 10.985754 -288.411412)
		(end 21.196808 -288.411412)
		(width 0.127)
		(layer "In2.Cu")
		(net "T9_BLAD4_RXD")
	)
	(segment
		(start 83.9089 -355.178106)
		(end 86.562946 -355.178106)
		(width 0.127)
		(layer "In2.Cu")
		(net "T9_BLAD4_RXD")
	)
	(segment
		(start 9.727438 -289.669728)
		(end 10.985754 -288.411412)
		(width 0.127)
		(layer "In2.Cu")
		(net "T9_BLAD4_RXD")
	)
	(segment
		(start 86.562946 -355.178106)
		(end 87.40902 -356.02418)
		(width 0.127)
		(layer "In2.Cu")
		(net "T9_BLAD4_RXD")
	)
	(segment
		(start 26.5049 -293.719504)
		(end 26.5049 -349.761556)
		(width 0.127)
		(layer "In2.Cu")
		(net "T9_BLAD4_RXD")
	)
	(segment
		(start 8.449818 -289.669728)
		(end 9.727438 -289.669728)
		(width 0.127)
		(layer "In2.Cu")
		(net "T9_BLAD4_RXD")
	)
	(segment
		(start 45.899832 -355.178106)
		(end 81.549748 -355.178106)
		(width 0.127)
		(layer "In2.Cu")
		(net "T9_BLAD4_RXD")
	)
	(via
		(at 43.269154 -355.936296)
		(size 0.508)
		(drill 0.254)
		(layers "F.Cu" "B.Cu")
		(net "T9_BLAD3_TXD")
	)
	(segment
		(start 24.365204 -293.247572)
		(end 24.365204 -349.853758)
		(width 0.127)
		(layer "In2.Cu")
		(net "T9_BLAD3_TXD")
	)
	(segment
		(start 9.335262 -292.57879)
		(end 12.288774 -289.625278)
		(width 0.127)
		(layer "In2.Cu")
		(net "T9_BLAD3_TXD")
	)
	(segment
		(start 45.709586 -358.381808)
		(end 83.374738 -358.381808)
		(width 0.127)
		(layer "In2.Cu")
		(net "T9_BLAD3_TXD")
	)
	(segment
		(start 83.374738 -358.381808)
		(end 85.63991 -360.64698)
		(width 0.127)
		(layer "In2.Cu")
		(net "T9_BLAD3_TXD")
	)
	(segment
		(start 43.269154 -355.941376)
		(end 45.709586 -358.381808)
		(width 0.127)
		(layer "In2.Cu")
		(net "T9_BLAD3_TXD")
	)
	(segment
		(start 24.365204 -349.853758)
		(end 28.431998 -353.920552)
		(width 0.127)
		(layer "In2.Cu")
		(net "T9_BLAD3_TXD")
	)
	(segment
		(start 6.449822 -290.66998)
		(end 8.358632 -292.57879)
		(width 0.127)
		(layer "In2.Cu")
		(net "T9_BLAD3_TXD")
	)
	(segment
		(start 12.288774 -289.625278)
		(end 20.74291 -289.625278)
		(width 0.127)
		(layer "In2.Cu")
		(net "T9_BLAD3_TXD")
	)
	(segment
		(start 43.269154 -355.941376)
		(end 43.269154 -355.936296)
		(width 0.127)
		(layer "In2.Cu")
		(net "T9_BLAD3_TXD")
	)
	(segment
		(start 8.358632 -292.57879)
		(end 9.335262 -292.57879)
		(width 0.127)
		(layer "In2.Cu")
		(net "T9_BLAD3_TXD")
	)
	(segment
		(start 41.24833 -353.920552)
		(end 43.269154 -355.941376)
		(width 0.127)
		(layer "In2.Cu")
		(net "T9_BLAD3_TXD")
	)
	(segment
		(start 28.431998 -353.920552)
		(end 41.24833 -353.920552)
		(width 0.127)
		(layer "In2.Cu")
		(net "T9_BLAD3_TXD")
	)
	(segment
		(start 85.63991 -360.64698)
		(end 85.63991 -361.87507)
		(width 0.127)
		(layer "In2.Cu")
		(net "T9_BLAD3_TXD")
	)
	(segment
		(start 20.74291 -289.625278)
		(end 24.365204 -293.247572)
		(width 0.127)
		(layer "In2.Cu")
		(net "T9_BLAD3_TXD")
	)
	(via
		(at 41.665398 -355.657404)
		(size 0.508)
		(drill 0.254)
		(layers "F.Cu" "B.Cu")
		(net "T9_BLAD2_TXD")
	)
	(segment
		(start 28.23337 -354.259642)
		(end 40.267636 -354.259642)
		(width 0.127)
		(layer "In2.Cu")
		(net "T9_BLAD2_TXD")
	)
	(segment
		(start 41.665398 -355.657404)
		(end 44.914058 -358.906064)
		(width 0.127)
		(layer "In2.Cu")
		(net "T9_BLAD2_TXD")
	)
	(segment
		(start 84.144104 -364.440978)
		(end 85.13699 -365.433864)
		(width 0.127)
		(layer "In2.Cu")
		(net "T9_BLAD2_TXD")
	)
	(segment
		(start 13.749274 -289.989514)
		(end 20.592034 -289.989514)
		(width 0.127)
		(layer "In2.Cu")
		(net "T9_BLAD2_TXD")
	)
	(segment
		(start 8.449818 -293.66972)
		(end 10.069068 -293.66972)
		(width 0.127)
		(layer "In2.Cu")
		(net "T9_BLAD2_TXD")
	)
	(segment
		(start 84.144104 -360.179874)
		(end 84.144104 -364.440978)
		(width 0.127)
		(layer "In2.Cu")
		(net "T9_BLAD2_TXD")
	)
	(segment
		(start 10.069068 -293.66972)
		(end 13.749274 -289.989514)
		(width 0.127)
		(layer "In2.Cu")
		(net "T9_BLAD2_TXD")
	)
	(segment
		(start 24.035004 -293.432484)
		(end 24.035004 -350.061276)
		(width 0.127)
		(layer "In2.Cu")
		(net "T9_BLAD2_TXD")
	)
	(segment
		(start 85.13699 -365.433864)
		(end 89.701116 -365.433864)
		(width 0.127)
		(layer "In2.Cu")
		(net "T9_BLAD2_TXD")
	)
	(segment
		(start 89.701116 -365.433864)
		(end 90.71991 -364.41507)
		(width 0.127)
		(layer "In2.Cu")
		(net "T9_BLAD2_TXD")
	)
	(segment
		(start 24.035004 -350.061276)
		(end 28.23337 -354.259642)
		(width 0.127)
		(layer "In2.Cu")
		(net "T9_BLAD2_TXD")
	)
	(segment
		(start 44.914058 -358.906064)
		(end 82.870294 -358.906064)
		(width 0.127)
		(layer "In2.Cu")
		(net "T9_BLAD2_TXD")
	)
	(segment
		(start 20.592034 -289.989514)
		(end 24.035004 -293.432484)
		(width 0.127)
		(layer "In2.Cu")
		(net "T9_BLAD2_TXD")
	)
	(segment
		(start 40.267636 -354.259642)
		(end 41.665398 -355.657404)
		(width 0.127)
		(layer "In2.Cu")
		(net "T9_BLAD2_TXD")
	)
	(segment
		(start 82.870294 -358.906064)
		(end 84.144104 -360.179874)
		(width 0.127)
		(layer "In2.Cu")
		(net "T9_BLAD2_TXD")
	)
	(via
		(at 85.000084 -355.804216)
		(size 0.508)
		(drill 0.254)
		(layers "F.Cu" "B.Cu")
		(net "T9_BLAD4_TXD")
	)
	(segment
		(start 85.960204 -355.804216)
		(end 90.71991 -360.563922)
		(width 0.127)
		(layer "In2.Cu")
		(net "T9_BLAD4_TXD")
	)
	(segment
		(start 26.153618 -350.559624)
		(end 28.792932 -353.198938)
		(width 0.127)
		(layer "In2.Cu")
		(net "T9_BLAD4_TXD")
	)
	(segment
		(start 90.71991 -360.563922)
		(end 90.71991 -361.87507)
		(width 0.127)
		(layer "In2.Cu")
		(net "T9_BLAD4_TXD")
	)
	(segment
		(start 9.657588 -290.461192)
		(end 11.36142 -288.75736)
		(width 0.127)
		(layer "In2.Cu")
		(net "T9_BLAD4_TXD")
	)
	(segment
		(start 85.000084 -355.804216)
		(end 85.960204 -355.804216)
		(width 0.127)
		(layer "In2.Cu")
		(net "T9_BLAD4_TXD")
	)
	(segment
		(start 6.449822 -288.669984)
		(end 8.24103 -290.461192)
		(width 0.127)
		(layer "In2.Cu")
		(net "T9_BLAD4_TXD")
	)
	(segment
		(start 8.24103 -290.461192)
		(end 9.657588 -290.461192)
		(width 0.127)
		(layer "In2.Cu")
		(net "T9_BLAD4_TXD")
	)
	(segment
		(start 11.36142 -288.75736)
		(end 21.045932 -288.75736)
		(width 0.127)
		(layer "In2.Cu")
		(net "T9_BLAD4_TXD")
	)
	(segment
		(start 21.045932 -288.75736)
		(end 26.153618 -293.865046)
		(width 0.127)
		(layer "In2.Cu")
		(net "T9_BLAD4_TXD")
	)
	(segment
		(start 47.238412 -357.205534)
		(end 83.598766 -357.205534)
		(width 0.127)
		(layer "In2.Cu")
		(net "T9_BLAD4_TXD")
	)
	(segment
		(start 83.598766 -357.205534)
		(end 85.000084 -355.804216)
		(width 0.127)
		(layer "In2.Cu")
		(net "T9_BLAD4_TXD")
	)
	(segment
		(start 26.153618 -293.865046)
		(end 26.153618 -350.559624)
		(width 0.127)
		(layer "In2.Cu")
		(net "T9_BLAD4_TXD")
	)
	(segment
		(start 43.231816 -353.198938)
		(end 47.238412 -357.205534)
		(width 0.127)
		(layer "In2.Cu")
		(net "T9_BLAD4_TXD")
	)
	(segment
		(start 28.792932 -353.198938)
		(end 43.231816 -353.198938)
		(width 0.127)
		(layer "In2.Cu")
		(net "T9_BLAD4_TXD")
	)
	(via
		(at 40.288972 -355.459792)
		(size 0.508)
		(drill 0.254)
		(layers "F.Cu" "B.Cu")
		(net "T9_BLAD2_RXD")
	)
	(segment
		(start 91.98991 -364.581186)
		(end 91.98991 -363.14507)
		(width 0.127)
		(layer "In2.Cu")
		(net "T9_BLAD2_RXD")
	)
	(segment
		(start 9.583674 -294.669972)
		(end 13.90015 -290.353496)
		(width 0.127)
		(layer "In2.Cu")
		(net "T9_BLAD2_RXD")
	)
	(segment
		(start 85.085174 -365.861092)
		(end 90.710004 -365.861092)
		(width 0.127)
		(layer "In2.Cu")
		(net "T9_BLAD2_RXD")
	)
	(segment
		(start 23.692866 -293.605204)
		(end 23.692866 -350.246696)
		(width 0.127)
		(layer "In2.Cu")
		(net "T9_BLAD2_RXD")
	)
	(segment
		(start 39.716456 -354.90912)
		(end 39.7383 -354.90912)
		(width 0.127)
		(layer "In2.Cu")
		(net "T9_BLAD2_RXD")
	)
	(segment
		(start 13.90015 -290.353496)
		(end 20.441158 -290.353496)
		(width 0.127)
		(layer "In2.Cu")
		(net "T9_BLAD2_RXD")
	)
	(segment
		(start 44.173648 -359.344468)
		(end 82.64525 -359.344468)
		(width 0.127)
		(layer "In2.Cu")
		(net "T9_BLAD2_RXD")
	)
	(segment
		(start 39.402766 -354.59543)
		(end 39.716456 -354.90912)
		(width 0.127)
		(layer "In2.Cu")
		(net "T9_BLAD2_RXD")
	)
	(segment
		(start 39.7383 -354.90912)
		(end 40.288972 -355.459792)
		(width 0.127)
		(layer "In2.Cu")
		(net "T9_BLAD2_RXD")
	)
	(segment
		(start 28.0416 -354.59543)
		(end 39.402766 -354.59543)
		(width 0.127)
		(layer "In2.Cu")
		(net "T9_BLAD2_RXD")
	)
	(segment
		(start 23.692866 -350.246696)
		(end 28.0416 -354.59543)
		(width 0.127)
		(layer "In2.Cu")
		(net "T9_BLAD2_RXD")
	)
	(segment
		(start 20.441158 -290.353496)
		(end 23.692866 -293.605204)
		(width 0.127)
		(layer "In2.Cu")
		(net "T9_BLAD2_RXD")
	)
	(segment
		(start 83.716876 -364.492794)
		(end 85.085174 -365.861092)
		(width 0.127)
		(layer "In2.Cu")
		(net "T9_BLAD2_RXD")
	)
	(segment
		(start 40.288972 -355.459792)
		(end 44.173648 -359.344468)
		(width 0.127)
		(layer "In2.Cu")
		(net "T9_BLAD2_RXD")
	)
	(segment
		(start 82.64525 -359.344468)
		(end 83.716876 -360.416094)
		(width 0.127)
		(layer "In2.Cu")
		(net "T9_BLAD2_RXD")
	)
	(segment
		(start 90.710004 -365.861092)
		(end 91.98991 -364.581186)
		(width 0.127)
		(layer "In2.Cu")
		(net "T9_BLAD2_RXD")
	)
	(segment
		(start 6.449822 -294.669972)
		(end 9.583674 -294.669972)
		(width 0.127)
		(layer "In2.Cu")
		(net "T9_BLAD2_RXD")
	)
	(segment
		(start 83.716876 -360.416094)
		(end 83.716876 -364.492794)
		(width 0.127)
		(layer "In2.Cu")
		(net "T9_BLAD2_RXD")
	)
	(via
		(at 82.711544 -355.374956)
		(size 0.508)
		(drill 0.254)
		(layers "F.Cu" "B.Cu")
		(net "T9_BLAD1_RXD")
	)
	(segment
		(start 23.208996 -313.563762)
		(end 13.007848 -303.362614)
		(width 0.127)
		(layer "In5.Cu")
		(net "T9_BLAD1_RXD")
	)
	(segment
		(start 88.474296 -363.43209)
		(end 87.765636 -363.43209)
		(width 0.127)
		(layer "In5.Cu")
		(net "T9_BLAD1_RXD")
	)
	(segment
		(start 40.189404 -356.808278)
		(end 39.063422 -355.682296)
		(width 0.127)
		(layer "In5.Cu")
		(net "T9_BLAD1_RXD")
	)
	(segment
		(start 90.06586 -363.936788)
		(end 88.978994 -363.936788)
		(width 0.127)
		(layer "In5.Cu")
		(net "T9_BLAD1_RXD")
	)
	(segment
		(start 87.765636 -363.43209)
		(end 87.478616 -363.14507)
		(width 0.127)
		(layer "In5.Cu")
		(net "T9_BLAD1_RXD")
	)
	(segment
		(start 85.166962 -357.089456)
		(end 87.275416 -357.089456)
		(width 0.127)
		(layer "In5.Cu")
		(net "T9_BLAD1_RXD")
	)
	(segment
		(start 8.69315 -296.669968)
		(end 6.449822 -296.669968)
		(width 0.127)
		(layer "In5.Cu")
		(net "T9_BLAD1_RXD")
	)
	(segment
		(start 87.275416 -357.089456)
		(end 91.618816 -361.432856)
		(width 0.127)
		(layer "In5.Cu")
		(net "T9_BLAD1_RXD")
	)
	(segment
		(start 44.854876 -355.374956)
		(end 43.421554 -356.808278)
		(width 0.127)
		(layer "In5.Cu")
		(net "T9_BLAD1_RXD")
	)
	(segment
		(start 43.421554 -356.808278)
		(end 40.189404 -356.808278)
		(width 0.127)
		(layer "In5.Cu")
		(net "T9_BLAD1_RXD")
	)
	(segment
		(start 9.900412 -297.87723)
		(end 8.69315 -296.669968)
		(width 0.127)
		(layer "In5.Cu")
		(net "T9_BLAD1_RXD")
	)
	(segment
		(start 23.208996 -349.630746)
		(end 23.208996 -313.563762)
		(width 0.127)
		(layer "In5.Cu")
		(net "T9_BLAD1_RXD")
	)
	(segment
		(start 13.007848 -302.039782)
		(end 9.900412 -298.932346)
		(width 0.127)
		(layer "In5.Cu")
		(net "T9_BLAD1_RXD")
	)
	(segment
		(start 29.260546 -355.682296)
		(end 23.208996 -349.630746)
		(width 0.127)
		(layer "In5.Cu")
		(net "T9_BLAD1_RXD")
	)
	(segment
		(start 87.478616 -363.14507)
		(end 86.90991 -363.14507)
		(width 0.127)
		(layer "In5.Cu")
		(net "T9_BLAD1_RXD")
	)
	(segment
		(start 83.452462 -355.374956)
		(end 85.166962 -357.089456)
		(width 0.127)
		(layer "In5.Cu")
		(net "T9_BLAD1_RXD")
	)
	(segment
		(start 82.711544 -355.374956)
		(end 44.854876 -355.374956)
		(width 0.127)
		(layer "In5.Cu")
		(net "T9_BLAD1_RXD")
	)
	(segment
		(start 9.900412 -298.932346)
		(end 9.900412 -297.87723)
		(width 0.127)
		(layer "In5.Cu")
		(net "T9_BLAD1_RXD")
	)
	(segment
		(start 39.063422 -355.682296)
		(end 29.260546 -355.682296)
		(width 0.127)
		(layer "In5.Cu")
		(net "T9_BLAD1_RXD")
	)
	(segment
		(start 91.618816 -361.432856)
		(end 91.618816 -362.383832)
		(width 0.127)
		(layer "In5.Cu")
		(net "T9_BLAD1_RXD")
	)
	(segment
		(start 82.711544 -355.374956)
		(end 83.452462 -355.374956)
		(width 0.127)
		(layer "In5.Cu")
		(net "T9_BLAD1_RXD")
	)
	(segment
		(start 13.007848 -303.362614)
		(end 13.007848 -302.039782)
		(width 0.127)
		(layer "In5.Cu")
		(net "T9_BLAD1_RXD")
	)
	(segment
		(start 91.618816 -362.383832)
		(end 90.06586 -363.936788)
		(width 0.127)
		(layer "In5.Cu")
		(net "T9_BLAD1_RXD")
	)
	(segment
		(start 88.978994 -363.936788)
		(end 88.474296 -363.43209)
		(width 0.127)
		(layer "In5.Cu")
		(net "T9_BLAD1_RXD")
	)
	(via
		(at 81.128616 -355.941884)
		(size 0.508)
		(drill 0.254)
		(layers "F.Cu" "B.Cu")
		(net "T9_BLAD4_EN")
	)
	(segment
		(start 23.35657 -350.734376)
		(end 28.692348 -356.070154)
		(width 0.127)
		(layer "In5.Cu")
		(net "T9_BLAD4_EN")
	)
	(segment
		(start 28.692348 -356.070154)
		(end 38.884352 -356.070154)
		(width 0.127)
		(layer "In5.Cu")
		(net "T9_BLAD4_EN")
	)
	(segment
		(start 22.878796 -314.186316)
		(end 22.878796 -349.767652)
		(width 0.127)
		(layer "In5.Cu")
		(net "T9_BLAD4_EN")
	)
	(segment
		(start 22.878796 -349.767652)
		(end 23.35657 -350.245426)
		(width 0.127)
		(layer "In5.Cu")
		(net "T9_BLAD4_EN")
	)
	(segment
		(start 89.44991 -360.60507)
		(end 86.616032 -357.771192)
		(width 0.127)
		(layer "In5.Cu")
		(net "T9_BLAD4_EN")
	)
	(segment
		(start 84.93633 -357.771192)
		(end 83.107022 -355.941884)
		(width 0.127)
		(layer "In5.Cu")
		(net "T9_BLAD4_EN")
	)
	(segment
		(start 83.107022 -355.941884)
		(end 81.128616 -355.941884)
		(width 0.127)
		(layer "In5.Cu")
		(net "T9_BLAD4_EN")
	)
	(segment
		(start 86.616032 -357.771192)
		(end 84.93633 -357.771192)
		(width 0.127)
		(layer "In5.Cu")
		(net "T9_BLAD4_EN")
	)
	(segment
		(start 12.423902 -302.438562)
		(end 12.423902 -303.731422)
		(width 0.127)
		(layer "In5.Cu")
		(net "T9_BLAD4_EN")
	)
	(segment
		(start 40.13581 -357.321612)
		(end 45.108876 -357.321612)
		(width 0.127)
		(layer "In5.Cu")
		(net "T9_BLAD4_EN")
	)
	(segment
		(start 38.884352 -356.070154)
		(end 40.13581 -357.321612)
		(width 0.127)
		(layer "In5.Cu")
		(net "T9_BLAD4_EN")
	)
	(segment
		(start 12.423902 -303.731422)
		(end 22.878796 -314.186316)
		(width 0.127)
		(layer "In5.Cu")
		(net "T9_BLAD4_EN")
	)
	(segment
		(start 8.655304 -298.669964)
		(end 12.423902 -302.438562)
		(width 0.127)
		(layer "In5.Cu")
		(net "T9_BLAD4_EN")
	)
	(segment
		(start 6.449822 -298.669964)
		(end 8.655304 -298.669964)
		(width 0.127)
		(layer "In5.Cu")
		(net "T9_BLAD4_EN")
	)
	(segment
		(start 23.35657 -350.245426)
		(end 23.35657 -350.734376)
		(width 0.127)
		(layer "In5.Cu")
		(net "T9_BLAD4_EN")
	)
	(segment
		(start 45.108876 -357.321612)
		(end 46.488604 -355.941884)
		(width 0.127)
		(layer "In5.Cu")
		(net "T9_BLAD4_EN")
	)
	(segment
		(start 46.488604 -355.941884)
		(end 81.128616 -355.941884)
		(width 0.127)
		(layer "In5.Cu")
		(net "T9_BLAD4_EN")
	)
	(via
		(at 44.725082 -356.189534)
		(size 0.508)
		(drill 0.254)
		(layers "F.Cu" "B.Cu")
		(net "T9_BLAD3_RXD")
	)
	(segment
		(start 24.695404 -293.039292)
		(end 24.695404 -349.68307)
		(width 0.127)
		(layer "In2.Cu")
		(net "T9_BLAD3_RXD")
	)
	(segment
		(start 28.562046 -353.549712)
		(end 42.085768 -353.549712)
		(width 0.127)
		(layer "In2.Cu")
		(net "T9_BLAD3_RXD")
	)
	(segment
		(start 45.639482 -357.103426)
		(end 46.383194 -357.847138)
		(width 0.127)
		(layer "In2.Cu")
		(net "T9_BLAD3_RXD")
	)
	(segment
		(start 9.705848 -291.669724)
		(end 12.13104 -289.244532)
		(width 0.127)
		(layer "In2.Cu")
		(net "T9_BLAD3_RXD")
	)
	(segment
		(start 44.725082 -356.189534)
		(end 45.638974 -357.103426)
		(width 0.127)
		(layer "In2.Cu")
		(net "T9_BLAD3_RXD")
	)
	(segment
		(start 20.900644 -289.244532)
		(end 24.695404 -293.039292)
		(width 0.127)
		(layer "In2.Cu")
		(net "T9_BLAD3_RXD")
	)
	(segment
		(start 42.77995 -354.243894)
		(end 42.77995 -354.244402)
		(width 0.127)
		(layer "In2.Cu")
		(net "T9_BLAD3_RXD")
	)
	(segment
		(start 42.77995 -354.244402)
		(end 44.725082 -356.189534)
		(width 0.127)
		(layer "In2.Cu")
		(net "T9_BLAD3_RXD")
	)
	(segment
		(start 45.638974 -357.103426)
		(end 45.639482 -357.103426)
		(width 0.127)
		(layer "In2.Cu")
		(net "T9_BLAD3_RXD")
	)
	(segment
		(start 8.449818 -291.669724)
		(end 9.705848 -291.669724)
		(width 0.127)
		(layer "In2.Cu")
		(net "T9_BLAD3_RXD")
	)
	(segment
		(start 12.13104 -289.244532)
		(end 20.900644 -289.244532)
		(width 0.127)
		(layer "In2.Cu")
		(net "T9_BLAD3_RXD")
	)
	(segment
		(start 46.383194 -357.847138)
		(end 84.151978 -357.847138)
		(width 0.127)
		(layer "In2.Cu")
		(net "T9_BLAD3_RXD")
	)
	(segment
		(start 24.695404 -349.68307)
		(end 28.562046 -353.549712)
		(width 0.127)
		(layer "In2.Cu")
		(net "T9_BLAD3_RXD")
	)
	(segment
		(start 84.151978 -357.847138)
		(end 86.90991 -360.60507)
		(width 0.127)
		(layer "In2.Cu")
		(net "T9_BLAD3_RXD")
	)
	(segment
		(start 42.085768 -353.549712)
		(end 42.77995 -354.243894)
		(width 0.127)
		(layer "In2.Cu")
		(net "T9_BLAD3_RXD")
	)
	(via
		(at 25.813004 -354.99929)
		(size 0.508)
		(drill 0.254)
		(layers "F.Cu" "B.Cu")
		(net "T9_BLAD2_EN")
	)
	(segment
		(start 6.449822 -300.66996)
		(end 8.548624 -300.66996)
		(width 0.127)
		(layer "In5.Cu")
		(net "T9_BLAD2_EN")
	)
	(segment
		(start 25.813004 -354.99929)
		(end 27.625548 -356.811834)
		(width 0.127)
		(layer "In5.Cu")
		(net "T9_BLAD2_EN")
	)
	(segment
		(start 87.668608 -362.655612)
		(end 88.960452 -362.655612)
		(width 0.127)
		(layer "In5.Cu")
		(net "T9_BLAD2_EN")
	)
	(segment
		(start 22.218396 -315.056012)
		(end 22.218396 -350.041464)
		(width 0.127)
		(layer "In5.Cu")
		(net "T9_BLAD2_EN")
	)
	(segment
		(start 8.548624 -300.66996)
		(end 10.554462 -302.675798)
		(width 0.127)
		(layer "In5.Cu")
		(net "T9_BLAD2_EN")
	)
	(segment
		(start 10.554462 -302.675798)
		(end 10.554462 -303.392078)
		(width 0.127)
		(layer "In5.Cu")
		(net "T9_BLAD2_EN")
	)
	(segment
		(start 39.868348 -358.284018)
		(end 83.297014 -358.284018)
		(width 0.127)
		(layer "In5.Cu")
		(net "T9_BLAD2_EN")
	)
	(segment
		(start 22.218396 -350.041464)
		(end 22.61489 -350.437958)
		(width 0.127)
		(layer "In5.Cu")
		(net "T9_BLAD2_EN")
	)
	(segment
		(start 88.960452 -362.655612)
		(end 89.44991 -363.14507)
		(width 0.127)
		(layer "In5.Cu")
		(net "T9_BLAD2_EN")
	)
	(segment
		(start 83.297014 -358.284018)
		(end 87.668608 -362.655612)
		(width 0.127)
		(layer "In5.Cu")
		(net "T9_BLAD2_EN")
	)
	(segment
		(start 22.61489 -351.801176)
		(end 25.813004 -354.99929)
		(width 0.127)
		(layer "In5.Cu")
		(net "T9_BLAD2_EN")
	)
	(segment
		(start 10.554462 -303.392078)
		(end 22.218396 -315.056012)
		(width 0.127)
		(layer "In5.Cu")
		(net "T9_BLAD2_EN")
	)
	(segment
		(start 27.625548 -356.811834)
		(end 38.396164 -356.811834)
		(width 0.127)
		(layer "In5.Cu")
		(net "T9_BLAD2_EN")
	)
	(segment
		(start 22.61489 -350.437958)
		(end 22.61489 -351.801176)
		(width 0.127)
		(layer "In5.Cu")
		(net "T9_BLAD2_EN")
	)
	(segment
		(start 38.396164 -356.811834)
		(end 39.868348 -358.284018)
		(width 0.127)
		(layer "In5.Cu")
		(net "T9_BLAD2_EN")
	)
	(via
		(at 79.802482 -356.469442)
		(size 0.508)
		(drill 0.254)
		(layers "F.Cu" "B.Cu")
		(net "T9_BLAD3_EN")
	)
	(segment
		(start 84.871814 -358.287574)
		(end 83.053682 -356.469442)
		(width 0.127)
		(layer "In5.Cu")
		(net "T9_BLAD3_EN")
	)
	(segment
		(start 22.957282 -350.313244)
		(end 22.957282 -351.18675)
		(width 0.127)
		(layer "In5.Cu")
		(net "T9_BLAD3_EN")
	)
	(segment
		(start 22.957282 -351.18675)
		(end 28.239974 -356.469442)
		(width 0.127)
		(layer "In5.Cu")
		(net "T9_BLAD3_EN")
	)
	(segment
		(start 22.548596 -314.770008)
		(end 22.548596 -349.904558)
		(width 0.127)
		(layer "In5.Cu")
		(net "T9_BLAD3_EN")
	)
	(segment
		(start 40.071802 -357.81361)
		(end 48.876712 -357.81361)
		(width 0.127)
		(layer "In5.Cu")
		(net "T9_BLAD3_EN")
	)
	(segment
		(start 50.22088 -356.469442)
		(end 79.802482 -356.469442)
		(width 0.127)
		(layer "In5.Cu")
		(net "T9_BLAD3_EN")
	)
	(segment
		(start 83.053682 -356.469442)
		(end 79.802482 -356.469442)
		(width 0.127)
		(layer "In5.Cu")
		(net "T9_BLAD3_EN")
	)
	(segment
		(start 12.854178 -305.07559)
		(end 22.548596 -314.770008)
		(width 0.127)
		(layer "In5.Cu")
		(net "T9_BLAD3_EN")
	)
	(segment
		(start 11.4935 -302.713644)
		(end 11.4935 -303.715166)
		(width 0.127)
		(layer "In5.Cu")
		(net "T9_BLAD3_EN")
	)
	(segment
		(start 22.548596 -349.904558)
		(end 22.957282 -350.313244)
		(width 0.127)
		(layer "In5.Cu")
		(net "T9_BLAD3_EN")
	)
	(segment
		(start 12.853924 -305.07559)
		(end 12.854178 -305.07559)
		(width 0.127)
		(layer "In5.Cu")
		(net "T9_BLAD3_EN")
	)
	(segment
		(start 38.727634 -356.469442)
		(end 40.071802 -357.81361)
		(width 0.127)
		(layer "In5.Cu")
		(net "T9_BLAD3_EN")
	)
	(segment
		(start 11.4935 -303.715166)
		(end 12.853924 -305.07559)
		(width 0.127)
		(layer "In5.Cu")
		(net "T9_BLAD3_EN")
	)
	(segment
		(start 8.449818 -299.669962)
		(end 11.4935 -302.713644)
		(width 0.127)
		(layer "In5.Cu")
		(net "T9_BLAD3_EN")
	)
	(segment
		(start 86.215982 -358.287574)
		(end 84.871814 -358.287574)
		(width 0.127)
		(layer "In5.Cu")
		(net "T9_BLAD3_EN")
	)
	(segment
		(start 88.17991 -360.251502)
		(end 86.215982 -358.287574)
		(width 0.127)
		(layer "In5.Cu")
		(net "T9_BLAD3_EN")
	)
	(segment
		(start 28.239974 -356.469442)
		(end 38.727634 -356.469442)
		(width 0.127)
		(layer "In5.Cu")
		(net "T9_BLAD3_EN")
	)
	(segment
		(start 48.876712 -357.81361)
		(end 50.22088 -356.469442)
		(width 0.127)
		(layer "In5.Cu")
		(net "T9_BLAD3_EN")
	)
	(segment
		(start 88.17991 -361.87507)
		(end 88.17991 -360.251502)
		(width 0.127)
		(layer "In5.Cu")
		(net "T9_BLAD3_EN")
	)
	(segment
		(start 9.03732 -221.668848)
		(end 9.862566 -222.494094)
		(width 0.1524)
		(layer "F.Cu")
		(net "I2C_PSU1_SDA")
	)
	(segment
		(start 9.862566 -222.494094)
		(end 9.862566 -224.819464)
		(width 0.1524)
		(layer "F.Cu")
		(net "I2C_PSU1_SDA")
	)
	(segment
		(start 6.880352 -220.82887)
		(end 7.72033 -221.668848)
		(width 0.1524)
		(layer "F.Cu")
		(net "I2C_PSU1_SDA")
	)
	(segment
		(start 9.862566 -224.819464)
		(end 15.523718 -230.480616)
		(width 0.1524)
		(layer "F.Cu")
		(net "I2C_PSU1_SDA")
	)
	(segment
		(start 5.047996 -219.607384)
		(end 6.269482 -220.82887)
		(width 0.1524)
		(layer "F.Cu")
		(net "I2C_PSU1_SDA")
	)
	(segment
		(start 5.047996 -218.769692)
		(end 5.047996 -219.607384)
		(width 0.1524)
		(layer "F.Cu")
		(net "I2C_PSU1_SDA")
	)
	(segment
		(start 7.72033 -221.668848)
		(end 9.03732 -221.668848)
		(width 0.1524)
		(layer "F.Cu")
		(net "I2C_PSU1_SDA")
	)
	(segment
		(start 6.269482 -220.82887)
		(end 6.880352 -220.82887)
		(width 0.1524)
		(layer "F.Cu")
		(net "I2C_PSU1_SDA")
	)
	(segment
		(start 3.948938 -217.670634)
		(end 5.047996 -218.769692)
		(width 0.1524)
		(layer "F.Cu")
		(net "I2C_PSU1_SDA")
	)
	(segment
		(start 15.523718 -230.480616)
		(end 23.528782 -230.480616)
		(width 0.1524)
		(layer "F.Cu")
		(net "I2C_PSU1_SDA")
	)
	(via
		(at 23.528782 -230.480616)
		(size 0.508)
		(drill 0.254)
		(layers "F.Cu" "B.Cu")
		(net "I2C_PSU1_SDA")
	)
	(segment
		(start 24.201882 -112.862106)
		(end 30.063186 -107.000802)
		(width 0.1524)
		(layer "B.Cu")
		(net "I2C_PSU1_SDA")
	)
	(segment
		(start 30.063186 -107.000802)
		(end 36.12642 -107.000802)
		(width 0.1524)
		(layer "B.Cu")
		(net "I2C_PSU1_SDA")
	)
	(segment
		(start 24.080216 -203.915264)
		(end 30.04439 -197.95109)
		(width 0.1524)
		(layer "B.Cu")
		(net "I2C_PSU1_SDA")
	)
	(segment
		(start 33.085786 -181.073806)
		(end 24.201882 -172.189902)
		(width 0.1524)
		(layer "B.Cu")
		(net "I2C_PSU1_SDA")
	)
	(segment
		(start 35.665918 -18.600674)
		(end 28.167076 -18.600674)
		(width 0.1524)
		(layer "B.Cu")
		(net "I2C_PSU1_SDA")
	)
	(segment
		(start 30.04439 -197.95109)
		(end 31.098744 -197.95109)
		(width 0.1524)
		(layer "B.Cu")
		(net "I2C_PSU1_SDA")
	)
	(segment
		(start 31.098744 -197.95109)
		(end 33.085786 -195.964048)
		(width 0.1524)
		(layer "B.Cu")
		(net "I2C_PSU1_SDA")
	)
	(segment
		(start 24.201882 -172.189902)
		(end 24.201882 -112.862106)
		(width 0.1524)
		(layer "B.Cu")
		(net "I2C_PSU1_SDA")
	)
	(segment
		(start 33.085786 -195.964048)
		(end 33.085786 -181.073806)
		(width 0.1524)
		(layer "B.Cu")
		(net "I2C_PSU1_SDA")
	)
	(segment
		(start 35.53968 -4.590034)
		(end 37.081206 -6.13156)
		(width 0.1524)
		(layer "B.Cu")
		(net "I2C_PSU1_SDA")
	)
	(segment
		(start 28.167076 -18.600674)
		(end 25.70861 -21.05914)
		(width 0.1524)
		(layer "B.Cu")
		(net "I2C_PSU1_SDA")
	)
	(segment
		(start 37.145214 -105.982008)
		(end 37.145214 -94.595442)
		(width 0.1524)
		(layer "B.Cu")
		(net "I2C_PSU1_SDA")
	)
	(segment
		(start 37.081206 -17.185386)
		(end 35.665918 -18.600674)
		(width 0.1524)
		(layer "B.Cu")
		(net "I2C_PSU1_SDA")
	)
	(segment
		(start 25.70861 -21.05914)
		(end 25.70861 -83.921346)
		(width 0.1524)
		(layer "B.Cu")
		(net "I2C_PSU1_SDA")
	)
	(segment
		(start 37.145214 -94.595442)
		(end 35.53968 -92.989908)
		(width 0.1524)
		(layer "B.Cu")
		(net "I2C_PSU1_SDA")
	)
	(segment
		(start 25.70861 -83.921346)
		(end 34.777172 -92.989908)
		(width 0.1524)
		(layer "B.Cu")
		(net "I2C_PSU1_SDA")
	)
	(segment
		(start 36.12642 -107.000802)
		(end 37.145214 -105.982008)
		(width 0.1524)
		(layer "B.Cu")
		(net "I2C_PSU1_SDA")
	)
	(segment
		(start 34.777172 -92.989908)
		(end 35.53968 -92.989908)
		(width 0.1524)
		(layer "B.Cu")
		(net "I2C_PSU1_SDA")
	)
	(segment
		(start 23.528782 -230.480616)
		(end 24.080216 -229.929182)
		(width 0.1524)
		(layer "B.Cu")
		(net "I2C_PSU1_SDA")
	)
	(segment
		(start 24.080216 -229.929182)
		(end 24.080216 -203.915264)
		(width 0.1524)
		(layer "B.Cu")
		(net "I2C_PSU1_SDA")
	)
	(segment
		(start 37.081206 -6.13156)
		(end 37.081206 -17.185386)
		(width 0.1524)
		(layer "B.Cu")
		(net "I2C_PSU1_SDA")
	)
	(segment
		(start 3.578098 -220.637862)
		(end 2.70002 -219.759784)
		(width 0.1524)
		(layer "F.Cu")
		(net "I2C_PSU1_SCL")
	)
	(segment
		(start 2.70002 -219.759784)
		(end 2.70002 -219.42171)
		(width 0.1524)
		(layer "F.Cu")
		(net "I2C_PSU1_SCL")
	)
	(segment
		(start 4.093464 -220.637862)
		(end 3.578098 -220.637862)
		(width 0.1524)
		(layer "F.Cu")
		(net "I2C_PSU1_SCL")
	)
	(segment
		(start 14.429994 -231.217724)
		(end 8.953754 -225.741484)
		(width 0.1524)
		(layer "F.Cu")
		(net "I2C_PSU1_SCL")
	)
	(segment
		(start 24.252428 -230.5939)
		(end 23.628604 -231.217724)
		(width 0.1524)
		(layer "F.Cu")
		(net "I2C_PSU1_SCL")
	)
	(segment
		(start 6.51764 -224.952052)
		(end 5.066792 -223.501204)
		(width 0.1524)
		(layer "F.Cu")
		(net "I2C_PSU1_SCL")
	)
	(segment
		(start 7.26186 -224.952052)
		(end 6.51764 -224.952052)
		(width 0.1524)
		(layer "F.Cu")
		(net "I2C_PSU1_SCL")
	)
	(segment
		(start 23.628604 -231.217724)
		(end 14.429994 -231.217724)
		(width 0.1524)
		(layer "F.Cu")
		(net "I2C_PSU1_SCL")
	)
	(segment
		(start 8.051292 -225.741484)
		(end 7.26186 -224.952052)
		(width 0.1524)
		(layer "F.Cu")
		(net "I2C_PSU1_SCL")
	)
	(segment
		(start 2.70002 -219.42171)
		(end 1.948942 -218.670632)
		(width 0.1524)
		(layer "F.Cu")
		(net "I2C_PSU1_SCL")
	)
	(segment
		(start 23.422864 -228.56571)
		(end 24.252428 -229.395274)
		(width 0.1524)
		(layer "F.Cu")
		(net "I2C_PSU1_SCL")
	)
	(segment
		(start 5.066792 -221.61119)
		(end 4.093464 -220.637862)
		(width 0.1524)
		(layer "F.Cu")
		(net "I2C_PSU1_SCL")
	)
	(segment
		(start 24.252428 -229.395274)
		(end 24.252428 -230.5939)
		(width 0.1524)
		(layer "F.Cu")
		(net "I2C_PSU1_SCL")
	)
	(segment
		(start 8.953754 -225.741484)
		(end 8.051292 -225.741484)
		(width 0.1524)
		(layer "F.Cu")
		(net "I2C_PSU1_SCL")
	)
	(segment
		(start 5.066792 -223.501204)
		(end 5.066792 -221.61119)
		(width 0.1524)
		(layer "F.Cu")
		(net "I2C_PSU1_SCL")
	)
	(via
		(at 23.422864 -228.56571)
		(size 0.508)
		(drill 0.254)
		(layers "F.Cu" "B.Cu")
		(net "I2C_PSU1_SCL")
	)
	(segment
		(start 23.77821 -112.423194)
		(end 29.34335 -106.858054)
		(width 0.1524)
		(layer "B.Cu")
		(net "I2C_PSU1_SCL")
	)
	(segment
		(start 23.422864 -228.56571)
		(end 23.422864 -224.123758)
		(width 0.1524)
		(layer "B.Cu")
		(net "I2C_PSU1_SCL")
	)
	(segment
		(start 31.38551 -195.146168)
		(end 32.467804 -194.063874)
		(width 0.1524)
		(layer "B.Cu")
		(net "I2C_PSU1_SCL")
	)
	(segment
		(start 23.657306 -201.813922)
		(end 30.32506 -195.146168)
		(width 0.1524)
		(layer "B.Cu")
		(net "I2C_PSU1_SCL")
	)
	(segment
		(start 23.422864 -224.123758)
		(end 23.657306 -223.889316)
		(width 0.1524)
		(layer "B.Cu")
		(net "I2C_PSU1_SCL")
	)
	(segment
		(start 32.467804 -181.09819)
		(end 23.77821 -172.408596)
		(width 0.1524)
		(layer "B.Cu")
		(net "I2C_PSU1_SCL")
	)
	(segment
		(start 30.292802 -104.262682)
		(end 31.14167 -104.262682)
		(width 0.1524)
		(layer "B.Cu")
		(net "I2C_PSU1_SCL")
	)
	(segment
		(start 30.32506 -195.146168)
		(end 31.38551 -195.146168)
		(width 0.1524)
		(layer "B.Cu")
		(net "I2C_PSU1_SCL")
	)
	(segment
		(start 29.330396 -10.980166)
		(end 28.343352 -11.96721)
		(width 0.1524)
		(layer "B.Cu")
		(net "I2C_PSU1_SCL")
	)
	(segment
		(start 34.409888 -99.1997)
		(end 35.53968 -98.069908)
		(width 0.1524)
		(layer "B.Cu")
		(net "I2C_PSU1_SCL")
	)
	(segment
		(start 28.343352 -11.96721)
		(end 28.343352 -16.170148)
		(width 0.1524)
		(layer "B.Cu")
		(net "I2C_PSU1_SCL")
	)
	(segment
		(start 24.916638 -84.312252)
		(end 34.409888 -93.805502)
		(width 0.1524)
		(layer "B.Cu")
		(net "I2C_PSU1_SCL")
	)
	(segment
		(start 23.657306 -223.889316)
		(end 23.657306 -201.813922)
		(width 0.1524)
		(layer "B.Cu")
		(net "I2C_PSU1_SCL")
	)
	(segment
		(start 34.409888 -100.994464)
		(end 34.409888 -99.1997)
		(width 0.1524)
		(layer "B.Cu")
		(net "I2C_PSU1_SCL")
	)
	(segment
		(start 31.14167 -104.262682)
		(end 34.409888 -100.994464)
		(width 0.1524)
		(layer "B.Cu")
		(net "I2C_PSU1_SCL")
	)
	(segment
		(start 34.409888 -96.940116)
		(end 35.53968 -98.069908)
		(width 0.1524)
		(layer "B.Cu")
		(net "I2C_PSU1_SCL")
	)
	(segment
		(start 34.409888 -93.805502)
		(end 34.409888 -96.940116)
		(width 0.1524)
		(layer "B.Cu")
		(net "I2C_PSU1_SCL")
	)
	(segment
		(start 23.77821 -172.408596)
		(end 23.77821 -112.423194)
		(width 0.1524)
		(layer "B.Cu")
		(net "I2C_PSU1_SCL")
	)
	(segment
		(start 34.229548 -10.980166)
		(end 29.330396 -10.980166)
		(width 0.1524)
		(layer "B.Cu")
		(net "I2C_PSU1_SCL")
	)
	(segment
		(start 28.343352 -16.170148)
		(end 24.916638 -19.596862)
		(width 0.1524)
		(layer "B.Cu")
		(net "I2C_PSU1_SCL")
	)
	(segment
		(start 29.34335 -106.858054)
		(end 29.34335 -105.212134)
		(width 0.1524)
		(layer "B.Cu")
		(net "I2C_PSU1_SCL")
	)
	(segment
		(start 24.916638 -19.596862)
		(end 24.916638 -84.312252)
		(width 0.1524)
		(layer "B.Cu")
		(net "I2C_PSU1_SCL")
	)
	(segment
		(start 29.34335 -105.212134)
		(end 30.292802 -104.262682)
		(width 0.1524)
		(layer "B.Cu")
		(net "I2C_PSU1_SCL")
	)
	(segment
		(start 35.53968 -9.670034)
		(end 34.229548 -10.980166)
		(width 0.1524)
		(layer "B.Cu")
		(net "I2C_PSU1_SCL")
	)
	(segment
		(start 32.467804 -194.063874)
		(end 32.467804 -181.09819)
		(width 0.1524)
		(layer "B.Cu")
		(net "I2C_PSU1_SCL")
	)
	(zone
		(layer "F.Cu")
		(hatch none 0.5)
		(connect_pads
			(clearance 0)
		)
		(min_thickness 0.25)
		(keepout
			(tracks not_allowed)
			(vias allowed)
			(pads allowed)
			(copperpour not_allowed)
			(footprints allowed)
		)
		(placement
			(enabled no)
			(sheetname "")
		)
		(fill
			(thermal_gap 0.5)
			(thermal_bridge_width 0.5)
			(island_removal_mode 0)
		)
		(polygon
			(pts
				(arc
					(start 14.59992 -473.700094)
					(mid 16.599916 -471.700098)
					(end 18.599912 -473.700094)
				)
				(arc
					(start 18.599912 -473.700094)
					(mid 16.599916 -475.70009)
					(end 14.59992 -473.700094)
				)
			)
		)
	)
	(zone
		(layer "F.Cu")
		(hatch none 0.5)
		(connect_pads
			(clearance 0)
		)
		(min_thickness 0.25)
		(keepout
			(tracks allowed)
			(vias allowed)
			(pads allowed)
			(copperpour allowed)
			(footprints not_allowed)
		)
		(placement
			(enabled no)
			(sheetname "")
		)
		(fill
			(thermal_gap 0.5)
			(thermal_bridge_width 0.5)
			(island_removal_mode 0)
		)
		(polygon
			(pts
				(xy 55.999888 -54.749954) (xy 55.999888 -79.749904) (xy 44.99991 -79.749904) (xy 44.99991 -54.749954)
			)
		)
	)
	(zone
		(layer "F.Cu")
		(hatch none 0.5)
		(connect_pads
			(clearance 0)
		)
		(min_thickness 0.25)
		(keepout
			(tracks not_allowed)
			(vias allowed)
			(pads allowed)
			(copperpour not_allowed)
			(footprints allowed)
		)
		(placement
			(enabled no)
			(sheetname "")
		)
		(fill
			(thermal_gap 0.5)
			(thermal_bridge_width 0.5)
			(island_removal_mode 0)
		)
		(polygon
			(pts
				(arc
					(start 87.399876 -508.96012)
					(mid 91.400122 -504.959874)
					(end 95.400114 -508.96012)
				)
				(arc
					(start 95.400114 -508.96012)
					(mid 91.400122 -512.960112)
					(end 87.399876 -508.96012)
				)
			)
		)
	)
	(zone
		(layer "F.Cu")
		(hatch none 0.5)
		(connect_pads
			(clearance 0)
		)
		(min_thickness 0.25)
		(keepout
			(tracks allowed)
			(vias allowed)
			(pads allowed)
			(copperpour allowed)
			(footprints not_allowed)
		)
		(placement
			(enabled no)
			(sheetname "")
		)
		(fill
			(thermal_gap 0.5)
			(thermal_bridge_width 0.5)
			(island_removal_mode 0)
		)
		(polygon
			(pts
				(arc
					(start 73.000108 -430.150016)
					(mid 78.000098 -425.150026)
					(end 83.000088 -430.150016)
				)
				(arc
					(start 83.000088 -430.150016)
					(mid 78.000098 -435.150006)
					(end 73.000108 -430.150016)
				)
			)
		)
	)
	(zone
		(layer "F.Cu")
		(hatch none 0.5)
		(connect_pads
			(clearance 0)
		)
		(min_thickness 0.25)
		(keepout
			(tracks not_allowed)
			(vias allowed)
			(pads allowed)
			(copperpour not_allowed)
			(footprints allowed)
		)
		(placement
			(enabled no)
			(sheetname "")
		)
		(fill
			(thermal_gap 0.5)
			(thermal_bridge_width 0.5)
			(island_removal_mode 0)
		)
		(polygon
			(pts
				(arc
					(start 87.399876 -331.16012)
					(mid 91.400122 -327.159874)
					(end 95.400114 -331.16012)
				)
				(arc
					(start 95.400114 -331.16012)
					(mid 91.400122 -335.160112)
					(end 87.399876 -331.16012)
				)
			)
		)
	)
	(zone
		(layer "F.Cu")
		(hatch none 0.5)
		(connect_pads
			(clearance 0)
		)
		(min_thickness 0.25)
		(keepout
			(tracks allowed)
			(vias allowed)
			(pads allowed)
			(copperpour allowed)
			(footprints not_allowed)
		)
		(placement
			(enabled no)
			(sheetname "")
		)
		(fill
			(thermal_gap 0.5)
			(thermal_bridge_width 0.5)
			(island_removal_mode 0)
		)
		(polygon
			(pts
				(xy 44.99991 -54.749954) (xy 44.99991 -79.749904) (xy 55.999888 -79.749904) (xy 55.999888 -54.749954)
			)
		)
	)
	(zone
		(layer "F.Cu")
		(hatch none 0.5)
		(connect_pads
			(clearance 0)
		)
		(min_thickness 0.25)
		(keepout
			(tracks not_allowed)
			(vias allowed)
			(pads allowed)
			(copperpour not_allowed)
			(footprints allowed)
		)
		(placement
			(enabled no)
			(sheetname "")
		)
		(fill
			(thermal_gap 0.5)
			(thermal_bridge_width 0.5)
			(island_removal_mode 0)
		)
		(polygon
			(pts
				(arc
					(start 96.400112 -286.71012)
					(mid 91.400122 -291.71011)
					(end 86.399878 -286.71012)
				)
				(arc
					(start 86.399878 -286.71012)
					(mid 91.400122 -281.709876)
					(end 96.400112 -286.71012)
				)
			)
		)
	)
	(zone
		(layer "F.Cu")
		(hatch none 0.5)
		(connect_pads
			(clearance 0)
		)
		(min_thickness 0.25)
		(keepout
			(tracks allowed)
			(vias allowed)
			(pads allowed)
			(copperpour allowed)
			(footprints not_allowed)
		)
		(placement
			(enabled no)
			(sheetname "")
		)
		(fill
			(thermal_gap 0.5)
			(thermal_bridge_width 0.5)
			(island_removal_mode 0)
		)
		(polygon
			(pts
				(xy 55.999888 -99.199954) (xy 55.999888 -124.199904) (xy 44.99991 -124.199904) (xy 44.99991 -99.199954)
			)
		)
	)
	(zone
		(layer "F.Cu")
		(hatch none 0.5)
		(connect_pads
			(clearance 0)
		)
		(min_thickness 0.25)
		(keepout
			(tracks not_allowed)
			(vias allowed)
			(pads allowed)
			(copperpour not_allowed)
			(footprints allowed)
		)
		(placement
			(enabled no)
			(sheetname "")
		)
		(fill
			(thermal_gap 0.5)
			(thermal_bridge_width 0.5)
			(island_removal_mode 0)
		)
		(polygon
			(pts
				(arc
					(start 87.399876 -20.01012)
					(mid 91.400122 -16.009874)
					(end 95.400114 -20.01012)
				)
				(arc
					(start 95.400114 -20.01012)
					(mid 91.400122 -24.010112)
					(end 87.399876 -20.01012)
				)
			)
		)
	)
	(zone
		(layer "F.Cu")
		(hatch none 0.5)
		(connect_pads
			(clearance 0)
		)
		(min_thickness 0.25)
		(keepout
			(tracks allowed)
			(vias allowed)
			(pads allowed)
			(copperpour allowed)
			(footprints not_allowed)
		)
		(placement
			(enabled no)
			(sheetname "")
		)
		(fill
			(thermal_gap 0.5)
			(thermal_bridge_width 0.5)
			(island_removal_mode 0)
		)
		(polygon
			(pts
				(arc
					(start 86.399878 -508.96012)
					(mid 91.400122 -503.959876)
					(end 96.400112 -508.96012)
				)
				(arc
					(start 96.400112 -508.96012)
					(mid 91.400122 -513.96011)
					(end 86.399878 -508.96012)
				)
			)
		)
	)
	(zone
		(layer "F.Cu")
		(hatch none 0.5)
		(connect_pads
			(clearance 0)
		)
		(min_thickness 0.25)
		(keepout
			(tracks allowed)
			(vias allowed)
			(pads allowed)
			(copperpour allowed)
			(footprints not_allowed)
		)
		(placement
			(enabled no)
			(sheetname "")
		)
		(fill
			(thermal_gap 0.5)
			(thermal_bridge_width 0.5)
			(island_removal_mode 0)
		)
		(polygon
			(pts
				(arc
					(start 86.399878 -153.36012)
					(mid 91.400122 -148.359876)
					(end 96.400112 -153.36012)
				)
				(arc
					(start 96.400112 -153.36012)
					(mid 91.400122 -158.36011)
					(end 86.399878 -153.36012)
				)
			)
		)
	)
	(zone
		(layer "F.Cu")
		(hatch none 0.5)
		(connect_pads
			(clearance 0)
		)
		(min_thickness 0.25)
		(keepout
			(tracks not_allowed)
			(vias allowed)
			(pads allowed)
			(copperpour not_allowed)
			(footprints allowed)
		)
		(placement
			(enabled no)
			(sheetname "")
		)
		(fill
			(thermal_gap 0.5)
			(thermal_bridge_width 0.5)
			(island_removal_mode 0)
		)
		(polygon
			(pts
				(arc
					(start 76.000102 -210.09991)
					(mid 78.000098 -208.099914)
					(end 80.000094 -210.09991)
				)
				(arc
					(start 80.000094 -210.09991)
					(mid 78.000098 -212.099906)
					(end 76.000102 -210.09991)
				)
			)
		)
	)
	(zone
		(layer "F.Cu")
		(hatch none 0.5)
		(connect_pads
			(clearance 0)
		)
		(min_thickness 0.25)
		(keepout
			(tracks allowed)
			(vias allowed)
			(pads allowed)
			(copperpour allowed)
			(footprints not_allowed)
		)
		(placement
			(enabled no)
			(sheetname "")
		)
		(fill
			(thermal_gap 0.5)
			(thermal_bridge_width 0.5)
			(island_removal_mode 0)
		)
		(polygon
			(pts
				(xy 55.999888 -321.449954) (xy 55.999888 -346.449904) (xy 44.99991 -346.449904) (xy 44.99991 -321.449954)
			)
		)
	)
	(zone
		(layer "F.Cu")
		(hatch none 0.5)
		(connect_pads
			(clearance 0)
		)
		(min_thickness 0.25)
		(keepout
			(tracks not_allowed)
			(vias allowed)
			(pads allowed)
			(copperpour not_allowed)
			(footprints allowed)
		)
		(placement
			(enabled no)
			(sheetname "")
		)
		(fill
			(thermal_gap 0.5)
			(thermal_bridge_width 0.5)
			(island_removal_mode 0)
		)
		(polygon
			(pts
				(arc
					(start 21.599906 -207.000094)
					(mid 16.599916 -212.000084)
					(end 11.599926 -207.000094)
				)
				(arc
					(start 11.599926 -207.000094)
					(mid 16.599916 -202.000104)
					(end 21.599906 -207.000094)
				)
			)
		)
	)
	(zone
		(layer "F.Cu")
		(hatch none 0.5)
		(connect_pads
			(clearance 0)
		)
		(min_thickness 0.25)
		(keepout
			(tracks not_allowed)
			(vias allowed)
			(pads allowed)
			(copperpour not_allowed)
			(footprints allowed)
		)
		(placement
			(enabled no)
			(sheetname "")
		)
		(fill
			(thermal_gap 0.5)
			(thermal_bridge_width 0.5)
			(island_removal_mode 0)
		)
		(polygon
			(pts
				(arc
					(start 76.000102 -32.29991)
					(mid 78.000098 -30.299914)
					(end 80.000094 -32.29991)
				)
				(arc
					(start 80.000094 -32.29991)
					(mid 78.000098 -34.299906)
					(end 76.000102 -32.29991)
				)
			)
		)
	)
	(zone
		(layer "F.Cu")
		(hatch none 0.5)
		(connect_pads
			(clearance 0)
		)
		(min_thickness 0.25)
		(keepout
			(tracks not_allowed)
			(vias allowed)
			(pads allowed)
			(copperpour not_allowed)
			(footprints allowed)
		)
		(placement
			(enabled no)
			(sheetname "")
		)
		(fill
			(thermal_gap 0.5)
			(thermal_bridge_width 0.5)
			(island_removal_mode 0)
		)
		(polygon
			(pts
				(arc
					(start 14.59992 -207.000094)
					(mid 16.599916 -205.000098)
					(end 18.599912 -207.000094)
				)
				(arc
					(start 18.599912 -207.000094)
					(mid 16.599916 -209.00009)
					(end 14.59992 -207.000094)
				)
			)
		)
	)
	(zone
		(layer "F.Cu")
		(hatch none 0.5)
		(connect_pads
			(clearance 0)
		)
		(min_thickness 0.25)
		(keepout
			(tracks not_allowed)
			(vias allowed)
			(pads allowed)
			(copperpour not_allowed)
			(footprints allowed)
		)
		(placement
			(enabled no)
			(sheetname "")
		)
		(fill
			(thermal_gap 0.5)
			(thermal_bridge_width 0.5)
			(island_removal_mode 0)
		)
		(polygon
			(pts
				(arc
					(start 21.599906 -29.200094)
					(mid 16.599916 -34.200084)
					(end 11.599926 -29.200094)
				)
				(arc
					(start 11.599926 -29.200094)
					(mid 16.599916 -24.200104)
					(end 21.599906 -29.200094)
				)
			)
		)
	)
	(zone
		(layer "F.Cu")
		(hatch none 0.5)
		(connect_pads
			(clearance 0)
		)
		(min_thickness 0.25)
		(keepout
			(tracks not_allowed)
			(vias allowed)
			(pads allowed)
			(copperpour not_allowed)
			(footprints allowed)
		)
		(placement
			(enabled no)
			(sheetname "")
		)
		(fill
			(thermal_gap 0.5)
			(thermal_bridge_width 0.5)
			(island_removal_mode 0)
		)
		(polygon
			(pts
				(arc
					(start 87.399876 -153.36012)
					(mid 91.400122 -149.359874)
					(end 95.400114 -153.36012)
				)
				(arc
					(start 95.400114 -153.36012)
					(mid 91.400122 -157.360112)
					(end 87.399876 -153.36012)
				)
			)
		)
	)
	(zone
		(layer "F.Cu")
		(hatch none 0.5)
		(connect_pads
			(clearance 0)
		)
		(min_thickness 0.25)
		(keepout
			(tracks allowed)
			(vias allowed)
			(pads allowed)
			(copperpour allowed)
			(footprints not_allowed)
		)
		(placement
			(enabled no)
			(sheetname "")
		)
		(fill
			(thermal_gap 0.5)
			(thermal_bridge_width 0.5)
			(island_removal_mode 0)
		)
		(polygon
			(pts
				(xy 55.999888 -499.249954) (xy 55.999888 -524.249904) (xy 44.99991 -524.249904) (xy 44.99991 -499.249954)
			)
		)
	)
	(zone
		(layer "F.Cu")
		(hatch none 0.5)
		(connect_pads
			(clearance 0)
		)
		(min_thickness 0.25)
		(keepout
			(tracks allowed)
			(vias allowed)
			(pads allowed)
			(copperpour allowed)
			(footprints not_allowed)
		)
		(placement
			(enabled no)
			(sheetname "")
		)
		(fill
			(thermal_gap 0.5)
			(thermal_bridge_width 0.5)
			(island_removal_mode 0)
		)
		(polygon
			(pts
				(xy 44.99991 -365.899954) (xy 44.99991 -390.899904) (xy 55.999888 -390.899904) (xy 55.999888 -365.899954)
			)
		)
	)
	(zone
		(layer "F.Cu")
		(hatch none 0.5)
		(connect_pads
			(clearance 0)
		)
		(min_thickness 0.25)
		(keepout
			(tracks allowed)
			(vias allowed)
			(pads allowed)
			(copperpour allowed)
			(footprints not_allowed)
		)
		(placement
			(enabled no)
			(sheetname "")
		)
		(fill
			(thermal_gap 0.5)
			(thermal_bridge_width 0.5)
			(island_removal_mode 0)
		)
		(polygon
			(pts
				(xy 0.895096 -144.949926) (xy 0.895096 -127.649986) (xy 17.645126 -127.649986) (xy 17.645126 -144.949926)
			)
		)
	)
	(zone
		(layer "F.Cu")
		(hatch none 0.5)
		(connect_pads
			(clearance 0)
		)
		(min_thickness 0.25)
		(keepout
			(tracks allowed)
			(vias allowed)
			(pads allowed)
			(copperpour allowed)
			(footprints not_allowed)
		)
		(placement
			(enabled no)
			(sheetname "")
		)
		(fill
			(thermal_gap 0.5)
			(thermal_bridge_width 0.5)
			(island_removal_mode 0)
		)
		(polygon
			(pts
				(arc
					(start 21.599906 -29.200094)
					(mid 16.599916 -34.200084)
					(end 11.599926 -29.200094)
				)
				(arc
					(start 11.599926 -29.200094)
					(mid 16.599916 -24.200104)
					(end 21.599906 -29.200094)
				)
			)
		)
	)
	(zone
		(layer "F.Cu")
		(hatch none 0.5)
		(connect_pads
			(clearance 0)
		)
		(min_thickness 0.25)
		(keepout
			(tracks not_allowed)
			(vias allowed)
			(pads allowed)
			(copperpour not_allowed)
			(footprints allowed)
		)
		(placement
			(enabled no)
			(sheetname "")
		)
		(fill
			(thermal_gap 0.5)
			(thermal_bridge_width 0.5)
			(island_removal_mode 0)
		)
		(polygon
			(pts
				(arc
					(start 96.400112 -508.96012)
					(mid 91.400122 -513.96011)
					(end 86.399878 -508.96012)
				)
				(arc
					(start 86.399878 -508.96012)
					(mid 91.400122 -503.959876)
					(end 96.400112 -508.96012)
				)
			)
		)
	)
	(zone
		(layer "F.Cu")
		(hatch none 0.5)
		(connect_pads
			(clearance 0)
		)
		(min_thickness 0.25)
		(keepout
			(tracks allowed)
			(vias allowed)
			(pads allowed)
			(copperpour allowed)
			(footprints not_allowed)
		)
		(placement
			(enabled no)
			(sheetname "")
		)
		(fill
			(thermal_gap 0.5)
			(thermal_bridge_width 0.5)
			(island_removal_mode 0)
		)
		(polygon
			(pts
				(arc
					(start 86.399878 -331.16012)
					(mid 91.400122 -326.159876)
					(end 96.400112 -331.16012)
				)
				(arc
					(start 96.400112 -331.16012)
					(mid 91.400122 -336.16011)
					(end 86.399878 -331.16012)
				)
			)
		)
	)
	(zone
		(layer "F.Cu")
		(hatch none 0.5)
		(connect_pads
			(clearance 0)
		)
		(min_thickness 0.25)
		(keepout
			(tracks not_allowed)
			(vias allowed)
			(pads allowed)
			(copperpour not_allowed)
			(footprints allowed)
		)
		(placement
			(enabled no)
			(sheetname "")
		)
		(fill
			(thermal_gap 0.5)
			(thermal_bridge_width 0.5)
			(island_removal_mode 0)
		)
		(polygon
			(pts
				(arc
					(start 87.399876 -108.91012)
					(mid 91.400122 -104.909874)
					(end 95.400114 -108.91012)
				)
				(arc
					(start 95.400114 -108.91012)
					(mid 91.400122 -112.910112)
					(end 87.399876 -108.91012)
				)
			)
		)
	)
	(zone
		(layer "F.Cu")
		(hatch none 0.5)
		(connect_pads
			(clearance 0)
		)
		(min_thickness 0.25)
		(keepout
			(tracks not_allowed)
			(vias allowed)
			(pads allowed)
			(copperpour not_allowed)
			(footprints allowed)
		)
		(placement
			(enabled no)
			(sheetname "")
		)
		(fill
			(thermal_gap 0.5)
			(thermal_bridge_width 0.5)
			(island_removal_mode 0)
		)
		(polygon
			(pts
				(arc
					(start 83.000088 -32.29991)
					(mid 78.000098 -37.2999)
					(end 73.000108 -32.29991)
				)
				(arc
					(start 73.000108 -32.29991)
					(mid 78.000098 -27.29992)
					(end 83.000088 -32.29991)
				)
			)
		)
	)
	(zone
		(layer "F.Cu")
		(hatch none 0.5)
		(connect_pads
			(clearance 0)
		)
		(min_thickness 0.25)
		(keepout
			(tracks allowed)
			(vias allowed)
			(pads allowed)
			(copperpour allowed)
			(footprints not_allowed)
		)
		(placement
			(enabled no)
			(sheetname "")
		)
		(fill
			(thermal_gap 0.5)
			(thermal_bridge_width 0.5)
			(island_removal_mode 0)
		)
		(polygon
			(pts
				(xy 2.325116 -420.900098) (xy 13.875004 -420.900098) (xy 13.875004 -464.90001) (xy 2.325116 -464.90001)
			)
		)
	)
	(zone
		(layer "F.Cu")
		(hatch none 0.5)
		(connect_pads
			(clearance 0)
		)
		(min_thickness 0.25)
		(keepout
			(tracks not_allowed)
			(vias allowed)
			(pads allowed)
			(copperpour not_allowed)
			(footprints allowed)
		)
		(placement
			(enabled no)
			(sheetname "")
		)
		(fill
			(thermal_gap 0.5)
			(thermal_bridge_width 0.5)
			(island_removal_mode 0)
		)
		(polygon
			(pts
				(arc
					(start 21.599906 -118.100094)
					(mid 16.599916 -123.100084)
					(end 11.599926 -118.100094)
				)
				(arc
					(start 11.599926 -118.100094)
					(mid 16.599916 -113.100104)
					(end 21.599906 -118.100094)
				)
			)
		)
	)
	(zone
		(layer "F.Cu")
		(hatch none 0.5)
		(connect_pads
			(clearance 0)
		)
		(min_thickness 0.25)
		(keepout
			(tracks allowed)
			(vias allowed)
			(pads allowed)
			(copperpour allowed)
			(footprints not_allowed)
		)
		(placement
			(enabled no)
			(sheetname "")
		)
		(fill
			(thermal_gap 0.5)
			(thermal_bridge_width 0.5)
			(island_removal_mode 0)
		)
		(polygon
			(pts
				(xy 44.99991 -143.649954) (xy 44.99991 -168.649904) (xy 55.999888 -168.649904) (xy 55.999888 -143.649954)
			)
		)
	)
	(zone
		(layer "F.Cu")
		(hatch none 0.5)
		(connect_pads
			(clearance 0)
		)
		(min_thickness 0.25)
		(keepout
			(tracks allowed)
			(vias allowed)
			(pads allowed)
			(copperpour allowed)
			(footprints not_allowed)
		)
		(placement
			(enabled no)
			(sheetname "")
		)
		(fill
			(thermal_gap 0.5)
			(thermal_bridge_width 0.5)
			(island_removal_mode 0)
		)
		(polygon
			(pts
				(arc
					(start 21.599906 -384.800094)
					(mid 16.599916 -389.800084)
					(end 11.599926 -384.800094)
				)
				(arc
					(start 11.599926 -384.800094)
					(mid 16.599916 -379.800104)
					(end 21.599906 -384.800094)
				)
			)
		)
	)
	(zone
		(layer "F.Cu")
		(hatch none 0.5)
		(connect_pads
			(clearance 0)
		)
		(min_thickness 0.25)
		(keepout
			(tracks allowed)
			(vias allowed)
			(pads allowed)
			(copperpour allowed)
			(footprints not_allowed)
		)
		(placement
			(enabled no)
			(sheetname "")
		)
		(fill
			(thermal_gap 0.5)
			(thermal_bridge_width 0.5)
			(island_removal_mode 0)
		)
		(polygon
			(pts
				(xy 44.99991 -99.199954) (xy 44.99991 -124.199904) (xy 55.999888 -124.199904) (xy 55.999888 -99.199954)
			)
		)
	)
	(zone
		(layer "F.Cu")
		(hatch none 0.5)
		(connect_pads
			(clearance 0)
		)
		(min_thickness 0.25)
		(keepout
			(tracks not_allowed)
			(vias allowed)
			(pads allowed)
			(copperpour not_allowed)
			(footprints allowed)
		)
		(placement
			(enabled no)
			(sheetname "")
		)
		(fill
			(thermal_gap 0.5)
			(thermal_bridge_width 0.5)
			(island_removal_mode 0)
		)
		(polygon
			(pts
				(arc
					(start 75.3999 -78.300072)
					(mid 78.000098 -75.699874)
					(end 80.600042 -78.300072)
				)
				(arc
					(start 80.600042 -78.300072)
					(mid 78.000098 -80.900016)
					(end 75.3999 -78.300072)
				)
			)
		)
	)
	(zone
		(layer "F.Cu")
		(hatch none 0.5)
		(connect_pads
			(clearance 0)
		)
		(min_thickness 0.25)
		(keepout
			(tracks allowed)
			(vias allowed)
			(pads allowed)
			(copperpour allowed)
			(footprints not_allowed)
		)
		(placement
			(enabled no)
			(sheetname "")
		)
		(fill
			(thermal_gap 0.5)
			(thermal_bridge_width 0.5)
			(island_removal_mode 0)
		)
		(polygon
			(pts
				(xy 16.996918 -507.99492) (xy 16.996918 -525.105122) (xy 0.90297 -525.105122) (xy 0.90297 -507.99492)
			)
		)
	)
	(zone
		(layer "F.Cu")
		(hatch none 0.5)
		(connect_pads
			(clearance 0)
		)
		(min_thickness 0.25)
		(keepout
			(tracks allowed)
			(vias allowed)
			(pads allowed)
			(copperpour allowed)
			(footprints not_allowed)
		)
		(placement
			(enabled no)
			(sheetname "")
		)
		(fill
			(thermal_gap 0.5)
			(thermal_bridge_width 0.5)
			(island_removal_mode 0)
		)
		(polygon
			(pts
				(xy 13.875004 -464.90001) (xy 2.325116 -464.90001) (xy 2.325116 -420.900098) (xy 13.875004 -420.900098)
			)
		)
	)
	(zone
		(layer "F.Cu")
		(hatch none 0.5)
		(connect_pads
			(clearance 0)
		)
		(min_thickness 0.25)
		(keepout
			(tracks allowed)
			(vias allowed)
			(pads allowed)
			(copperpour allowed)
			(footprints not_allowed)
		)
		(placement
			(enabled no)
			(sheetname "")
		)
		(fill
			(thermal_gap 0.5)
			(thermal_bridge_width 0.5)
			(island_removal_mode 0)
		)
		(polygon
			(pts
				(xy 55.999888 -10.299954) (xy 55.999888 -35.299904) (xy 44.99991 -35.299904) (xy 44.99991 -10.299954)
			)
		)
	)
	(zone
		(layer "F.Cu")
		(hatch none 0.5)
		(connect_pads
			(clearance 0)
		)
		(min_thickness 0.25)
		(keepout
			(tracks allowed)
			(vias allowed)
			(pads allowed)
			(copperpour allowed)
			(footprints not_allowed)
		)
		(placement
			(enabled no)
			(sheetname "")
		)
		(fill
			(thermal_gap 0.5)
			(thermal_bridge_width 0.5)
			(island_removal_mode 0)
		)
		(polygon
			(pts
				(xy 44.99991 -10.299954) (xy 44.99991 -35.299904) (xy 55.999888 -35.299904) (xy 55.999888 -10.299954)
			)
		)
	)
	(zone
		(layer "F.Cu")
		(hatch none 0.5)
		(connect_pads
			(clearance 0)
		)
		(min_thickness 0.25)
		(keepout
			(tracks allowed)
			(vias allowed)
			(pads allowed)
			(copperpour allowed)
			(footprints not_allowed)
		)
		(placement
			(enabled no)
			(sheetname "")
		)
		(fill
			(thermal_gap 0.5)
			(thermal_bridge_width 0.5)
			(island_removal_mode 0)
		)
		(polygon
			(pts
				(arc
					(start 86.399878 -20.01012)
					(mid 91.400122 -15.009876)
					(end 96.400112 -20.01012)
				)
				(arc
					(start 96.400112 -20.01012)
					(mid 91.400122 -25.01011)
					(end 86.399878 -20.01012)
				)
			)
		)
	)
	(zone
		(layer "F.Cu")
		(hatch none 0.5)
		(connect_pads
			(clearance 0)
		)
		(min_thickness 0.25)
		(keepout
			(tracks allowed)
			(vias allowed)
			(pads allowed)
			(copperpour allowed)
			(footprints not_allowed)
		)
		(placement
			(enabled no)
			(sheetname "")
		)
		(fill
			(thermal_gap 0.5)
			(thermal_bridge_width 0.5)
			(island_removal_mode 0)
		)
		(polygon
			(pts
				(xy 55.999888 -143.649954) (xy 55.999888 -168.649904) (xy 44.99991 -168.649904) (xy 44.99991 -143.649954)
			)
		)
	)
	(zone
		(layer "F.Cu")
		(hatch none 0.5)
		(connect_pads
			(clearance 0)
		)
		(min_thickness 0.25)
		(keepout
			(tracks allowed)
			(vias allowed)
			(pads allowed)
			(copperpour allowed)
			(footprints not_allowed)
		)
		(placement
			(enabled no)
			(sheetname "")
		)
		(fill
			(thermal_gap 0.5)
			(thermal_bridge_width 0.5)
			(island_removal_mode 0)
		)
		(polygon
			(pts
				(xy 16.996918 -481.48494) (xy 16.996918 -498.594888) (xy 0.90297 -498.594888) (xy 0.90297 -481.48494)
			)
		)
	)
	(zone
		(layer "F.Cu")
		(hatch none 0.5)
		(connect_pads
			(clearance 0)
		)
		(min_thickness 0.25)
		(keepout
			(tracks not_allowed)
			(vias allowed)
			(pads allowed)
			(copperpour not_allowed)
			(footprints allowed)
		)
		(placement
			(enabled no)
			(sheetname "")
		)
		(fill
			(thermal_gap 0.5)
			(thermal_bridge_width 0.5)
			(island_removal_mode 0)
		)
		(polygon
			(pts
				(arc
					(start 96.400112 -375.61012)
					(mid 91.400122 -380.61011)
					(end 86.399878 -375.61012)
				)
				(arc
					(start 86.399878 -375.61012)
					(mid 91.400122 -370.609876)
					(end 96.400112 -375.61012)
				)
			)
		)
	)
	(zone
		(layer "F.Cu")
		(hatch none 0.5)
		(connect_pads
			(clearance 0)
		)
		(min_thickness 0.25)
		(keepout
			(tracks allowed)
			(vias allowed)
			(pads allowed)
			(copperpour allowed)
			(footprints not_allowed)
		)
		(placement
			(enabled no)
			(sheetname "")
		)
		(fill
			(thermal_gap 0.5)
			(thermal_bridge_width 0.5)
			(island_removal_mode 0)
		)
		(polygon
			(pts
				(xy 0.700024 -161.275014) (xy 7.29996 -161.275014) (xy 7.29996 -156.325062) (xy 0.700024 -156.325062)
			)
		)
	)
	(zone
		(layer "F.Cu")
		(hatch none 0.5)
		(connect_pads
			(clearance 0)
		)
		(min_thickness 0.25)
		(keepout
			(tracks allowed)
			(vias allowed)
			(pads allowed)
			(copperpour allowed)
			(footprints not_allowed)
		)
		(placement
			(enabled no)
			(sheetname "")
		)
		(fill
			(thermal_gap 0.5)
			(thermal_bridge_width 0.5)
			(island_removal_mode 0)
		)
		(polygon
			(pts
				(arc
					(start 86.399878 -420.06012)
					(mid 91.400122 -415.059876)
					(end 96.400112 -420.06012)
				)
				(arc
					(start 96.400112 -420.06012)
					(mid 91.400122 -425.06011)
					(end 86.399878 -420.06012)
				)
			)
		)
	)
	(zone
		(layer "F.Cu")
		(hatch none 0.5)
		(connect_pads
			(clearance 0)
		)
		(min_thickness 0.25)
		(keepout
			(tracks allowed)
			(vias allowed)
			(pads allowed)
			(copperpour allowed)
			(footprints not_allowed)
		)
		(placement
			(enabled no)
			(sheetname "")
		)
		(fill
			(thermal_gap 0.5)
			(thermal_bridge_width 0.5)
			(island_removal_mode 0)
		)
		(polygon
			(pts
				(arc
					(start 96.400112 -108.91012)
					(mid 91.400122 -113.91011)
					(end 86.399878 -108.91012)
				)
				(arc
					(start 86.399878 -108.91012)
					(mid 91.400122 -103.909876)
					(end 96.400112 -108.91012)
				)
			)
		)
	)
	(zone
		(layer "F.Cu")
		(hatch none 0.5)
		(connect_pads
			(clearance 0)
		)
		(min_thickness 0.25)
		(keepout
			(tracks allowed)
			(vias allowed)
			(pads allowed)
			(copperpour allowed)
			(footprints not_allowed)
		)
		(placement
			(enabled no)
			(sheetname "")
		)
		(fill
			(thermal_gap 0.5)
			(thermal_bridge_width 0.5)
			(island_removal_mode 0)
		)
		(polygon
			(pts
				(xy 55.999888 -232.549954) (xy 55.999888 -257.549904) (xy 44.99991 -257.549904) (xy 44.99991 -232.549954)
			)
		)
	)
	(zone
		(layer "F.Cu")
		(hatch none 0.5)
		(connect_pads
			(clearance 0)
		)
		(min_thickness 0.25)
		(keepout
			(tracks allowed)
			(vias allowed)
			(pads allowed)
			(copperpour allowed)
			(footprints not_allowed)
		)
		(placement
			(enabled no)
			(sheetname "")
		)
		(fill
			(thermal_gap 0.5)
			(thermal_bridge_width 0.5)
			(island_removal_mode 0)
		)
		(polygon
			(pts
				(xy 55.999888 -188.099954) (xy 55.999888 -213.099904) (xy 44.99991 -213.099904) (xy 44.99991 -188.099954)
			)
		)
	)
	(zone
		(layer "F.Cu")
		(hatch none 0.5)
		(connect_pads
			(clearance 0)
		)
		(min_thickness 0.25)
		(keepout
			(tracks allowed)
			(vias allowed)
			(pads allowed)
			(copperpour allowed)
			(footprints not_allowed)
		)
		(placement
			(enabled no)
			(sheetname "")
		)
		(fill
			(thermal_gap 0.5)
			(thermal_bridge_width 0.5)
			(island_removal_mode 0)
		)
		(polygon
			(pts
				(xy 37.975032 -353.5299) (xy 37.975032 -441.63996) (xy 28.02509 -441.63996) (xy 28.02509 -353.5299)
			)
		)
	)
	(zone
		(layer "F.Cu")
		(hatch none 0.5)
		(connect_pads
			(clearance 0)
		)
		(min_thickness 0.25)
		(keepout
			(tracks allowed)
			(vias allowed)
			(pads allowed)
			(copperpour allowed)
			(footprints not_allowed)
		)
		(placement
			(enabled no)
			(sheetname "")
		)
		(fill
			(thermal_gap 0.5)
			(thermal_bridge_width 0.5)
			(island_removal_mode 0)
		)
		(polygon
			(pts
				(xy 16.996918 -22.005036) (xy 0.90297 -22.005036) (xy 0.90297 -4.895088) (xy 16.996918 -4.895088)
			)
		)
	)
	(zone
		(layer "F.Cu")
		(hatch none 0.5)
		(connect_pads
			(clearance 0)
		)
		(min_thickness 0.25)
		(keepout
			(tracks allowed)
			(vias allowed)
			(pads allowed)
			(copperpour allowed)
			(footprints not_allowed)
		)
		(placement
			(enabled no)
			(sheetname "")
		)
		(fill
			(thermal_gap 0.5)
			(thermal_bridge_width 0.5)
			(island_removal_mode 0)
		)
		(polygon
			(pts
				(xy 16.996918 -92.495116) (xy 16.996918 -109.605064) (xy 0.90297 -109.605064) (xy 0.90297 -92.495116)
			)
		)
	)
	(zone
		(layer "F.Cu")
		(hatch none 0.5)
		(connect_pads
			(clearance 0)
		)
		(min_thickness 0.25)
		(keepout
			(tracks not_allowed)
			(vias allowed)
			(pads allowed)
			(copperpour not_allowed)
			(footprints allowed)
		)
		(placement
			(enabled no)
			(sheetname "")
		)
		(fill
			(thermal_gap 0.5)
			(thermal_bridge_width 0.5)
			(island_removal_mode 0)
		)
		(polygon
			(pts
				(arc
					(start 87.399876 -464.51012)
					(mid 91.400122 -460.509874)
					(end 95.400114 -464.51012)
				)
				(arc
					(start 95.400114 -464.51012)
					(mid 91.400122 -468.510112)
					(end 87.399876 -464.51012)
				)
			)
		)
	)
	(zone
		(layer "F.Cu")
		(hatch none 0.5)
		(connect_pads
			(clearance 0)
		)
		(min_thickness 0.25)
		(keepout
			(tracks allowed)
			(vias allowed)
			(pads allowed)
			(copperpour allowed)
			(footprints not_allowed)
		)
		(placement
			(enabled no)
			(sheetname "")
		)
		(fill
			(thermal_gap 0.5)
			(thermal_bridge_width 0.5)
			(island_removal_mode 0)
		)
		(polygon
			(pts
				(arc
					(start 11.599926 -295.900094)
					(mid 16.599916 -290.900104)
					(end 21.599906 -295.900094)
				)
				(arc
					(start 21.599906 -295.900094)
					(mid 16.599916 -300.900084)
					(end 11.599926 -295.900094)
				)
			)
		)
	)
	(zone
		(layer "F.Cu")
		(hatch none 0.5)
		(connect_pads
			(clearance 0)
		)
		(min_thickness 0.25)
		(keepout
			(tracks allowed)
			(vias allowed)
			(pads allowed)
			(copperpour allowed)
			(footprints not_allowed)
		)
		(placement
			(enabled no)
			(sheetname "")
		)
		(fill
			(thermal_gap 0.5)
			(thermal_bridge_width 0.5)
			(island_removal_mode 0)
		)
		(polygon
			(pts
				(arc
					(start 86.399878 -64.46012)
					(mid 91.400122 -59.459876)
					(end 96.400112 -64.46012)
				)
				(arc
					(start 96.400112 -64.46012)
					(mid 91.400122 -69.46011)
					(end 86.399878 -64.46012)
				)
			)
		)
	)
	(zone
		(layer "F.Cu")
		(hatch none 0.5)
		(connect_pads
			(clearance 0)
		)
		(min_thickness 0.25)
		(keepout
			(tracks not_allowed)
			(vias allowed)
			(pads allowed)
			(copperpour not_allowed)
			(footprints allowed)
		)
		(placement
			(enabled no)
			(sheetname "")
		)
		(fill
			(thermal_gap 0.5)
			(thermal_bridge_width 0.5)
			(island_removal_mode 0)
		)
		(polygon
			(pts
				(arc
					(start 76.000102 -341.250016)
					(mid 78.000098 -339.25002)
					(end 80.000094 -341.250016)
				)
				(arc
					(start 80.000094 -341.250016)
					(mid 78.000098 -343.250012)
					(end 76.000102 -341.250016)
				)
			)
		)
	)
	(zone
		(layer "F.Cu")
		(hatch none 0.5)
		(connect_pads
			(clearance 0)
		)
		(min_thickness 0.25)
		(keepout
			(tracks not_allowed)
			(vias allowed)
			(pads allowed)
			(copperpour not_allowed)
			(footprints allowed)
		)
		(placement
			(enabled no)
			(sheetname "")
		)
		(fill
			(thermal_gap 0.5)
			(thermal_bridge_width 0.5)
			(island_removal_mode 0)
		)
		(polygon
			(pts
				(arc
					(start 87.399876 -420.06012)
					(mid 91.400122 -416.059874)
					(end 95.400114 -420.06012)
				)
				(arc
					(start 95.400114 -420.06012)
					(mid 91.400122 -424.060112)
					(end 87.399876 -420.06012)
				)
			)
		)
	)
	(zone
		(layer "F.Cu")
		(hatch none 0.5)
		(connect_pads
			(clearance 0)
		)
		(min_thickness 0.25)
		(keepout
			(tracks not_allowed)
			(vias allowed)
			(pads allowed)
			(copperpour not_allowed)
			(footprints allowed)
		)
		(placement
			(enabled no)
			(sheetname "")
		)
		(fill
			(thermal_gap 0.5)
			(thermal_bridge_width 0.5)
			(island_removal_mode 0)
		)
		(polygon
			(pts
				(arc
					(start 96.400112 -331.16012)
					(mid 91.400122 -336.16011)
					(end 86.399878 -331.16012)
				)
				(arc
					(start 86.399878 -331.16012)
					(mid 91.400122 -326.159876)
					(end 96.400112 -331.16012)
				)
			)
		)
	)
	(zone
		(layer "F.Cu")
		(hatch none 0.5)
		(connect_pads
			(clearance 0)
		)
		(min_thickness 0.25)
		(keepout
			(tracks not_allowed)
			(vias allowed)
			(pads allowed)
			(copperpour not_allowed)
			(footprints allowed)
		)
		(placement
			(enabled no)
			(sheetname "")
		)
		(fill
			(thermal_gap 0.5)
			(thermal_bridge_width 0.5)
			(island_removal_mode 0)
		)
		(polygon
			(pts
				(arc
					(start 83.000088 -430.150016)
					(mid 78.000098 -435.150006)
					(end 73.000108 -430.150016)
				)
				(arc
					(start 73.000108 -430.150016)
					(mid 78.000098 -425.150026)
					(end 83.000088 -430.150016)
				)
			)
		)
	)
	(zone
		(layer "F.Cu")
		(hatch none 0.5)
		(connect_pads
			(clearance 0)
		)
		(min_thickness 0.25)
		(keepout
			(tracks not_allowed)
			(vias allowed)
			(pads allowed)
			(copperpour not_allowed)
			(footprints allowed)
		)
		(placement
			(enabled no)
			(sheetname "")
		)
		(fill
			(thermal_gap 0.5)
			(thermal_bridge_width 0.5)
			(island_removal_mode 0)
		)
		(polygon
			(pts
				(arc
					(start 14.59992 -118.100094)
					(mid 16.599916 -116.100098)
					(end 18.599912 -118.100094)
				)
				(arc
					(start 18.599912 -118.100094)
					(mid 16.599916 -120.10009)
					(end 14.59992 -118.100094)
				)
			)
		)
	)
	(zone
		(layer "F.Cu")
		(hatch none 0.5)
		(connect_pads
			(clearance 0)
		)
		(min_thickness 0.25)
		(keepout
			(tracks not_allowed)
			(vias allowed)
			(pads allowed)
			(copperpour not_allowed)
			(footprints allowed)
		)
		(placement
			(enabled no)
			(sheetname "")
		)
		(fill
			(thermal_gap 0.5)
			(thermal_bridge_width 0.5)
			(island_removal_mode 0)
		)
		(polygon
			(pts
				(arc
					(start 76.000102 -430.150016)
					(mid 78.000098 -428.15002)
					(end 80.000094 -430.150016)
				)
				(arc
					(start 80.000094 -430.150016)
					(mid 78.000098 -432.150012)
					(end 76.000102 -430.150016)
				)
			)
		)
	)
	(zone
		(layer "F.Cu")
		(hatch none 0.5)
		(connect_pads
			(clearance 0)
		)
		(min_thickness 0.25)
		(keepout
			(tracks not_allowed)
			(vias allowed)
			(pads allowed)
			(copperpour not_allowed)
			(footprints allowed)
		)
		(placement
			(enabled no)
			(sheetname "")
		)
		(fill
			(thermal_gap 0.5)
			(thermal_bridge_width 0.5)
			(island_removal_mode 0)
		)
		(polygon
			(pts
				(arc
					(start 83.000088 -341.250016)
					(mid 78.000098 -346.250006)
					(end 73.000108 -341.250016)
				)
				(arc
					(start 73.000108 -341.250016)
					(mid 78.000098 -336.250026)
					(end 83.000088 -341.250016)
				)
			)
		)
	)
	(zone
		(layer "F.Cu")
		(hatch none 0.5)
		(connect_pads
			(clearance 0)
		)
		(min_thickness 0.25)
		(keepout
			(tracks allowed)
			(vias allowed)
			(pads allowed)
			(copperpour allowed)
			(footprints not_allowed)
		)
		(placement
			(enabled no)
			(sheetname "")
		)
		(fill
			(thermal_gap 0.5)
			(thermal_bridge_width 0.5)
			(island_removal_mode 0)
		)
		(polygon
			(pts
				(xy 44.99991 -232.549954) (xy 44.99991 -257.549904) (xy 55.999888 -257.549904) (xy 55.999888 -232.549954)
			)
		)
	)
	(zone
		(layer "F.Cu")
		(hatch none 0.5)
		(connect_pads
			(clearance 0)
		)
		(min_thickness 0.25)
		(keepout
			(tracks allowed)
			(vias allowed)
			(pads allowed)
			(copperpour allowed)
			(footprints not_allowed)
		)
		(placement
			(enabled no)
			(sheetname "")
		)
		(fill
			(thermal_gap 0.5)
			(thermal_bridge_width 0.5)
			(island_removal_mode 0)
		)
		(polygon
			(pts
				(xy 0.700024 -154.325066) (xy 0.700024 -149.375114) (xy 7.29996 -149.375114) (xy 7.29996 -154.325066)
			)
		)
	)
	(zone
		(layer "F.Cu")
		(hatch none 0.5)
		(connect_pads
			(clearance 0)
		)
		(min_thickness 0.25)
		(keepout
			(tracks not_allowed)
			(vias allowed)
			(pads allowed)
			(copperpour not_allowed)
			(footprints allowed)
		)
		(placement
			(enabled no)
			(sheetname "")
		)
		(fill
			(thermal_gap 0.5)
			(thermal_bridge_width 0.5)
			(island_removal_mode 0)
		)
		(polygon
			(pts
				(arc
					(start 96.400112 -20.01012)
					(mid 91.400122 -25.01011)
					(end 86.399878 -20.01012)
				)
				(arc
					(start 86.399878 -20.01012)
					(mid 91.400122 -15.009876)
					(end 96.400112 -20.01012)
				)
			)
		)
	)
	(zone
		(layer "F.Cu")
		(hatch none 0.5)
		(connect_pads
			(clearance 0)
		)
		(min_thickness 0.25)
		(keepout
			(tracks not_allowed)
			(vias allowed)
			(pads allowed)
			(copperpour not_allowed)
			(footprints allowed)
		)
		(placement
			(enabled no)
			(sheetname "")
		)
		(fill
			(thermal_gap 0.5)
			(thermal_bridge_width 0.5)
			(island_removal_mode 0)
		)
		(polygon
			(pts
				(arc
					(start 87.399876 -197.81012)
					(mid 91.400122 -193.809874)
					(end 95.400114 -197.81012)
				)
				(arc
					(start 95.400114 -197.81012)
					(mid 91.400122 -201.810112)
					(end 87.399876 -197.81012)
				)
			)
		)
	)
	(zone
		(layer "F.Cu")
		(hatch none 0.5)
		(connect_pads
			(clearance 0)
		)
		(min_thickness 0.25)
		(keepout
			(tracks not_allowed)
			(vias allowed)
			(pads allowed)
			(copperpour not_allowed)
			(footprints allowed)
		)
		(placement
			(enabled no)
			(sheetname "")
		)
		(fill
			(thermal_gap 0.5)
			(thermal_bridge_width 0.5)
			(island_removal_mode 0)
		)
		(polygon
			(pts
				(arc
					(start 81.60004 -478.799906)
					(mid 78.000098 -482.399848)
					(end 74.399902 -478.799906)
				)
				(arc
					(start 74.399902 -477.799908)
					(mid 78.000098 -474.199712)
					(end 81.60004 -477.799908)
				)
			)
		)
	)
	(zone
		(layer "F.Cu")
		(hatch none 0.5)
		(connect_pads
			(clearance 0)
		)
		(min_thickness 0.25)
		(keepout
			(tracks allowed)
			(vias allowed)
			(pads allowed)
			(copperpour allowed)
			(footprints not_allowed)
		)
		(placement
			(enabled no)
			(sheetname "")
		)
		(fill
			(thermal_gap 0.5)
			(thermal_bridge_width 0.5)
			(island_removal_mode 0)
		)
		(polygon
			(pts
				(arc
					(start 21.599906 -118.100094)
					(mid 16.599916 -123.100084)
					(end 11.599926 -118.100094)
				)
				(arc
					(start 11.599926 -118.100094)
					(mid 16.599916 -113.100104)
					(end 21.599906 -118.100094)
				)
			)
		)
	)
	(zone
		(layer "F.Cu")
		(hatch none 0.5)
		(connect_pads
			(clearance 0)
		)
		(min_thickness 0.25)
		(keepout
			(tracks allowed)
			(vias allowed)
			(pads allowed)
			(copperpour allowed)
			(footprints not_allowed)
		)
		(placement
			(enabled no)
			(sheetname "")
		)
		(fill
			(thermal_gap 0.5)
			(thermal_bridge_width 0.5)
			(island_removal_mode 0)
		)
		(polygon
			(pts
				(arc
					(start 74.399902 -477.799908)
					(mid 78.000098 -474.199712)
					(end 81.60004 -477.799908)
				)
				(arc
					(start 81.60004 -478.799906)
					(mid 78.000098 -482.399848)
					(end 74.399902 -478.799906)
				)
			)
		)
	)
	(zone
		(layer "F.Cu")
		(hatch none 0.5)
		(connect_pads
			(clearance 0)
		)
		(min_thickness 0.25)
		(keepout
			(tracks allowed)
			(vias allowed)
			(pads allowed)
			(copperpour allowed)
			(footprints not_allowed)
		)
		(placement
			(enabled no)
			(sheetname "")
		)
		(fill
			(thermal_gap 0.5)
			(thermal_bridge_width 0.5)
			(island_removal_mode 0)
		)
		(polygon
			(pts
				(xy 37.975032 -265.130026) (xy 37.975032 -353.240086) (xy 28.02509 -353.240086) (xy 28.02509 -265.130026)
			)
		)
	)
	(zone
		(layer "F.Cu")
		(hatch none 0.5)
		(connect_pads
			(clearance 0)
		)
		(min_thickness 0.25)
		(keepout
			(tracks allowed)
			(vias allowed)
			(pads allowed)
			(copperpour allowed)
			(footprints not_allowed)
		)
		(placement
			(enabled no)
			(sheetname "")
		)
		(fill
			(thermal_gap 0.5)
			(thermal_bridge_width 0.5)
			(island_removal_mode 0)
		)
		(polygon
			(pts
				(xy 37.975032 -88.330024) (xy 37.975032 -176.440084) (xy 28.02509 -176.440084) (xy 28.02509 -88.330024)
			)
		)
	)
	(zone
		(layer "F.Cu")
		(hatch none 0.5)
		(connect_pads
			(clearance 0)
		)
		(min_thickness 0.25)
		(keepout
			(tracks not_allowed)
			(vias allowed)
			(pads allowed)
			(copperpour not_allowed)
			(footprints allowed)
		)
		(placement
			(enabled no)
			(sheetname "")
		)
		(fill
			(thermal_gap 0.5)
			(thermal_bridge_width 0.5)
			(island_removal_mode 0)
		)
		(polygon
			(pts
				(arc
					(start 87.399876 -242.26012)
					(mid 91.400122 -238.259874)
					(end 95.400114 -242.26012)
				)
				(arc
					(start 95.400114 -242.26012)
					(mid 91.400122 -246.260112)
					(end 87.399876 -242.26012)
				)
			)
		)
	)
	(zone
		(layer "F.Cu")
		(hatch none 0.5)
		(connect_pads
			(clearance 0)
		)
		(min_thickness 0.25)
		(keepout
			(tracks not_allowed)
			(vias allowed)
			(pads allowed)
			(copperpour not_allowed)
			(footprints allowed)
		)
		(placement
			(enabled no)
			(sheetname "")
		)
		(fill
			(thermal_gap 0.5)
			(thermal_bridge_width 0.5)
			(island_removal_mode 0)
		)
		(polygon
			(pts
				(arc
					(start 96.400112 -153.36012)
					(mid 91.400122 -158.36011)
					(end 86.399878 -153.36012)
				)
				(arc
					(start 86.399878 -153.36012)
					(mid 91.400122 -148.359876)
					(end 96.400112 -153.36012)
				)
			)
		)
	)
	(zone
		(layer "F.Cu")
		(hatch none 0.5)
		(connect_pads
			(clearance 0)
		)
		(min_thickness 0.25)
		(keepout
			(tracks allowed)
			(vias allowed)
			(pads allowed)
			(copperpour allowed)
			(footprints not_allowed)
		)
		(placement
			(enabled no)
			(sheetname "")
		)
		(fill
			(thermal_gap 0.5)
			(thermal_bridge_width 0.5)
			(island_removal_mode 0)
		)
		(polygon
			(pts
				(xy 55.999888 -365.899954) (xy 55.999888 -390.899904) (xy 44.99991 -390.899904) (xy 44.99991 -365.899954)
			)
		)
	)
	(zone
		(layer "F.Cu")
		(hatch none 0.5)
		(connect_pads
			(clearance 0)
		)
		(min_thickness 0.25)
		(keepout
			(tracks allowed)
			(vias allowed)
			(pads allowed)
			(copperpour allowed)
			(footprints not_allowed)
		)
		(placement
			(enabled no)
			(sheetname "")
		)
		(fill
			(thermal_gap 0.5)
			(thermal_bridge_width 0.5)
			(island_removal_mode 0)
		)
		(polygon
			(pts
				(arc
					(start 86.399878 -197.81012)
					(mid 91.400122 -192.809876)
					(end 96.400112 -197.81012)
				)
				(arc
					(start 96.400112 -197.81012)
					(mid 91.400122 -202.81011)
					(end 86.399878 -197.81012)
				)
			)
		)
	)
	(zone
		(layer "F.Cu")
		(hatch none 0.5)
		(connect_pads
			(clearance 0)
		)
		(min_thickness 0.25)
		(keepout
			(tracks not_allowed)
			(vias allowed)
			(pads allowed)
			(copperpour not_allowed)
			(footprints allowed)
		)
		(placement
			(enabled no)
			(sheetname "")
		)
		(fill
			(thermal_gap 0.5)
			(thermal_bridge_width 0.5)
			(island_removal_mode 0)
		)
		(polygon
			(pts
				(arc
					(start 14.59992 -295.900094)
					(mid 16.599916 -293.900098)
					(end 18.599912 -295.900094)
				)
				(arc
					(start 18.599912 -295.900094)
					(mid 16.599916 -297.90009)
					(end 14.59992 -295.900094)
				)
			)
		)
	)
	(zone
		(layer "F.Cu")
		(hatch none 0.5)
		(connect_pads
			(clearance 0)
		)
		(min_thickness 0.25)
		(keepout
			(tracks not_allowed)
			(vias allowed)
			(pads allowed)
			(copperpour not_allowed)
			(footprints allowed)
		)
		(placement
			(enabled no)
			(sheetname "")
		)
		(fill
			(thermal_gap 0.5)
			(thermal_bridge_width 0.5)
			(island_removal_mode 0)
		)
		(polygon
			(pts
				(arc
					(start 75.3999 -477.799908)
					(mid 78.000098 -475.19971)
					(end 80.600042 -477.799908)
				)
				(arc
					(start 80.600042 -478.799906)
					(mid 78.000098 -481.39985)
					(end 75.3999 -478.799906)
				)
			)
		)
	)
	(zone
		(layer "F.Cu")
		(hatch none 0.5)
		(connect_pads
			(clearance 0)
		)
		(min_thickness 0.25)
		(keepout
			(tracks allowed)
			(vias allowed)
			(pads allowed)
			(copperpour allowed)
			(footprints not_allowed)
		)
		(placement
			(enabled no)
			(sheetname "")
		)
		(fill
			(thermal_gap 0.5)
			(thermal_bridge_width 0.5)
			(island_removal_mode 0)
		)
		(polygon
			(pts
				(xy 16.996918 -75.054968) (xy 0.90297 -75.054968) (xy 0.90297 -57.94502) (xy 16.996918 -57.94502)
			)
		)
	)
	(zone
		(layer "F.Cu")
		(hatch none 0.5)
		(connect_pads
			(clearance 0)
		)
		(min_thickness 0.25)
		(keepout
			(tracks allowed)
			(vias allowed)
			(pads allowed)
			(copperpour allowed)
			(footprints not_allowed)
		)
		(placement
			(enabled no)
			(sheetname "")
		)
		(fill
			(thermal_gap 0.5)
			(thermal_bridge_width 0.5)
			(island_removal_mode 0)
		)
		(polygon
			(pts
				(xy 0.700024 -382.774952) (xy 7.29996 -382.774952) (xy 7.29996 -377.825) (xy 0.700024 -377.825)
			)
		)
	)
	(zone
		(layer "F.Cu")
		(hatch none 0.5)
		(connect_pads
			(clearance 0)
		)
		(min_thickness 0.25)
		(keepout
			(tracks allowed)
			(vias allowed)
			(pads allowed)
			(copperpour allowed)
			(footprints not_allowed)
		)
		(placement
			(enabled no)
			(sheetname "")
		)
		(fill
			(thermal_gap 0.5)
			(thermal_bridge_width 0.5)
			(island_removal_mode 0)
		)
		(polygon
			(pts
				(xy 44.99991 -454.799954) (xy 44.99991 -479.799904) (xy 55.999888 -479.799904) (xy 55.999888 -454.799954)
			)
		)
	)
	(zone
		(layer "F.Cu")
		(hatch none 0.5)
		(connect_pads
			(clearance 0)
		)
		(min_thickness 0.25)
		(keepout
			(tracks allowed)
			(vias allowed)
			(pads allowed)
			(copperpour allowed)
			(footprints not_allowed)
		)
		(placement
			(enabled no)
			(sheetname "")
		)
		(fill
			(thermal_gap 0.5)
			(thermal_bridge_width 0.5)
			(island_removal_mode 0)
		)
		(polygon
			(pts
				(arc
					(start 86.399878 -286.71012)
					(mid 91.400122 -281.709876)
					(end 96.400112 -286.71012)
				)
				(arc
					(start 96.400112 -286.71012)
					(mid 91.400122 -291.71011)
					(end 86.399878 -286.71012)
				)
			)
		)
	)
	(zone
		(layer "F.Cu")
		(hatch none 0.5)
		(connect_pads
			(clearance 0)
		)
		(min_thickness 0.25)
		(keepout
			(tracks not_allowed)
			(vias allowed)
			(pads allowed)
			(copperpour not_allowed)
			(footprints allowed)
		)
		(placement
			(enabled no)
			(sheetname "")
		)
		(fill
			(thermal_gap 0.5)
			(thermal_bridge_width 0.5)
			(island_removal_mode 0)
		)
		(polygon
			(pts
				(arc
					(start 76.000102 -121.19991)
					(mid 78.000098 -119.199914)
					(end 80.000094 -121.19991)
				)
				(arc
					(start 80.000094 -121.19991)
					(mid 78.000098 -123.199906)
					(end 76.000102 -121.19991)
				)
			)
		)
	)
	(zone
		(layer "F.Cu")
		(hatch none 0.5)
		(connect_pads
			(clearance 0)
		)
		(min_thickness 0.25)
		(keepout
			(tracks allowed)
			(vias allowed)
			(pads allowed)
			(copperpour allowed)
			(footprints not_allowed)
		)
		(placement
			(enabled no)
			(sheetname "")
		)
		(fill
			(thermal_gap 0.5)
			(thermal_bridge_width 0.5)
			(island_removal_mode 0)
		)
		(polygon
			(pts
				(arc
					(start 11.599926 -473.700094)
					(mid 16.599916 -468.700104)
					(end 21.599906 -473.700094)
				)
				(arc
					(start 21.599906 -473.700094)
					(mid 16.599916 -478.700084)
					(end 11.599926 -473.700094)
				)
			)
		)
	)
	(zone
		(layer "F.Cu")
		(hatch none 0.5)
		(connect_pads
			(clearance 0)
		)
		(min_thickness 0.25)
		(keepout
			(tracks allowed)
			(vias allowed)
			(pads allowed)
			(copperpour allowed)
			(footprints not_allowed)
		)
		(placement
			(enabled no)
			(sheetname "")
		)
		(fill
			(thermal_gap 0.5)
			(thermal_bridge_width 0.5)
			(island_removal_mode 0)
		)
		(polygon
			(pts
				(xy 0.700024 -375.825004) (xy 7.29996 -375.825004) (xy 7.29996 -370.875052) (xy 0.700024 -370.875052)
			)
		)
	)
	(zone
		(layer "F.Cu")
		(hatch none 0.5)
		(connect_pads
			(clearance 0)
		)
		(min_thickness 0.25)
		(keepout
			(tracks allowed)
			(vias allowed)
			(pads allowed)
			(copperpour allowed)
			(footprints not_allowed)
		)
		(placement
			(enabled no)
			(sheetname "")
		)
		(fill
			(thermal_gap 0.5)
			(thermal_bridge_width 0.5)
			(island_removal_mode 0)
		)
		(polygon
			(pts
				(arc
					(start 102.00005 -1.999996)
					(mid 101.707157 -1.292891)
					(end 101.000052 -0.999998)
				)
				(xy 40.999918 -0.999998) (xy 40.999918 -528.999958)
				(arc
					(start 101.000052 -528.999958)
					(mid 101.707157 -528.707065)
					(end 102.00005 -527.99996)
				)
			)
		)
	)
	(zone
		(layer "F.Cu")
		(hatch none 0.5)
		(connect_pads
			(clearance 0)
		)
		(min_thickness 0.25)
		(keepout
			(tracks not_allowed)
			(vias allowed)
			(pads allowed)
			(copperpour not_allowed)
			(footprints allowed)
		)
		(placement
			(enabled no)
			(sheetname "")
		)
		(fill
			(thermal_gap 0.5)
			(thermal_bridge_width 0.5)
			(island_removal_mode 0)
		)
		(polygon
			(pts
				(arc
					(start 14.59992 -384.800094)
					(mid 16.599916 -382.800098)
					(end 18.599912 -384.800094)
				)
				(arc
					(start 18.599912 -384.800094)
					(mid 16.599916 -386.80009)
					(end 14.59992 -384.800094)
				)
			)
		)
	)
	(zone
		(layer "F.Cu")
		(hatch none 0.5)
		(connect_pads
			(clearance 0)
		)
		(min_thickness 0.25)
		(keepout
			(tracks allowed)
			(vias allowed)
			(pads allowed)
			(copperpour allowed)
			(footprints not_allowed)
		)
		(placement
			(enabled no)
			(sheetname "")
		)
		(fill
			(thermal_gap 0.5)
			(thermal_bridge_width 0.5)
			(island_removal_mode 0)
		)
		(polygon
			(pts
				(xy 55.999888 -276.999954) (xy 55.999888 -301.999904) (xy 44.99991 -301.999904) (xy 44.99991 -276.999954)
			)
		)
	)
	(zone
		(layer "F.Cu")
		(hatch none 0.5)
		(connect_pads
			(clearance 0)
		)
		(min_thickness 0.25)
		(keepout
			(tracks allowed)
			(vias allowed)
			(pads allowed)
			(copperpour allowed)
			(footprints not_allowed)
		)
		(placement
			(enabled no)
			(sheetname "")
		)
		(fill
			(thermal_gap 0.5)
			(thermal_bridge_width 0.5)
			(island_removal_mode 0)
		)
		(polygon
			(pts
				(arc
					(start 73.000108 -32.29991)
					(mid 78.000098 -27.29992)
					(end 83.000088 -32.29991)
				)
				(arc
					(start 83.000088 -32.29991)
					(mid 78.000098 -37.2999)
					(end 73.000108 -32.29991)
				)
			)
		)
	)
	(zone
		(layer "F.Cu")
		(hatch none 0.5)
		(connect_pads
			(clearance 0)
		)
		(min_thickness 0.25)
		(keepout
			(tracks allowed)
			(vias allowed)
			(pads allowed)
			(copperpour allowed)
			(footprints not_allowed)
		)
		(placement
			(enabled no)
			(sheetname "")
		)
		(fill
			(thermal_gap 0.5)
			(thermal_bridge_width 0.5)
			(island_removal_mode 0)
		)
		(polygon
			(pts
				(arc
					(start 86.399878 -375.61012)
					(mid 91.400122 -370.609876)
					(end 96.400112 -375.61012)
				)
				(arc
					(start 96.400112 -375.61012)
					(mid 91.400122 -380.61011)
					(end 86.399878 -375.61012)
				)
			)
		)
	)
	(zone
		(layer "F.Cu")
		(hatch none 0.5)
		(connect_pads
			(clearance 0)
		)
		(min_thickness 0.25)
		(keepout
			(tracks allowed)
			(vias allowed)
			(pads allowed)
			(copperpour allowed)
			(footprints not_allowed)
		)
		(placement
			(enabled no)
			(sheetname "")
		)
		(fill
			(thermal_gap 0.5)
			(thermal_bridge_width 0.5)
			(island_removal_mode 0)
		)
		(polygon
			(pts
				(arc
					(start 86.399878 -242.26012)
					(mid 91.400122 -237.259876)
					(end 96.400112 -242.26012)
				)
				(arc
					(start 96.400112 -242.26012)
					(mid 91.400122 -247.26011)
					(end 86.399878 -242.26012)
				)
			)
		)
	)
	(zone
		(layer "F.Cu")
		(hatch none 0.5)
		(connect_pads
			(clearance 0)
		)
		(min_thickness 0.25)
		(keepout
			(tracks allowed)
			(vias allowed)
			(pads allowed)
			(copperpour allowed)
			(footprints not_allowed)
		)
		(placement
			(enabled no)
			(sheetname "")
		)
		(fill
			(thermal_gap 0.5)
			(thermal_bridge_width 0.5)
			(island_removal_mode 0)
		)
		(polygon
			(pts
				(xy 16.996918 -39.44493) (xy 16.996918 -56.554878) (xy 0.90297 -56.554878) (xy 0.90297 -39.44493)
			)
		)
	)
	(zone
		(layer "F.Cu")
		(hatch none 0.5)
		(connect_pads
			(clearance 0)
		)
		(min_thickness 0.25)
		(keepout
			(tracks not_allowed)
			(vias allowed)
			(pads allowed)
			(copperpour not_allowed)
			(footprints allowed)
		)
		(placement
			(enabled no)
			(sheetname "")
		)
		(fill
			(thermal_gap 0.5)
			(thermal_bridge_width 0.5)
			(island_removal_mode 0)
		)
		(polygon
			(pts
				(arc
					(start 87.399876 -64.46012)
					(mid 91.400122 -60.459874)
					(end 95.400114 -64.46012)
				)
				(arc
					(start 95.400114 -64.46012)
					(mid 91.400122 -68.460112)
					(end 87.399876 -64.46012)
				)
			)
		)
	)
	(zone
		(layer "F.Cu")
		(hatch none 0.5)
		(connect_pads
			(clearance 0)
		)
		(min_thickness 0.25)
		(keepout
			(tracks allowed)
			(vias allowed)
			(pads allowed)
			(copperpour allowed)
			(footprints not_allowed)
		)
		(placement
			(enabled no)
			(sheetname "")
		)
		(fill
			(thermal_gap 0.5)
			(thermal_bridge_width 0.5)
			(island_removal_mode 0)
		)
		(polygon
			(pts
				(arc
					(start 81.60004 -78.300072)
					(mid 78.000098 -81.900014)
					(end 74.399902 -78.300072)
				)
				(arc
					(start 74.399902 -78.300072)
					(mid 78.000098 -74.699876)
					(end 81.60004 -78.300072)
				)
			)
		)
	)
	(zone
		(layer "F.Cu")
		(hatch none 0.5)
		(connect_pads
			(clearance 0)
		)
		(min_thickness 0.25)
		(keepout
			(tracks not_allowed)
			(vias allowed)
			(pads allowed)
			(copperpour not_allowed)
			(footprints allowed)
		)
		(placement
			(enabled no)
			(sheetname "")
		)
		(fill
			(thermal_gap 0.5)
			(thermal_bridge_width 0.5)
			(island_removal_mode 0)
		)
		(polygon
			(pts
				(arc
					(start 21.599906 -384.800094)
					(mid 16.599916 -389.800084)
					(end 11.599926 -384.800094)
				)
				(arc
					(start 11.599926 -384.800094)
					(mid 16.599916 -379.800104)
					(end 21.599906 -384.800094)
				)
			)
		)
	)
	(zone
		(layer "F.Cu")
		(hatch none 0.5)
		(connect_pads
			(clearance 0)
		)
		(min_thickness 0.25)
		(keepout
			(tracks not_allowed)
			(vias allowed)
			(pads allowed)
			(copperpour not_allowed)
			(footprints allowed)
		)
		(placement
			(enabled no)
			(sheetname "")
		)
		(fill
			(thermal_gap 0.5)
			(thermal_bridge_width 0.5)
			(island_removal_mode 0)
		)
		(polygon
			(pts
				(arc
					(start 14.59992 -29.200094)
					(mid 16.599916 -27.200098)
					(end 18.599912 -29.200094)
				)
				(arc
					(start 18.599912 -29.200094)
					(mid 16.599916 -31.20009)
					(end 14.59992 -29.200094)
				)
			)
		)
	)
	(zone
		(layer "F.Cu")
		(hatch none 0.5)
		(connect_pads
			(clearance 0)
		)
		(min_thickness 0.25)
		(keepout
			(tracks not_allowed)
			(vias allowed)
			(pads allowed)
			(copperpour not_allowed)
			(footprints allowed)
		)
		(placement
			(enabled no)
			(sheetname "")
		)
		(fill
			(thermal_gap 0.5)
			(thermal_bridge_width 0.5)
			(island_removal_mode 0)
		)
		(polygon
			(pts
				(arc
					(start 96.400112 -64.46012)
					(mid 91.400122 -69.46011)
					(end 86.399878 -64.46012)
				)
				(arc
					(start 86.399878 -64.46012)
					(mid 91.400122 -59.459876)
					(end 96.400112 -64.46012)
				)
			)
		)
	)
	(zone
		(layer "F.Cu")
		(hatch none 0.5)
		(connect_pads
			(clearance 0)
		)
		(min_thickness 0.25)
		(keepout
			(tracks allowed)
			(vias allowed)
			(pads allowed)
			(copperpour allowed)
			(footprints not_allowed)
		)
		(placement
			(enabled no)
			(sheetname "")
		)
		(fill
			(thermal_gap 0.5)
			(thermal_bridge_width 0.5)
			(island_removal_mode 0)
		)
		(polygon
			(pts
				(xy 44.99991 -188.099954) (xy 44.99991 -213.099904) (xy 55.999888 -213.099904) (xy 55.999888 -188.099954)
			)
		)
	)
	(zone
		(layer "F.Cu")
		(hatch none 0.5)
		(connect_pads
			(clearance 0)
		)
		(min_thickness 0.25)
		(keepout
			(tracks allowed)
			(vias allowed)
			(pads allowed)
			(copperpour allowed)
			(footprints not_allowed)
		)
		(placement
			(enabled no)
			(sheetname "")
		)
		(fill
			(thermal_gap 0.5)
			(thermal_bridge_width 0.5)
			(island_removal_mode 0)
		)
		(polygon
			(pts
				(xy 9.400032 -175.369982) (xy 9.400032 -355.970078) (xy 0.999998 -355.970078) (xy 0.999998 -175.369982)
			)
		)
	)
	(zone
		(layer "F.Cu")
		(hatch none 0.5)
		(connect_pads
			(clearance 0)
		)
		(min_thickness 0.25)
		(keepout
			(tracks allowed)
			(vias allowed)
			(pads allowed)
			(copperpour allowed)
			(footprints not_allowed)
		)
		(placement
			(enabled no)
			(sheetname "")
		)
		(fill
			(thermal_gap 0.5)
			(thermal_bridge_width 0.5)
			(island_removal_mode 0)
		)
		(polygon
			(pts
				(xy 44.99991 -276.999954) (xy 44.99991 -301.999904) (xy 55.999888 -301.999904) (xy 55.999888 -276.999954)
			)
		)
	)
	(zone
		(layer "F.Cu")
		(hatch none 0.5)
		(connect_pads
			(clearance 0)
		)
		(min_thickness 0.25)
		(keepout
			(tracks not_allowed)
			(vias allowed)
			(pads allowed)
			(copperpour not_allowed)
			(footprints allowed)
		)
		(placement
			(enabled no)
			(sheetname "")
		)
		(fill
			(thermal_gap 0.5)
			(thermal_bridge_width 0.5)
			(island_removal_mode 0)
		)
		(polygon
			(pts
				(arc
					(start 83.000088 -121.19991)
					(mid 78.000098 -126.1999)
					(end 73.000108 -121.19991)
				)
				(arc
					(start 73.000108 -121.19991)
					(mid 78.000098 -116.19992)
					(end 83.000088 -121.19991)
				)
			)
		)
	)
	(zone
		(layer "F.Cu")
		(hatch none 0.5)
		(connect_pads
			(clearance 0)
		)
		(min_thickness 0.25)
		(keepout
			(tracks allowed)
			(vias allowed)
			(pads allowed)
			(copperpour allowed)
			(footprints not_allowed)
		)
		(placement
			(enabled no)
			(sheetname "")
		)
		(fill
			(thermal_gap 0.5)
			(thermal_bridge_width 0.5)
			(island_removal_mode 0)
		)
		(polygon
			(pts
				(arc
					(start 73.000108 -210.09991)
					(mid 78.000098 -205.09992)
					(end 83.000088 -210.09991)
				)
				(arc
					(start 83.000088 -210.09991)
					(mid 78.000098 -215.0999)
					(end 73.000108 -210.09991)
				)
			)
		)
	)
	(zone
		(layer "F.Cu")
		(hatch none 0.5)
		(connect_pads
			(clearance 0)
		)
		(min_thickness 0.25)
		(keepout
			(tracks not_allowed)
			(vias allowed)
			(pads allowed)
			(copperpour not_allowed)
			(footprints allowed)
		)
		(placement
			(enabled no)
			(sheetname "")
		)
		(fill
			(thermal_gap 0.5)
			(thermal_bridge_width 0.5)
			(island_removal_mode 0)
		)
		(polygon
			(pts
				(arc
					(start 87.399876 -286.71012)
					(mid 91.400122 -282.709874)
					(end 95.400114 -286.71012)
				)
				(arc
					(start 95.400114 -286.71012)
					(mid 91.400122 -290.710112)
					(end 87.399876 -286.71012)
				)
			)
		)
	)
	(zone
		(layer "F.Cu")
		(hatch none 0.5)
		(connect_pads
			(clearance 0)
		)
		(min_thickness 0.25)
		(keepout
			(tracks allowed)
			(vias allowed)
			(pads allowed)
			(copperpour allowed)
			(footprints not_allowed)
		)
		(placement
			(enabled no)
			(sheetname "")
		)
		(fill
			(thermal_gap 0.5)
			(thermal_bridge_width 0.5)
			(island_removal_mode 0)
		)
		(polygon
			(pts
				(xy 44.99991 -499.249954) (xy 44.99991 -524.249904) (xy 55.999888 -524.249904) (xy 55.999888 -499.249954)
			)
		)
	)
	(zone
		(layer "F.Cu")
		(hatch none 0.5)
		(connect_pads
			(clearance 0)
		)
		(min_thickness 0.25)
		(keepout
			(tracks allowed)
			(vias allowed)
			(pads allowed)
			(copperpour allowed)
			(footprints not_allowed)
		)
		(placement
			(enabled no)
			(sheetname "")
		)
		(fill
			(thermal_gap 0.5)
			(thermal_bridge_width 0.5)
			(island_removal_mode 0)
		)
		(polygon
			(pts
				(xy 37.975032 -176.729898) (xy 37.975032 -264.839958) (xy 28.02509 -264.839958) (xy 28.02509 -176.729898)
			)
		)
	)
	(zone
		(layer "F.Cu")
		(hatch none 0.5)
		(connect_pads
			(clearance 0)
		)
		(min_thickness 0.25)
		(keepout
			(tracks not_allowed)
			(vias allowed)
			(pads allowed)
			(copperpour not_allowed)
			(footprints allowed)
		)
		(placement
			(enabled no)
			(sheetname "")
		)
		(fill
			(thermal_gap 0.5)
			(thermal_bridge_width 0.5)
			(island_removal_mode 0)
		)
		(polygon
			(pts
				(arc
					(start 96.400112 -420.06012)
					(mid 91.400122 -425.06011)
					(end 86.399878 -420.06012)
				)
				(arc
					(start 86.399878 -420.06012)
					(mid 91.400122 -415.059876)
					(end 96.400112 -420.06012)
				)
			)
		)
	)
	(zone
		(layer "F.Cu")
		(hatch none 0.5)
		(connect_pads
			(clearance 0)
		)
		(min_thickness 0.25)
		(keepout
			(tracks allowed)
			(vias allowed)
			(pads allowed)
			(copperpour allowed)
			(footprints not_allowed)
		)
		(placement
			(enabled no)
			(sheetname "")
		)
		(fill
			(thermal_gap 0.5)
			(thermal_bridge_width 0.5)
			(island_removal_mode 0)
		)
		(polygon
			(pts
				(xy 44.99991 -410.349954) (xy 44.99991 -435.349904) (xy 55.999888 -435.349904) (xy 55.999888 -410.349954)
			)
		)
	)
	(zone
		(layer "F.Cu")
		(hatch none 0.5)
		(connect_pads
			(clearance 0)
		)
		(min_thickness 0.25)
		(keepout
			(tracks not_allowed)
			(vias allowed)
			(pads allowed)
			(copperpour not_allowed)
			(footprints allowed)
		)
		(placement
			(enabled no)
			(sheetname "")
		)
		(fill
			(thermal_gap 0.5)
			(thermal_bridge_width 0.5)
			(island_removal_mode 0)
		)
		(polygon
			(pts
				(arc
					(start 87.399876 -375.61012)
					(mid 91.400122 -371.609874)
					(end 95.400114 -375.61012)
				)
				(arc
					(start 95.400114 -375.61012)
					(mid 91.400122 -379.610112)
					(end 87.399876 -375.61012)
				)
			)
		)
	)
	(zone
		(layer "F.Cu")
		(hatch none 0.5)
		(connect_pads
			(clearance 0)
		)
		(min_thickness 0.25)
		(keepout
			(tracks not_allowed)
			(vias allowed)
			(pads allowed)
			(copperpour not_allowed)
			(footprints allowed)
		)
		(placement
			(enabled no)
			(sheetname "")
		)
		(fill
			(thermal_gap 0.5)
			(thermal_bridge_width 0.5)
			(island_removal_mode 0)
		)
		(polygon
			(pts
				(arc
					(start 21.599906 -473.700094)
					(mid 16.599916 -478.700084)
					(end 11.599926 -473.700094)
				)
				(arc
					(start 11.599926 -473.700094)
					(mid 16.599916 -468.700104)
					(end 21.599906 -473.700094)
				)
			)
		)
	)
	(zone
		(layer "F.Cu")
		(hatch none 0.5)
		(connect_pads
			(clearance 0)
		)
		(min_thickness 0.25)
		(keepout
			(tracks not_allowed)
			(vias allowed)
			(pads allowed)
			(copperpour not_allowed)
			(footprints allowed)
		)
		(placement
			(enabled no)
			(sheetname "")
		)
		(fill
			(thermal_gap 0.5)
			(thermal_bridge_width 0.5)
			(island_removal_mode 0)
		)
		(polygon
			(pts
				(arc
					(start 83.000088 -519.050016)
					(mid 78.000098 -524.050006)
					(end 73.000108 -519.050016)
				)
				(arc
					(start 73.000108 -519.050016)
					(mid 78.000098 -514.050026)
					(end 83.000088 -519.050016)
				)
			)
		)
	)
	(zone
		(layer "F.Cu")
		(hatch none 0.5)
		(connect_pads
			(clearance 0)
		)
		(min_thickness 0.25)
		(keepout
			(tracks allowed)
			(vias allowed)
			(pads allowed)
			(copperpour allowed)
			(footprints not_allowed)
		)
		(placement
			(enabled no)
			(sheetname "")
		)
		(fill
			(thermal_gap 0.5)
			(thermal_bridge_width 0.5)
			(island_removal_mode 0)
		)
		(polygon
			(pts
				(arc
					(start 25.999948 -528.500086)
					(mid 26.146521 -528.853564)
					(end 26.500074 -528.999958)
				)
				(xy 28.02509 -528.999958) (xy 28.02509 -0.999998)
				(arc
					(start 26.500074 -0.999998)
					(mid 26.146432 -1.146482)
					(end 25.999948 -1.500124)
				)
				(arc
					(start 25.999948 -2.500122)
					(mid 25.267754 -4.267796)
					(end 23.50008 -4.99999)
				)
				(xy 16.996918 -4.99999) (xy 16.996918 -22.005036) (xy 0.999998 -22.005036) (xy 0.999998 -39.44493)
				(xy 16.996918 -39.44493) (xy 16.996918 -75.054968) (xy 0.999998 -75.054968) (xy 0.999998 -92.495116)
				(xy 16.996918 -92.495116) (xy 16.996918 -109.605064) (xy 0.999998 -109.605064) (xy 0.999998 -127.649986)
				(xy 17.645126 -127.649986) (xy 17.645126 -144.949926) (xy 0.999998 -144.949926) (xy 0.999998 -149.375114)
				(xy 7.29996 -149.375114) (xy 7.29996 -154.325066) (xy 0.999998 -154.325066) (xy 0.999998 -156.325062)
				(xy 7.29996 -156.325062) (xy 7.29996 -161.275014) (xy 0.999998 -161.275014) (xy 0.999998 -175.369982)
				(xy 9.400032 -175.369982) (xy 9.400032 -355.970078) (xy 0.999998 -355.970078) (xy 0.999998 -370.875052)
				(xy 7.29996 -370.875052) (xy 7.29996 -375.825004) (xy 0.999998 -375.825004) (xy 0.999998 -377.825)
				(xy 7.29996 -377.825) (xy 7.29996 -382.774952) (xy 0.999998 -382.774952) (xy 0.999998 -396.500096)
				(xy 17.645126 -396.500096) (xy 17.645126 -413.800036) (xy 0.999998 -413.800036) (xy 0.999998 -481.48494)
				(xy 16.996918 -481.48494) (xy 16.996918 -498.594888) (xy 0.999998 -498.594888) (xy 0.999998 -507.99492)
				(xy 16.996918 -507.99492) (xy 16.996918 -524.999966)
				(arc
					(start 23.50008 -524.999966)
					(mid 25.267843 -525.73225)
					(end 25.999948 -527.500088)
				)
			)
		)
	)
	(zone
		(layer "F.Cu")
		(hatch none 0.5)
		(connect_pads
			(clearance 0)
		)
		(min_thickness 0.25)
		(keepout
			(tracks not_allowed)
			(vias allowed)
			(pads allowed)
			(copperpour not_allowed)
			(footprints allowed)
		)
		(placement
			(enabled no)
			(sheetname "")
		)
		(fill
			(thermal_gap 0.5)
			(thermal_bridge_width 0.5)
			(island_removal_mode 0)
		)
		(polygon
			(pts
				(arc
					(start 96.400112 -464.51012)
					(mid 91.400122 -469.51011)
					(end 86.399878 -464.51012)
				)
				(arc
					(start 86.399878 -464.51012)
					(mid 91.400122 -459.509876)
					(end 96.400112 -464.51012)
				)
			)
		)
	)
	(zone
		(layer "F.Cu")
		(hatch none 0.5)
		(connect_pads
			(clearance 0)
		)
		(min_thickness 0.25)
		(keepout
			(tracks allowed)
			(vias allowed)
			(pads allowed)
			(copperpour allowed)
			(footprints not_allowed)
		)
		(placement
			(enabled no)
			(sheetname "")
		)
		(fill
			(thermal_gap 0.5)
			(thermal_bridge_width 0.5)
			(island_removal_mode 0)
		)
		(polygon
			(pts
				(arc
					(start 73.000108 -519.050016)
					(mid 78.000098 -514.050026)
					(end 83.000088 -519.050016)
				)
				(arc
					(start 83.000088 -519.050016)
					(mid 78.000098 -524.050006)
					(end 73.000108 -519.050016)
				)
			)
		)
	)
	(zone
		(layer "F.Cu")
		(hatch none 0.5)
		(connect_pads
			(clearance 0)
		)
		(min_thickness 0.25)
		(keepout
			(tracks allowed)
			(vias allowed)
			(pads allowed)
			(copperpour allowed)
			(footprints not_allowed)
		)
		(placement
			(enabled no)
			(sheetname "")
		)
		(fill
			(thermal_gap 0.5)
			(thermal_bridge_width 0.5)
			(island_removal_mode 0)
		)
		(polygon
			(pts
				(arc
					(start 73.000108 -341.250016)
					(mid 78.000098 -336.250026)
					(end 83.000088 -341.250016)
				)
				(arc
					(start 83.000088 -341.250016)
					(mid 78.000098 -346.250006)
					(end 73.000108 -341.250016)
				)
			)
		)
	)
	(zone
		(layer "F.Cu")
		(hatch none 0.5)
		(connect_pads
			(clearance 0)
		)
		(min_thickness 0.25)
		(keepout
			(tracks allowed)
			(vias allowed)
			(pads allowed)
			(copperpour allowed)
			(footprints not_allowed)
		)
		(placement
			(enabled no)
			(sheetname "")
		)
		(fill
			(thermal_gap 0.5)
			(thermal_bridge_width 0.5)
			(island_removal_mode 0)
		)
		(polygon
			(pts
				(xy 44.99991 -321.449954) (xy 44.99991 -346.449904) (xy 55.999888 -346.449904) (xy 55.999888 -321.449954)
			)
		)
	)
	(zone
		(layer "F.Cu")
		(hatch none 0.5)
		(connect_pads
			(clearance 0)
		)
		(min_thickness 0.25)
		(keepout
			(tracks allowed)
			(vias allowed)
			(pads allowed)
			(copperpour allowed)
			(footprints not_allowed)
		)
		(placement
			(enabled no)
			(sheetname "")
		)
		(fill
			(thermal_gap 0.5)
			(thermal_bridge_width 0.5)
			(island_removal_mode 0)
		)
		(polygon
			(pts
				(arc
					(start 73.000108 -121.19991)
					(mid 78.000098 -116.19992)
					(end 83.000088 -121.19991)
				)
				(arc
					(start 83.000088 -121.19991)
					(mid 78.000098 -126.1999)
					(end 73.000108 -121.19991)
				)
			)
		)
	)
	(zone
		(layer "F.Cu")
		(hatch none 0.5)
		(connect_pads
			(clearance 0)
		)
		(min_thickness 0.25)
		(keepout
			(tracks allowed)
			(vias allowed)
			(pads allowed)
			(copperpour allowed)
			(footprints not_allowed)
		)
		(placement
			(enabled no)
			(sheetname "")
		)
		(fill
			(thermal_gap 0.5)
			(thermal_bridge_width 0.5)
			(island_removal_mode 0)
		)
		(polygon
			(pts
				(arc
					(start 86.399878 -464.51012)
					(mid 91.400122 -459.509876)
					(end 96.400112 -464.51012)
				)
				(arc
					(start 96.400112 -464.51012)
					(mid 91.400122 -469.51011)
					(end 86.399878 -464.51012)
				)
			)
		)
	)
	(zone
		(layer "F.Cu")
		(hatch none 0.5)
		(connect_pads
			(clearance 0)
		)
		(min_thickness 0.25)
		(keepout
			(tracks not_allowed)
			(vias allowed)
			(pads allowed)
			(copperpour not_allowed)
			(footprints allowed)
		)
		(placement
			(enabled no)
			(sheetname "")
		)
		(fill
			(thermal_gap 0.5)
			(thermal_bridge_width 0.5)
			(island_removal_mode 0)
		)
		(polygon
			(pts
				(arc
					(start 96.400112 -242.26012)
					(mid 91.400122 -247.26011)
					(end 86.399878 -242.26012)
				)
				(arc
					(start 86.399878 -242.26012)
					(mid 91.400122 -237.259876)
					(end 96.400112 -242.26012)
				)
			)
		)
	)
	(zone
		(layer "F.Cu")
		(hatch none 0.5)
		(connect_pads
			(clearance 0)
		)
		(min_thickness 0.25)
		(keepout
			(tracks allowed)
			(vias allowed)
			(pads allowed)
			(copperpour allowed)
			(footprints not_allowed)
		)
		(placement
			(enabled no)
			(sheetname "")
		)
		(fill
			(thermal_gap 0.5)
			(thermal_bridge_width 0.5)
			(island_removal_mode 0)
		)
		(polygon
			(pts
				(xy 37.975032 0.070104) (xy 37.975032 -88.039956) (xy 28.02509 -88.039956) (xy 28.02509 0.070104)
			)
		)
	)
	(zone
		(layer "F.Cu")
		(hatch none 0.5)
		(connect_pads
			(clearance 0)
		)
		(min_thickness 0.25)
		(keepout
			(tracks not_allowed)
			(vias allowed)
			(pads allowed)
			(copperpour not_allowed)
			(footprints allowed)
		)
		(placement
			(enabled no)
			(sheetname "")
		)
		(fill
			(thermal_gap 0.5)
			(thermal_bridge_width 0.5)
			(island_removal_mode 0)
		)
		(polygon
			(pts
				(arc
					(start 21.599906 -295.900094)
					(mid 16.599916 -300.900084)
					(end 11.599926 -295.900094)
				)
				(arc
					(start 11.599926 -295.900094)
					(mid 16.599916 -290.900104)
					(end 21.599906 -295.900094)
				)
			)
		)
	)
	(zone
		(layer "F.Cu")
		(hatch none 0.5)
		(connect_pads
			(clearance 0)
		)
		(min_thickness 0.25)
		(keepout
			(tracks not_allowed)
			(vias allowed)
			(pads allowed)
			(copperpour not_allowed)
			(footprints allowed)
		)
		(placement
			(enabled no)
			(sheetname "")
		)
		(fill
			(thermal_gap 0.5)
			(thermal_bridge_width 0.5)
			(island_removal_mode 0)
		)
		(polygon
			(pts
				(arc
					(start 96.400112 -197.81012)
					(mid 91.400122 -202.81011)
					(end 86.399878 -197.81012)
				)
				(arc
					(start 86.399878 -197.81012)
					(mid 91.400122 -192.809876)
					(end 96.400112 -197.81012)
				)
			)
		)
	)
	(zone
		(layer "F.Cu")
		(hatch none 0.5)
		(connect_pads
			(clearance 0)
		)
		(min_thickness 0.25)
		(keepout
			(tracks not_allowed)
			(vias allowed)
			(pads allowed)
			(copperpour not_allowed)
			(footprints allowed)
		)
		(placement
			(enabled no)
			(sheetname "")
		)
		(fill
			(thermal_gap 0.5)
			(thermal_bridge_width 0.5)
			(island_removal_mode 0)
		)
		(polygon
			(pts
				(arc
					(start 76.000102 -519.050016)
					(mid 78.000098 -517.05002)
					(end 80.000094 -519.050016)
				)
				(arc
					(start 80.000094 -519.050016)
					(mid 78.000098 -521.050012)
					(end 76.000102 -519.050016)
				)
			)
		)
	)
	(zone
		(layer "F.Cu")
		(hatch none 0.5)
		(connect_pads
			(clearance 0)
		)
		(min_thickness 0.25)
		(keepout
			(tracks allowed)
			(vias allowed)
			(pads allowed)
			(copperpour allowed)
			(footprints not_allowed)
		)
		(placement
			(enabled no)
			(sheetname "")
		)
		(fill
			(thermal_gap 0.5)
			(thermal_bridge_width 0.5)
			(island_removal_mode 0)
		)
		(polygon
			(pts
				(arc
					(start 11.599926 -207.000094)
					(mid 16.599916 -202.000104)
					(end 21.599906 -207.000094)
				)
				(arc
					(start 21.599906 -207.000094)
					(mid 16.599916 -212.000084)
					(end 11.599926 -207.000094)
				)
			)
		)
	)
	(zone
		(layer "F.Cu")
		(hatch none 0.5)
		(connect_pads
			(clearance 0)
		)
		(min_thickness 0.25)
		(keepout
			(tracks not_allowed)
			(vias allowed)
			(pads allowed)
			(copperpour not_allowed)
			(footprints allowed)
		)
		(placement
			(enabled no)
			(sheetname "")
		)
		(fill
			(thermal_gap 0.5)
			(thermal_bridge_width 0.5)
			(island_removal_mode 0)
		)
		(polygon
			(pts
				(arc
					(start 81.60004 -78.300072)
					(mid 78.000098 -81.900014)
					(end 74.399902 -78.300072)
				)
				(arc
					(start 74.399902 -78.300072)
					(mid 78.000098 -74.699876)
					(end 81.60004 -78.300072)
				)
			)
		)
	)
	(zone
		(layer "F.Cu")
		(hatch none 0.5)
		(connect_pads
			(clearance 0)
		)
		(min_thickness 0.25)
		(keepout
			(tracks allowed)
			(vias allowed)
			(pads allowed)
			(copperpour allowed)
			(footprints not_allowed)
		)
		(placement
			(enabled no)
			(sheetname "")
		)
		(fill
			(thermal_gap 0.5)
			(thermal_bridge_width 0.5)
			(island_removal_mode 0)
		)
		(polygon
			(pts
				(xy 17.645126 -396.500096) (xy 17.645126 -413.800036) (xy 0.895096 -413.800036) (xy 0.895096 -396.500096)
			)
		)
	)
	(zone
		(layer "F.Cu")
		(hatch none 0.5)
		(connect_pads
			(clearance 0)
		)
		(min_thickness 0.25)
		(keepout
			(tracks allowed)
			(vias allowed)
			(pads allowed)
			(copperpour allowed)
			(footprints not_allowed)
		)
		(placement
			(enabled no)
			(sheetname "")
		)
		(fill
			(thermal_gap 0.5)
			(thermal_bridge_width 0.5)
			(island_removal_mode 0)
		)
		(polygon
			(pts
				(xy 37.975032 -441.930028) (xy 37.975032 -530.040088) (xy 28.02509 -530.040088) (xy 28.02509 -441.930028)
			)
		)
	)
	(zone
		(layer "F.Cu")
		(hatch none 0.5)
		(connect_pads
			(clearance 0)
		)
		(min_thickness 0.25)
		(keepout
			(tracks allowed)
			(vias allowed)
			(pads allowed)
			(copperpour allowed)
			(footprints not_allowed)
		)
		(placement
			(enabled no)
			(sheetname "")
		)
		(fill
			(thermal_gap 0.5)
			(thermal_bridge_width 0.5)
			(island_removal_mode 0)
		)
		(polygon
			(pts
				(xy 55.999888 -410.349954) (xy 55.999888 -435.349904) (xy 44.99991 -435.349904) (xy 44.99991 -410.349954)
			)
		)
	)
	(zone
		(layer "F.Cu")
		(hatch none 0.5)
		(connect_pads
			(clearance 0)
		)
		(min_thickness 0.25)
		(keepout
			(tracks not_allowed)
			(vias allowed)
			(pads allowed)
			(copperpour not_allowed)
			(footprints allowed)
		)
		(placement
			(enabled no)
			(sheetname "")
		)
		(fill
			(thermal_gap 0.5)
			(thermal_bridge_width 0.5)
			(island_removal_mode 0)
		)
		(polygon
			(pts
				(arc
					(start 83.000088 -210.09991)
					(mid 78.000098 -215.0999)
					(end 73.000108 -210.09991)
				)
				(arc
					(start 73.000108 -210.09991)
					(mid 78.000098 -205.09992)
					(end 83.000088 -210.09991)
				)
			)
		)
	)
	(zone
		(layer "F.Cu")
		(hatch none 0.5)
		(connect_pads
			(clearance 0)
		)
		(min_thickness 0.25)
		(keepout
			(tracks not_allowed)
			(vias allowed)
			(pads allowed)
			(copperpour not_allowed)
			(footprints allowed)
		)
		(placement
			(enabled no)
			(sheetname "")
		)
		(fill
			(thermal_gap 0.5)
			(thermal_bridge_width 0.5)
			(island_removal_mode 0)
		)
		(polygon
			(pts
				(arc
					(start 96.400112 -108.91012)
					(mid 91.400122 -113.91011)
					(end 86.399878 -108.91012)
				)
				(arc
					(start 86.399878 -108.91012)
					(mid 91.400122 -103.909876)
					(end 96.400112 -108.91012)
				)
			)
		)
	)
	(zone
		(layer "F.Cu")
		(hatch none 0.5)
		(connect_pads
			(clearance 0)
		)
		(min_thickness 0.25)
		(keepout
			(tracks allowed)
			(vias allowed)
			(pads allowed)
			(copperpour allowed)
			(footprints not_allowed)
		)
		(placement
			(enabled no)
			(sheetname "")
		)
		(fill
			(thermal_gap 0.5)
			(thermal_bridge_width 0.5)
			(island_removal_mode 0)
		)
		(polygon
			(pts
				(xy 55.999888 -454.799954) (xy 55.999888 -479.799904) (xy 44.99991 -479.799904) (xy 44.99991 -454.799954)
			)
		)
	)
	(zone
		(layers "F.Cu" "B.Cu" "In1.Cu" "In2.Cu" "In3.Cu" "In4.Cu" "In5.Cu" "In6.Cu")
		(name "Package Keepin")
		(hatch none 0.5)
		(connect_pads
			(clearance 0)
		)
		(min_thickness 0.25)
		(keepout
			(tracks allowed)
			(vias allowed)
			(pads allowed)
			(copperpour allowed)
			(footprints allowed)
		)
		(placement
			(enabled no)
			(sheetname "")
		)
		(fill
			(thermal_gap 0.5)
			(thermal_bridge_width 0.5)
			(island_removal_mode 0)
		)
		(polygon
			(pts
				(arc
					(start 101.984048 -1.999996)
					(mid 101.695842 -1.304206)
					(end 101.000052 -1.016)
				)
				(arc
					(start 26.500074 -1.016)
					(mid 26.157747 -1.157797)
					(end 26.01595 -1.500124)
				)
				(arc
					(start 26.01595 -2.500122)
					(mid 25.279069 -4.279111)
					(end 23.50008 -5.015992)
				)
				(arc
					(start 1.500124 -5.015992)
					(mid 1.157797 -5.157789)
					(end 1.016 -5.500116)
				)
				(arc
					(start 1.016 -524.500094)
					(mid 1.157812 -524.842332)
					(end 1.500124 -524.983964)
				)
				(arc
					(start 23.50008 -524.983964)
					(mid 25.279159 -525.720935)
					(end 26.01595 -527.500088)
				)
				(arc
					(start 26.01595 -528.500086)
					(mid 26.157836 -528.842249)
					(end 26.500074 -528.983956)
				)
				(arc
					(start 101.000052 -528.983956)
					(mid 101.695842 -528.69575)
					(end 101.984048 -527.99996)
				)
			)
		)
	)
	(zone
		(layers "F.Cu" "B.Cu" "In1.Cu" "In2.Cu" "In3.Cu" "In4.Cu" "In5.Cu" "In6.Cu")
		(name "Route Keepin")
		(hatch none 0.5)
		(connect_pads
			(clearance 0)
		)
		(min_thickness 0.25)
		(keepout
			(tracks allowed)
			(vias allowed)
			(pads allowed)
			(copperpour allowed)
			(footprints allowed)
		)
		(placement
			(enabled no)
			(sheetname "")
		)
		(fill
			(thermal_gap 0.5)
			(thermal_bridge_width 0.5)
			(island_removal_mode 0)
		)
		(polygon
			(pts
				(arc
					(start 102.492048 -1.999996)
					(mid 102.055052 -0.944996)
					(end 101.000052 -0.508)
				)
				(arc
					(start 26.500074 -0.508)
					(mid 25.798536 -0.798586)
					(end 25.50795 -1.500124)
				)
				(arc
					(start 25.50795 -2.500122)
					(mid 24.919858 -3.9199)
					(end 23.50008 -4.507992)
				)
				(arc
					(start 1.500124 -4.507992)
					(mid 0.798586 -4.798578)
					(end 0.508 -5.500116)
				)
				(arc
					(start 0.508 -524.500094)
					(mid 0.798602 -525.201542)
					(end 1.500124 -525.491964)
				)
				(arc
					(start 23.50008 -525.491964)
					(mid 24.919948 -526.080145)
					(end 25.50795 -527.500088)
				)
				(arc
					(start 25.50795 -528.500086)
					(mid 25.798626 -529.201459)
					(end 26.500074 -529.491956)
				)
				(arc
					(start 101.000052 -529.491956)
					(mid 102.055052 -529.05496)
					(end 102.492048 -527.99996)
				)
			)
		)
	)
	(zone
		(layers "F.Cu" "B.Cu" "In2.Cu" "In3.Cu" "In4.Cu" "In5.Cu")
		(hatch none 0.5)
		(connect_pads
			(clearance 0)
		)
		(min_thickness 0.25)
		(keepout
			(tracks not_allowed)
			(vias allowed)
			(pads allowed)
			(copperpour not_allowed)
			(footprints allowed)
		)
		(placement
			(enabled no)
			(sheetname "")
		)
		(fill yes
			(thermal_gap 0.5)
			(thermal_bridge_width 0.5)
			(island_removal_mode 0)
		)
		(polygon
			(pts
				(arc
					(start 81.107788 -477.799908)
					(mid 77.999844 -474.691964)
					(end 74.8919 -477.799908)
				)
				(arc
					(start 74.8919 -478.799906)
					(mid 77.999844 -481.90785)
					(end 81.107788 -478.799906)
				)
			)
		)
	)
	(zone
		(layer "B.Cu")
		(hatch none 0.5)
		(connect_pads
			(clearance 0)
		)
		(min_thickness 0.25)
		(keepout
			(tracks not_allowed)
			(vias allowed)
			(pads allowed)
			(copperpour not_allowed)
			(footprints allowed)
		)
		(placement
			(enabled no)
			(sheetname "")
		)
		(fill
			(thermal_gap 0.5)
			(thermal_bridge_width 0.5)
			(island_removal_mode 0)
		)
		(polygon
			(pts
				(arc
					(start 11.599926 -118.100094)
					(mid 16.599916 -123.100084)
					(end 21.599906 -118.100094)
				)
				(arc
					(start 21.599906 -118.100094)
					(mid 16.599916 -113.100104)
					(end 11.599926 -118.100094)
				)
			)
		)
	)
	(zone
		(layer "B.Cu")
		(hatch none 0.5)
		(connect_pads
			(clearance 0)
		)
		(min_thickness 0.25)
		(keepout
			(tracks allowed)
			(vias allowed)
			(pads allowed)
			(copperpour allowed)
			(footprints not_allowed)
		)
		(placement
			(enabled no)
			(sheetname "")
		)
		(fill
			(thermal_gap 0.5)
			(thermal_bridge_width 0.5)
			(island_removal_mode 0)
		)
		(polygon
			(pts
				(xy 39.180008 -269.685008) (xy 39.180008 -277.534878) (xy 97.16008 -277.534878) (xy 97.16008 -269.685008)
			)
		)
	)
	(zone
		(layer "B.Cu")
		(hatch none 0.5)
		(connect_pads
			(clearance 0)
		)
		(min_thickness 0.25)
		(keepout
			(tracks not_allowed)
			(vias allowed)
			(pads allowed)
			(copperpour not_allowed)
			(footprints allowed)
		)
		(placement
			(enabled no)
			(sheetname "")
		)
		(fill
			(thermal_gap 0.5)
			(thermal_bridge_width 0.5)
			(island_removal_mode 0)
		)
		(polygon
			(pts
				(arc
					(start 86.399878 -20.01012)
					(mid 91.400122 -25.010364)
					(end 96.400112 -20.01012)
				)
				(arc
					(start 96.400112 -20.01012)
					(mid 91.400122 -15.01013)
					(end 86.399878 -20.01012)
				)
			)
		)
	)
	(zone
		(layer "B.Cu")
		(hatch none 0.5)
		(connect_pads
			(clearance 0)
		)
		(min_thickness 0.25)
		(keepout
			(tracks allowed)
			(vias allowed)
			(pads allowed)
			(copperpour allowed)
			(footprints not_allowed)
		)
		(placement
			(enabled no)
			(sheetname "")
		)
		(fill
			(thermal_gap 0.5)
			(thermal_bridge_width 0.5)
			(island_removal_mode 0)
		)
		(polygon
			(pts
				(arc
					(start 8.599932 -29.200094)
					(mid 16.599916 -37.200078)
					(end 24.5999 -29.200094)
				)
				(arc
					(start 24.5999 -29.200094)
					(mid 16.599916 -21.20011)
					(end 8.599932 -29.200094)
				)
			)
		)
	)
	(zone
		(layer "B.Cu")
		(hatch none 0.5)
		(connect_pads
			(clearance 0)
		)
		(min_thickness 0.25)
		(keepout
			(tracks not_allowed)
			(vias allowed)
			(pads allowed)
			(copperpour not_allowed)
			(footprints allowed)
		)
		(placement
			(enabled no)
			(sheetname "")
		)
		(fill
			(thermal_gap 0.5)
			(thermal_bridge_width 0.5)
			(island_removal_mode 0)
		)
		(polygon
			(pts
				(arc
					(start 95.400114 -242.26012)
					(mid 91.400122 -238.260128)
					(end 87.399876 -242.26012)
				)
				(arc
					(start 87.399876 -242.26012)
					(mid 91.400122 -246.260366)
					(end 95.400114 -242.26012)
				)
			)
		)
	)
	(zone
		(layer "B.Cu")
		(hatch none 0.5)
		(connect_pads
			(clearance 0)
		)
		(min_thickness 0.25)
		(keepout
			(tracks not_allowed)
			(vias allowed)
			(pads allowed)
			(copperpour not_allowed)
			(footprints allowed)
		)
		(placement
			(enabled no)
			(sheetname "")
		)
		(fill
			(thermal_gap 0.5)
			(thermal_bridge_width 0.5)
			(island_removal_mode 0)
		)
		(polygon
			(pts
				(arc
					(start 80.600042 -78.300072)
					(mid 78.000098 -75.700128)
					(end 75.3999 -78.300072)
				)
				(arc
					(start 75.3999 -78.300072)
					(mid 78.000098 -80.90027)
					(end 80.600042 -78.300072)
				)
			)
		)
	)
	(zone
		(layer "B.Cu")
		(hatch none 0.5)
		(connect_pads
			(clearance 0)
		)
		(min_thickness 0.25)
		(keepout
			(tracks allowed)
			(vias allowed)
			(pads allowed)
			(copperpour allowed)
			(footprints not_allowed)
		)
		(placement
			(enabled no)
			(sheetname "")
		)
		(fill
			(thermal_gap 0.5)
			(thermal_bridge_width 0.5)
			(island_removal_mode 0)
		)
		(polygon
			(pts
				(xy 39.180008 -314.135008) (xy 39.180008 -321.984878) (xy 97.16008 -321.984878) (xy 97.16008 -314.135008)
			)
		)
	)
	(zone
		(layer "B.Cu")
		(hatch none 0.5)
		(connect_pads
			(clearance 0)
		)
		(min_thickness 0.25)
		(keepout
			(tracks not_allowed)
			(vias allowed)
			(pads allowed)
			(copperpour not_allowed)
			(footprints allowed)
		)
		(placement
			(enabled no)
			(sheetname "")
		)
		(fill
			(thermal_gap 0.5)
			(thermal_bridge_width 0.5)
			(island_removal_mode 0)
		)
		(polygon
			(pts
				(arc
					(start 86.399878 -286.71012)
					(mid 91.400122 -291.710364)
					(end 96.400112 -286.71012)
				)
				(arc
					(start 96.400112 -286.71012)
					(mid 91.400122 -281.71013)
					(end 86.399878 -286.71012)
				)
			)
		)
	)
	(zone
		(layer "B.Cu")
		(hatch none 0.5)
		(connect_pads
			(clearance 0)
		)
		(min_thickness 0.25)
		(keepout
			(tracks not_allowed)
			(vias allowed)
			(pads allowed)
			(copperpour not_allowed)
			(footprints allowed)
		)
		(placement
			(enabled no)
			(sheetname "")
		)
		(fill
			(thermal_gap 0.5)
			(thermal_bridge_width 0.5)
			(island_removal_mode 0)
		)
		(polygon
			(pts
				(arc
					(start 95.400114 -20.01012)
					(mid 91.400122 -16.010128)
					(end 87.399876 -20.01012)
				)
				(arc
					(start 87.399876 -20.01012)
					(mid 91.400122 -24.010366)
					(end 95.400114 -20.01012)
				)
			)
		)
	)
	(zone
		(layer "B.Cu")
		(hatch none 0.5)
		(connect_pads
			(clearance 0)
		)
		(min_thickness 0.25)
		(keepout
			(tracks not_allowed)
			(vias allowed)
			(pads allowed)
			(copperpour not_allowed)
			(footprints allowed)
		)
		(placement
			(enabled no)
			(sheetname "")
		)
		(fill
			(thermal_gap 0.5)
			(thermal_bridge_width 0.5)
			(island_removal_mode 0)
		)
		(polygon
			(pts
				(arc
					(start 86.399878 -64.46012)
					(mid 91.400122 -69.460364)
					(end 96.400112 -64.46012)
				)
				(arc
					(start 96.400112 -64.46012)
					(mid 91.400122 -59.46013)
					(end 86.399878 -64.46012)
				)
			)
		)
	)
	(zone
		(layer "B.Cu")
		(hatch none 0.5)
		(connect_pads
			(clearance 0)
		)
		(min_thickness 0.25)
		(keepout
			(tracks not_allowed)
			(vias allowed)
			(pads allowed)
			(copperpour not_allowed)
			(footprints allowed)
		)
		(placement
			(enabled no)
			(sheetname "")
		)
		(fill
			(thermal_gap 0.5)
			(thermal_bridge_width 0.5)
			(island_removal_mode 0)
		)
		(polygon
			(pts
				(arc
					(start 86.399878 -331.16012)
					(mid 91.400122 -336.160364)
					(end 96.400112 -331.16012)
				)
				(arc
					(start 96.400112 -331.16012)
					(mid 91.400122 -326.16013)
					(end 86.399878 -331.16012)
				)
			)
		)
	)
	(zone
		(layer "B.Cu")
		(hatch none 0.5)
		(connect_pads
			(clearance 0)
		)
		(min_thickness 0.25)
		(keepout
			(tracks allowed)
			(vias allowed)
			(pads allowed)
			(copperpour allowed)
			(footprints not_allowed)
		)
		(placement
			(enabled no)
			(sheetname "")
		)
		(fill
			(thermal_gap 0.5)
			(thermal_bridge_width 0.5)
			(island_removal_mode 0)
		)
		(polygon
			(pts
				(xy 39.180008 -91.885008) (xy 39.180008 -99.734878) (xy 97.16008 -99.734878) (xy 97.16008 -91.885008)
			)
		)
	)
	(zone
		(layer "B.Cu")
		(hatch none 0.5)
		(connect_pads
			(clearance 0)
		)
		(min_thickness 0.25)
		(keepout
			(tracks allowed)
			(vias allowed)
			(pads allowed)
			(copperpour allowed)
			(footprints not_allowed)
		)
		(placement
			(enabled no)
			(sheetname "")
		)
		(fill
			(thermal_gap 0.5)
			(thermal_bridge_width 0.5)
			(island_removal_mode 0)
		)
		(polygon
			(pts
				(arc
					(start 21.599906 -384.800094)
					(mid 16.599916 -379.800104)
					(end 11.599926 -384.800094)
				)
				(arc
					(start 11.599926 -384.800094)
					(mid 16.599916 -389.800084)
					(end 21.599906 -384.800094)
				)
			)
		)
	)
	(zone
		(layer "B.Cu")
		(hatch none 0.5)
		(connect_pads
			(clearance 0)
		)
		(min_thickness 0.25)
		(keepout
			(tracks allowed)
			(vias allowed)
			(pads allowed)
			(copperpour allowed)
			(footprints not_allowed)
		)
		(placement
			(enabled no)
			(sheetname "")
		)
		(fill
			(thermal_gap 0.5)
			(thermal_bridge_width 0.5)
			(island_removal_mode 0)
		)
		(polygon
			(pts
				(xy 39.180008 -2.985008) (xy 39.180008 -10.834878) (xy 97.16008 -10.834878) (xy 97.16008 -2.985008)
			)
		)
	)
	(zone
		(layer "B.Cu")
		(hatch none 0.5)
		(connect_pads
			(clearance 0)
		)
		(min_thickness 0.25)
		(keepout
			(tracks not_allowed)
			(vias allowed)
			(pads allowed)
			(copperpour not_allowed)
			(footprints allowed)
		)
		(placement
			(enabled no)
			(sheetname "")
		)
		(fill
			(thermal_gap 0.5)
			(thermal_bridge_width 0.5)
			(island_removal_mode 0)
		)
		(polygon
			(pts
				(arc
					(start 95.400114 -464.51012)
					(mid 91.400122 -460.510128)
					(end 87.399876 -464.51012)
				)
				(arc
					(start 87.399876 -464.51012)
					(mid 91.400122 -468.510366)
					(end 95.400114 -464.51012)
				)
			)
		)
	)
	(zone
		(layer "B.Cu")
		(hatch none 0.5)
		(connect_pads
			(clearance 0)
		)
		(min_thickness 0.25)
		(keepout
			(tracks not_allowed)
			(vias allowed)
			(pads allowed)
			(copperpour not_allowed)
			(footprints allowed)
		)
		(placement
			(enabled no)
			(sheetname "")
		)
		(fill
			(thermal_gap 0.5)
			(thermal_bridge_width 0.5)
			(island_removal_mode 0)
		)
		(polygon
			(pts
				(arc
					(start 86.399878 -153.36012)
					(mid 91.400122 -158.360364)
					(end 96.400112 -153.36012)
				)
				(arc
					(start 96.400112 -153.36012)
					(mid 91.400122 -148.36013)
					(end 86.399878 -153.36012)
				)
			)
		)
	)
	(zone
		(layer "B.Cu")
		(hatch none 0.5)
		(connect_pads
			(clearance 0)
		)
		(min_thickness 0.25)
		(keepout
			(tracks allowed)
			(vias allowed)
			(pads allowed)
			(copperpour allowed)
			(footprints not_allowed)
		)
		(placement
			(enabled no)
			(sheetname "")
		)
		(fill
			(thermal_gap 0.5)
			(thermal_bridge_width 0.5)
			(island_removal_mode 0)
		)
		(polygon
			(pts
				(arc
					(start 70.000114 -121.19991)
					(mid 78.000098 -129.199894)
					(end 86.000082 -121.19991)
				)
				(arc
					(start 86.000082 -121.19991)
					(mid 78.000098 -113.199926)
					(end 70.000114 -121.19991)
				)
			)
		)
	)
	(zone
		(layer "B.Cu")
		(hatch none 0.5)
		(connect_pads
			(clearance 0)
		)
		(min_thickness 0.25)
		(keepout
			(tracks not_allowed)
			(vias allowed)
			(pads allowed)
			(copperpour not_allowed)
			(footprints allowed)
		)
		(placement
			(enabled no)
			(sheetname "")
		)
		(fill
			(thermal_gap 0.5)
			(thermal_bridge_width 0.5)
			(island_removal_mode 0)
		)
		(polygon
			(pts
				(arc
					(start 73.000108 -210.09991)
					(mid 78.000098 -215.0999)
					(end 83.000088 -210.09991)
				)
				(arc
					(start 83.000088 -210.09991)
					(mid 78.000098 -205.09992)
					(end 73.000108 -210.09991)
				)
			)
		)
	)
	(zone
		(layer "B.Cu")
		(hatch none 0.5)
		(connect_pads
			(clearance 0)
		)
		(min_thickness 0.25)
		(keepout
			(tracks not_allowed)
			(vias allowed)
			(pads allowed)
			(copperpour not_allowed)
			(footprints allowed)
		)
		(placement
			(enabled no)
			(sheetname "")
		)
		(fill
			(thermal_gap 0.5)
			(thermal_bridge_width 0.5)
			(island_removal_mode 0)
		)
		(polygon
			(pts
				(arc
					(start 86.399878 -464.51012)
					(mid 91.400122 -469.510364)
					(end 96.400112 -464.51012)
				)
				(arc
					(start 96.400112 -464.51012)
					(mid 91.400122 -459.51013)
					(end 86.399878 -464.51012)
				)
			)
		)
	)
	(zone
		(layer "B.Cu")
		(hatch none 0.5)
		(connect_pads
			(clearance 0)
		)
		(min_thickness 0.25)
		(keepout
			(tracks not_allowed)
			(vias allowed)
			(pads allowed)
			(copperpour not_allowed)
			(footprints allowed)
		)
		(placement
			(enabled no)
			(sheetname "")
		)
		(fill
			(thermal_gap 0.5)
			(thermal_bridge_width 0.5)
			(island_removal_mode 0)
		)
		(polygon
			(pts
				(arc
					(start 73.000108 -341.250016)
					(mid 78.000098 -346.250006)
					(end 83.000088 -341.250016)
				)
				(arc
					(start 83.000088 -341.250016)
					(mid 78.000098 -336.250026)
					(end 73.000108 -341.250016)
				)
			)
		)
	)
	(zone
		(layer "B.Cu")
		(hatch none 0.5)
		(connect_pads
			(clearance 0)
		)
		(min_thickness 0.25)
		(keepout
			(tracks not_allowed)
			(vias allowed)
			(pads allowed)
			(copperpour not_allowed)
			(footprints allowed)
		)
		(placement
			(enabled no)
			(sheetname "")
		)
		(fill
			(thermal_gap 0.5)
			(thermal_bridge_width 0.5)
			(island_removal_mode 0)
		)
		(polygon
			(pts
				(arc
					(start 95.400114 -286.71012)
					(mid 91.400122 -282.710128)
					(end 87.399876 -286.71012)
				)
				(arc
					(start 87.399876 -286.71012)
					(mid 91.400122 -290.710366)
					(end 95.400114 -286.71012)
				)
			)
		)
	)
	(zone
		(layer "B.Cu")
		(hatch none 0.5)
		(connect_pads
			(clearance 0)
		)
		(min_thickness 0.25)
		(keepout
			(tracks allowed)
			(vias allowed)
			(pads allowed)
			(copperpour allowed)
			(footprints not_allowed)
		)
		(placement
			(enabled no)
			(sheetname "")
		)
		(fill
			(thermal_gap 0.5)
			(thermal_bridge_width 0.5)
			(island_removal_mode 0)
		)
		(polygon
			(pts
				(arc
					(start 8.599932 -207.000094)
					(mid 16.599916 -215.000078)
					(end 24.5999 -207.000094)
				)
				(arc
					(start 24.5999 -207.000094)
					(mid 16.599916 -199.00011)
					(end 8.599932 -207.000094)
				)
			)
		)
	)
	(zone
		(layer "B.Cu")
		(hatch none 0.5)
		(connect_pads
			(clearance 0)
		)
		(min_thickness 0.25)
		(keepout
			(tracks allowed)
			(vias allowed)
			(pads allowed)
			(copperpour allowed)
			(footprints not_allowed)
		)
		(placement
			(enabled no)
			(sheetname "")
		)
		(fill
			(thermal_gap 0.5)
			(thermal_bridge_width 0.5)
			(island_removal_mode 0)
		)
		(polygon
			(pts
				(xy 39.180008 -180.785008) (xy 39.180008 -188.634878) (xy 97.16008 -188.634878) (xy 97.16008 -180.785008)
			)
		)
	)
	(zone
		(layer "B.Cu")
		(hatch none 0.5)
		(connect_pads
			(clearance 0)
		)
		(min_thickness 0.25)
		(keepout
			(tracks not_allowed)
			(vias allowed)
			(pads allowed)
			(copperpour not_allowed)
			(footprints allowed)
		)
		(placement
			(enabled no)
			(sheetname "")
		)
		(fill
			(thermal_gap 0.5)
			(thermal_bridge_width 0.5)
			(island_removal_mode 0)
		)
		(polygon
			(pts
				(arc
					(start 95.400114 -508.96012)
					(mid 91.400122 -504.960128)
					(end 87.399876 -508.96012)
				)
				(arc
					(start 87.399876 -508.96012)
					(mid 91.400122 -512.960366)
					(end 95.400114 -508.96012)
				)
			)
		)
	)
	(zone
		(layer "B.Cu")
		(hatch none 0.5)
		(connect_pads
			(clearance 0)
		)
		(min_thickness 0.25)
		(keepout
			(tracks not_allowed)
			(vias allowed)
			(pads allowed)
			(copperpour not_allowed)
			(footprints allowed)
		)
		(placement
			(enabled no)
			(sheetname "")
		)
		(fill
			(thermal_gap 0.5)
			(thermal_bridge_width 0.5)
			(island_removal_mode 0)
		)
		(polygon
			(pts
				(arc
					(start 80.000094 -430.150016)
					(mid 78.000098 -428.15002)
					(end 76.000102 -430.150016)
				)
				(arc
					(start 76.000102 -430.150016)
					(mid 78.000098 -432.150012)
					(end 80.000094 -430.150016)
				)
			)
		)
	)
	(zone
		(layer "B.Cu")
		(hatch none 0.5)
		(connect_pads
			(clearance 0)
		)
		(min_thickness 0.25)
		(keepout
			(tracks not_allowed)
			(vias allowed)
			(pads allowed)
			(copperpour not_allowed)
			(footprints allowed)
		)
		(placement
			(enabled no)
			(sheetname "")
		)
		(fill
			(thermal_gap 0.5)
			(thermal_bridge_width 0.5)
			(island_removal_mode 0)
		)
		(polygon
			(pts
				(arc
					(start 86.399878 -420.06012)
					(mid 91.400122 -425.060364)
					(end 96.400112 -420.06012)
				)
				(arc
					(start 96.400112 -420.06012)
					(mid 91.400122 -415.06013)
					(end 86.399878 -420.06012)
				)
			)
		)
	)
	(zone
		(layer "B.Cu")
		(hatch none 0.5)
		(connect_pads
			(clearance 0)
		)
		(min_thickness 0.25)
		(keepout
			(tracks not_allowed)
			(vias allowed)
			(pads allowed)
			(copperpour not_allowed)
			(footprints allowed)
		)
		(placement
			(enabled no)
			(sheetname "")
		)
		(fill
			(thermal_gap 0.5)
			(thermal_bridge_width 0.5)
			(island_removal_mode 0)
		)
		(polygon
			(pts
				(arc
					(start 95.400114 -64.46012)
					(mid 91.400122 -60.460128)
					(end 87.399876 -64.46012)
				)
				(arc
					(start 87.399876 -64.46012)
					(mid 91.400122 -68.460366)
					(end 95.400114 -64.46012)
				)
			)
		)
	)
	(zone
		(layer "B.Cu")
		(hatch none 0.5)
		(connect_pads
			(clearance 0)
		)
		(min_thickness 0.25)
		(keepout
			(tracks allowed)
			(vias allowed)
			(pads allowed)
			(copperpour allowed)
			(footprints not_allowed)
		)
		(placement
			(enabled no)
			(sheetname "")
		)
		(fill
			(thermal_gap 0.5)
			(thermal_bridge_width 0.5)
			(island_removal_mode 0)
		)
		(polygon
			(pts
				(arc
					(start 8.599932 -118.100094)
					(mid 16.599916 -126.100078)
					(end 24.5999 -118.100094)
				)
				(arc
					(start 24.5999 -118.100094)
					(mid 16.599916 -110.10011)
					(end 8.599932 -118.100094)
				)
			)
		)
	)
	(zone
		(layer "B.Cu")
		(hatch none 0.5)
		(connect_pads
			(clearance 0)
		)
		(min_thickness 0.25)
		(keepout
			(tracks not_allowed)
			(vias allowed)
			(pads allowed)
			(copperpour not_allowed)
			(footprints allowed)
		)
		(placement
			(enabled no)
			(sheetname "")
		)
		(fill
			(thermal_gap 0.5)
			(thermal_bridge_width 0.5)
			(island_removal_mode 0)
		)
		(polygon
			(pts
				(arc
					(start 11.599926 -384.800094)
					(mid 16.599916 -389.800084)
					(end 21.599906 -384.800094)
				)
				(arc
					(start 21.599906 -384.800094)
					(mid 16.599916 -379.800104)
					(end 11.599926 -384.800094)
				)
			)
		)
	)
	(zone
		(layer "B.Cu")
		(hatch none 0.5)
		(connect_pads
			(clearance 0)
		)
		(min_thickness 0.25)
		(keepout
			(tracks not_allowed)
			(vias allowed)
			(pads allowed)
			(copperpour not_allowed)
			(footprints allowed)
		)
		(placement
			(enabled no)
			(sheetname "")
		)
		(fill
			(thermal_gap 0.5)
			(thermal_bridge_width 0.5)
			(island_removal_mode 0)
		)
		(polygon
			(pts
				(arc
					(start 18.599912 -207.000094)
					(mid 16.599916 -205.000098)
					(end 14.59992 -207.000094)
				)
				(arc
					(start 14.59992 -207.000094)
					(mid 16.599916 -209.00009)
					(end 18.599912 -207.000094)
				)
			)
		)
	)
	(zone
		(layer "B.Cu")
		(hatch none 0.5)
		(connect_pads
			(clearance 0)
		)
		(min_thickness 0.25)
		(keepout
			(tracks allowed)
			(vias allowed)
			(pads allowed)
			(copperpour allowed)
			(footprints not_allowed)
		)
		(placement
			(enabled no)
			(sheetname "")
		)
		(fill
			(thermal_gap 0.5)
			(thermal_bridge_width 0.5)
			(island_removal_mode 0)
		)
		(polygon
			(pts
				(arc
					(start 70.000114 -210.09991)
					(mid 78.000098 -218.099894)
					(end 86.000082 -210.09991)
				)
				(arc
					(start 86.000082 -210.09991)
					(mid 78.000098 -202.099926)
					(end 70.000114 -210.09991)
				)
			)
		)
	)
	(zone
		(layer "B.Cu")
		(hatch none 0.5)
		(connect_pads
			(clearance 0)
		)
		(min_thickness 0.25)
		(keepout
			(tracks allowed)
			(vias allowed)
			(pads allowed)
			(copperpour allowed)
			(footprints not_allowed)
		)
		(placement
			(enabled no)
			(sheetname "")
		)
		(fill
			(thermal_gap 0.5)
			(thermal_bridge_width 0.5)
			(island_removal_mode 0)
		)
		(polygon
			(pts
				(arc
					(start 83.000088 -210.09991)
					(mid 78.000098 -205.09992)
					(end 73.000108 -210.09991)
				)
				(arc
					(start 73.000108 -210.09991)
					(mid 78.000098 -215.0999)
					(end 83.000088 -210.09991)
				)
			)
		)
	)
	(zone
		(layer "B.Cu")
		(hatch none 0.5)
		(connect_pads
			(clearance 0)
		)
		(min_thickness 0.25)
		(keepout
			(tracks not_allowed)
			(vias allowed)
			(pads allowed)
			(copperpour not_allowed)
			(footprints allowed)
		)
		(placement
			(enabled no)
			(sheetname "")
		)
		(fill
			(thermal_gap 0.5)
			(thermal_bridge_width 0.5)
			(island_removal_mode 0)
		)
		(polygon
			(pts
				(arc
					(start 73.000108 -32.29991)
					(mid 78.000098 -37.2999)
					(end 83.000088 -32.29991)
				)
				(arc
					(start 83.000088 -32.29991)
					(mid 78.000098 -27.29992)
					(end 73.000108 -32.29991)
				)
			)
		)
	)
	(zone
		(layer "B.Cu")
		(hatch none 0.5)
		(connect_pads
			(clearance 0)
		)
		(min_thickness 0.25)
		(keepout
			(tracks allowed)
			(vias allowed)
			(pads allowed)
			(copperpour allowed)
			(footprints not_allowed)
		)
		(placement
			(enabled no)
			(sheetname "")
		)
		(fill
			(thermal_gap 0.5)
			(thermal_bridge_width 0.5)
			(island_removal_mode 0)
		)
		(polygon
			(pts
				(arc
					(start 70.000114 -519.050016)
					(mid 78.000098 -527.05)
					(end 86.000082 -519.050016)
				)
				(arc
					(start 86.000082 -519.050016)
					(mid 78.000098 -511.050032)
					(end 70.000114 -519.050016)
				)
			)
		)
	)
	(zone
		(layer "B.Cu")
		(hatch none 0.5)
		(connect_pads
			(clearance 0)
		)
		(min_thickness 0.25)
		(keepout
			(tracks not_allowed)
			(vias allowed)
			(pads allowed)
			(copperpour not_allowed)
			(footprints allowed)
		)
		(placement
			(enabled no)
			(sheetname "")
		)
		(fill
			(thermal_gap 0.5)
			(thermal_bridge_width 0.5)
			(island_removal_mode 0)
		)
		(polygon
			(pts
				(arc
					(start 11.599926 -473.700094)
					(mid 16.599916 -478.700084)
					(end 21.599906 -473.700094)
				)
				(arc
					(start 21.599906 -473.700094)
					(mid 16.599916 -468.700104)
					(end 11.599926 -473.700094)
				)
			)
		)
	)
	(zone
		(layer "B.Cu")
		(hatch none 0.5)
		(connect_pads
			(clearance 0)
		)
		(min_thickness 0.25)
		(keepout
			(tracks not_allowed)
			(vias allowed)
			(pads allowed)
			(copperpour not_allowed)
			(footprints allowed)
		)
		(placement
			(enabled no)
			(sheetname "")
		)
		(fill
			(thermal_gap 0.5)
			(thermal_bridge_width 0.5)
			(island_removal_mode 0)
		)
		(polygon
			(pts
				(arc
					(start 86.399878 -242.26012)
					(mid 91.400122 -247.260364)
					(end 96.400112 -242.26012)
				)
				(arc
					(start 96.400112 -242.26012)
					(mid 91.400122 -237.26013)
					(end 86.399878 -242.26012)
				)
			)
		)
	)
	(zone
		(layer "B.Cu")
		(hatch none 0.5)
		(connect_pads
			(clearance 0)
		)
		(min_thickness 0.25)
		(keepout
			(tracks allowed)
			(vias allowed)
			(pads allowed)
			(copperpour allowed)
			(footprints not_allowed)
		)
		(placement
			(enabled no)
			(sheetname "")
		)
		(fill
			(thermal_gap 0.5)
			(thermal_bridge_width 0.5)
			(island_removal_mode 0)
		)
		(polygon
			(pts
				(arc
					(start 83.000088 -32.29991)
					(mid 78.000098 -27.29992)
					(end 73.000108 -32.29991)
				)
				(arc
					(start 73.000108 -32.29991)
					(mid 78.000098 -37.2999)
					(end 83.000088 -32.29991)
				)
			)
		)
	)
	(zone
		(layer "B.Cu")
		(hatch none 0.5)
		(connect_pads
			(clearance 0)
		)
		(min_thickness 0.25)
		(keepout
			(tracks not_allowed)
			(vias allowed)
			(pads allowed)
			(copperpour not_allowed)
			(footprints allowed)
		)
		(placement
			(enabled no)
			(sheetname "")
		)
		(fill
			(thermal_gap 0.5)
			(thermal_bridge_width 0.5)
			(island_removal_mode 0)
		)
		(polygon
			(pts
				(arc
					(start 18.599912 -473.700094)
					(mid 16.599916 -471.700098)
					(end 14.59992 -473.700094)
				)
				(arc
					(start 14.59992 -473.700094)
					(mid 16.599916 -475.70009)
					(end 18.599912 -473.700094)
				)
			)
		)
	)
	(zone
		(layer "B.Cu")
		(hatch none 0.5)
		(connect_pads
			(clearance 0)
		)
		(min_thickness 0.25)
		(keepout
			(tracks allowed)
			(vias allowed)
			(pads allowed)
			(copperpour allowed)
			(footprints not_allowed)
		)
		(placement
			(enabled no)
			(sheetname "")
		)
		(fill
			(thermal_gap 0.5)
			(thermal_bridge_width 0.5)
			(island_removal_mode 0)
		)
		(polygon
			(pts
				(xy 39.180008 -136.335008) (xy 39.180008 -144.184878) (xy 97.16008 -144.184878) (xy 97.16008 -136.335008)
			)
		)
	)
	(zone
		(layer "B.Cu")
		(hatch none 0.5)
		(connect_pads
			(clearance 0)
		)
		(min_thickness 0.25)
		(keepout
			(tracks allowed)
			(vias allowed)
			(pads allowed)
			(copperpour allowed)
			(footprints not_allowed)
		)
		(placement
			(enabled no)
			(sheetname "")
		)
		(fill
			(thermal_gap 0.5)
			(thermal_bridge_width 0.5)
			(island_removal_mode 0)
		)
		(polygon
			(pts
				(xy 39.180008 -225.235008) (xy 39.180008 -233.084878) (xy 97.16008 -233.084878) (xy 97.16008 -225.235008)
			)
		)
	)
	(zone
		(layer "B.Cu")
		(hatch none 0.5)
		(connect_pads
			(clearance 0)
		)
		(min_thickness 0.25)
		(keepout
			(tracks allowed)
			(vias allowed)
			(pads allowed)
			(copperpour allowed)
			(footprints not_allowed)
		)
		(placement
			(enabled no)
			(sheetname "")
		)
		(fill
			(thermal_gap 0.5)
			(thermal_bridge_width 0.5)
			(island_removal_mode 0)
		)
		(polygon
			(pts
				(arc
					(start 21.599906 -295.900094)
					(mid 16.599916 -290.900104)
					(end 11.599926 -295.900094)
				)
				(arc
					(start 11.599926 -295.900094)
					(mid 16.599916 -300.900084)
					(end 21.599906 -295.900094)
				)
			)
		)
	)
	(zone
		(layer "B.Cu")
		(hatch none 0.5)
		(connect_pads
			(clearance 0)
		)
		(min_thickness 0.25)
		(keepout
			(tracks not_allowed)
			(vias allowed)
			(pads allowed)
			(copperpour not_allowed)
			(footprints allowed)
		)
		(placement
			(enabled no)
			(sheetname "")
		)
		(fill
			(thermal_gap 0.5)
			(thermal_bridge_width 0.5)
			(island_removal_mode 0)
		)
		(polygon
			(pts
				(arc
					(start 73.000108 -121.19991)
					(mid 78.000098 -126.1999)
					(end 83.000088 -121.19991)
				)
				(arc
					(start 83.000088 -121.19991)
					(mid 78.000098 -116.19992)
					(end 73.000108 -121.19991)
				)
			)
		)
	)
	(zone
		(layer "B.Cu")
		(hatch none 0.5)
		(connect_pads
			(clearance 0)
		)
		(min_thickness 0.25)
		(keepout
			(tracks not_allowed)
			(vias allowed)
			(pads allowed)
			(copperpour not_allowed)
			(footprints allowed)
		)
		(placement
			(enabled no)
			(sheetname "")
		)
		(fill
			(thermal_gap 0.5)
			(thermal_bridge_width 0.5)
			(island_removal_mode 0)
		)
		(polygon
			(pts
				(arc
					(start 73.000108 -519.050016)
					(mid 78.000098 -524.050006)
					(end 83.000088 -519.050016)
				)
				(arc
					(start 83.000088 -519.050016)
					(mid 78.000098 -514.050026)
					(end 73.000108 -519.050016)
				)
			)
		)
	)
	(zone
		(layer "B.Cu")
		(hatch none 0.5)
		(connect_pads
			(clearance 0)
		)
		(min_thickness 0.25)
		(keepout
			(tracks not_allowed)
			(vias allowed)
			(pads allowed)
			(copperpour not_allowed)
			(footprints allowed)
		)
		(placement
			(enabled no)
			(sheetname "")
		)
		(fill
			(thermal_gap 0.5)
			(thermal_bridge_width 0.5)
			(island_removal_mode 0)
		)
		(polygon
			(pts
				(arc
					(start 11.599926 -207.000094)
					(mid 16.599916 -212.000084)
					(end 21.599906 -207.000094)
				)
				(arc
					(start 21.599906 -207.000094)
					(mid 16.599916 -202.000104)
					(end 11.599926 -207.000094)
				)
			)
		)
	)
	(zone
		(layer "B.Cu")
		(hatch none 0.5)
		(connect_pads
			(clearance 0)
		)
		(min_thickness 0.25)
		(keepout
			(tracks allowed)
			(vias allowed)
			(pads allowed)
			(copperpour allowed)
			(footprints not_allowed)
		)
		(placement
			(enabled no)
			(sheetname "")
		)
		(fill
			(thermal_gap 0.5)
			(thermal_bridge_width 0.5)
			(island_removal_mode 0)
		)
		(polygon
			(pts
				(arc
					(start 21.599906 -473.700094)
					(mid 16.599916 -468.700104)
					(end 11.599926 -473.700094)
				)
				(arc
					(start 11.599926 -473.700094)
					(mid 16.599916 -478.700084)
					(end 21.599906 -473.700094)
				)
			)
		)
	)
	(zone
		(layer "B.Cu")
		(hatch none 0.5)
		(connect_pads
			(clearance 0)
		)
		(min_thickness 0.25)
		(keepout
			(tracks not_allowed)
			(vias allowed)
			(pads allowed)
			(copperpour not_allowed)
			(footprints allowed)
		)
		(placement
			(enabled no)
			(sheetname "")
		)
		(fill
			(thermal_gap 0.5)
			(thermal_bridge_width 0.5)
			(island_removal_mode 0)
		)
		(polygon
			(pts
				(arc
					(start 18.599912 -118.100094)
					(mid 16.599916 -116.100098)
					(end 14.59992 -118.100094)
				)
				(arc
					(start 14.59992 -118.100094)
					(mid 16.599916 -120.10009)
					(end 18.599912 -118.100094)
				)
			)
		)
	)
	(zone
		(layer "B.Cu")
		(hatch none 0.5)
		(connect_pads
			(clearance 0)
		)
		(min_thickness 0.25)
		(keepout
			(tracks allowed)
			(vias allowed)
			(pads allowed)
			(copperpour allowed)
			(footprints not_allowed)
		)
		(placement
			(enabled no)
			(sheetname "")
		)
		(fill
			(thermal_gap 0.5)
			(thermal_bridge_width 0.5)
			(island_removal_mode 0)
		)
		(polygon
			(pts
				(arc
					(start 83.000088 -121.19991)
					(mid 78.000098 -116.19992)
					(end 73.000108 -121.19991)
				)
				(arc
					(start 73.000108 -121.19991)
					(mid 78.000098 -126.1999)
					(end 83.000088 -121.19991)
				)
			)
		)
	)
	(zone
		(layer "B.Cu")
		(hatch none 0.5)
		(connect_pads
			(clearance 0)
		)
		(min_thickness 0.25)
		(keepout
			(tracks not_allowed)
			(vias allowed)
			(pads allowed)
			(copperpour not_allowed)
			(footprints allowed)
		)
		(placement
			(enabled no)
			(sheetname "")
		)
		(fill
			(thermal_gap 0.5)
			(thermal_bridge_width 0.5)
			(island_removal_mode 0)
		)
		(polygon
			(pts
				(arc
					(start 18.599912 -384.800094)
					(mid 16.599916 -382.800098)
					(end 14.59992 -384.800094)
				)
				(arc
					(start 14.59992 -384.800094)
					(mid 16.599916 -386.80009)
					(end 18.599912 -384.800094)
				)
			)
		)
	)
	(zone
		(layer "B.Cu")
		(hatch none 0.5)
		(connect_pads
			(clearance 0)
		)
		(min_thickness 0.25)
		(keepout
			(tracks not_allowed)
			(vias allowed)
			(pads allowed)
			(copperpour not_allowed)
			(footprints allowed)
		)
		(placement
			(enabled no)
			(sheetname "")
		)
		(fill
			(thermal_gap 0.5)
			(thermal_bridge_width 0.5)
			(island_removal_mode 0)
		)
		(polygon
			(pts
				(arc
					(start 73.000108 -430.150016)
					(mid 78.000098 -435.150006)
					(end 83.000088 -430.150016)
				)
				(arc
					(start 83.000088 -430.150016)
					(mid 78.000098 -425.150026)
					(end 73.000108 -430.150016)
				)
			)
		)
	)
	(zone
		(layer "B.Cu")
		(hatch none 0.5)
		(connect_pads
			(clearance 0)
		)
		(min_thickness 0.25)
		(keepout
			(tracks allowed)
			(vias allowed)
			(pads allowed)
			(copperpour allowed)
			(footprints not_allowed)
		)
		(placement
			(enabled no)
			(sheetname "")
		)
		(fill
			(thermal_gap 0.5)
			(thermal_bridge_width 0.5)
			(island_removal_mode 0)
		)
		(polygon
			(pts
				(arc
					(start 83.000088 -430.150016)
					(mid 78.000098 -425.150026)
					(end 73.000108 -430.150016)
				)
				(arc
					(start 73.000108 -430.150016)
					(mid 78.000098 -435.150006)
					(end 83.000088 -430.150016)
				)
			)
		)
	)
	(zone
		(layer "B.Cu")
		(hatch none 0.5)
		(connect_pads
			(clearance 0)
		)
		(min_thickness 0.25)
		(keepout
			(tracks not_allowed)
			(vias allowed)
			(pads allowed)
			(copperpour not_allowed)
			(footprints allowed)
		)
		(placement
			(enabled no)
			(sheetname "")
		)
		(fill
			(thermal_gap 0.5)
			(thermal_bridge_width 0.5)
			(island_removal_mode 0)
		)
		(polygon
			(pts
				(arc
					(start 86.399878 -508.96012)
					(mid 91.400122 -513.960364)
					(end 96.400112 -508.96012)
				)
				(arc
					(start 96.400112 -508.96012)
					(mid 91.400122 -503.96013)
					(end 86.399878 -508.96012)
				)
			)
		)
	)
	(zone
		(layer "B.Cu")
		(hatch none 0.5)
		(connect_pads
			(clearance 0)
		)
		(min_thickness 0.25)
		(keepout
			(tracks allowed)
			(vias allowed)
			(pads allowed)
			(copperpour allowed)
			(footprints not_allowed)
		)
		(placement
			(enabled no)
			(sheetname "")
		)
		(fill
			(thermal_gap 0.5)
			(thermal_bridge_width 0.5)
			(island_removal_mode 0)
		)
		(polygon
			(pts
				(arc
					(start 8.599932 -295.900094)
					(mid 16.599916 -303.900078)
					(end 24.5999 -295.900094)
				)
				(arc
					(start 24.5999 -295.900094)
					(mid 16.599916 -287.90011)
					(end 8.599932 -295.900094)
				)
			)
		)
	)
	(zone
		(layer "B.Cu")
		(hatch none 0.5)
		(connect_pads
			(clearance 0)
		)
		(min_thickness 0.25)
		(keepout
			(tracks allowed)
			(vias allowed)
			(pads allowed)
			(copperpour allowed)
			(footprints not_allowed)
		)
		(placement
			(enabled no)
			(sheetname "")
		)
		(fill
			(thermal_gap 0.5)
			(thermal_bridge_width 0.5)
			(island_removal_mode 0)
		)
		(polygon
			(pts
				(arc
					(start 21.599906 -207.000094)
					(mid 16.599916 -202.000104)
					(end 11.599926 -207.000094)
				)
				(arc
					(start 11.599926 -207.000094)
					(mid 16.599916 -212.000084)
					(end 21.599906 -207.000094)
				)
			)
		)
	)
	(zone
		(layer "B.Cu")
		(hatch none 0.5)
		(connect_pads
			(clearance 0)
		)
		(min_thickness 0.25)
		(keepout
			(tracks not_allowed)
			(vias allowed)
			(pads allowed)
			(copperpour not_allowed)
			(footprints allowed)
		)
		(placement
			(enabled no)
			(sheetname "")
		)
		(fill
			(thermal_gap 0.5)
			(thermal_bridge_width 0.5)
			(island_removal_mode 0)
		)
		(polygon
			(pts
				(arc
					(start 74.399902 -78.300072)
					(mid 78.000098 -81.900268)
					(end 81.60004 -78.300072)
				)
				(arc
					(start 81.60004 -78.300072)
					(mid 78.000098 -74.70013)
					(end 74.399902 -78.300072)
				)
			)
		)
	)
	(zone
		(layer "B.Cu")
		(hatch none 0.5)
		(connect_pads
			(clearance 0)
		)
		(min_thickness 0.25)
		(keepout
			(tracks not_allowed)
			(vias allowed)
			(pads allowed)
			(copperpour not_allowed)
			(footprints allowed)
		)
		(placement
			(enabled no)
			(sheetname "")
		)
		(fill
			(thermal_gap 0.5)
			(thermal_bridge_width 0.5)
			(island_removal_mode 0)
		)
		(polygon
			(pts
				(arc
					(start 11.599926 -295.900094)
					(mid 16.599916 -300.900084)
					(end 21.599906 -295.900094)
				)
				(arc
					(start 21.599906 -295.900094)
					(mid 16.599916 -290.900104)
					(end 11.599926 -295.900094)
				)
			)
		)
	)
	(zone
		(layer "B.Cu")
		(hatch none 0.5)
		(connect_pads
			(clearance 0)
		)
		(min_thickness 0.25)
		(keepout
			(tracks not_allowed)
			(vias allowed)
			(pads allowed)
			(copperpour not_allowed)
			(footprints allowed)
		)
		(placement
			(enabled no)
			(sheetname "")
		)
		(fill
			(thermal_gap 0.5)
			(thermal_bridge_width 0.5)
			(island_removal_mode 0)
		)
		(polygon
			(pts
				(arc
					(start 80.000094 -121.19991)
					(mid 78.000098 -119.199914)
					(end 76.000102 -121.19991)
				)
				(arc
					(start 76.000102 -121.19991)
					(mid 78.000098 -123.199906)
					(end 80.000094 -121.19991)
				)
			)
		)
	)
	(zone
		(layer "B.Cu")
		(hatch none 0.5)
		(connect_pads
			(clearance 0)
		)
		(min_thickness 0.25)
		(keepout
			(tracks not_allowed)
			(vias allowed)
			(pads allowed)
			(copperpour not_allowed)
			(footprints allowed)
		)
		(placement
			(enabled no)
			(sheetname "")
		)
		(fill
			(thermal_gap 0.5)
			(thermal_bridge_width 0.5)
			(island_removal_mode 0)
		)
		(polygon
			(pts
				(arc
					(start 95.400114 -153.36012)
					(mid 91.400122 -149.360128)
					(end 87.399876 -153.36012)
				)
				(arc
					(start 87.399876 -153.36012)
					(mid 91.400122 -157.360366)
					(end 95.400114 -153.36012)
				)
			)
		)
	)
	(zone
		(layer "B.Cu")
		(hatch none 0.5)
		(connect_pads
			(clearance 0)
		)
		(min_thickness 0.25)
		(keepout
			(tracks allowed)
			(vias allowed)
			(pads allowed)
			(copperpour allowed)
			(footprints not_allowed)
		)
		(placement
			(enabled no)
			(sheetname "")
		)
		(fill
			(thermal_gap 0.5)
			(thermal_bridge_width 0.5)
			(island_removal_mode 0)
		)
		(polygon
			(pts
				(arc
					(start 70.000114 -32.29991)
					(mid 78.000098 -40.299894)
					(end 86.000082 -32.29991)
				)
				(arc
					(start 86.000082 -32.29991)
					(mid 78.000098 -24.299926)
					(end 70.000114 -32.29991)
				)
			)
		)
	)
	(zone
		(layer "B.Cu")
		(hatch none 0.5)
		(connect_pads
			(clearance 0)
		)
		(min_thickness 0.25)
		(keepout
			(tracks allowed)
			(vias allowed)
			(pads allowed)
			(copperpour allowed)
			(footprints not_allowed)
		)
		(placement
			(enabled no)
			(sheetname "")
		)
		(fill
			(thermal_gap 0.5)
			(thermal_bridge_width 0.5)
			(island_removal_mode 0)
		)
		(polygon
			(pts
				(arc
					(start 83.000088 -341.250016)
					(mid 78.000098 -336.250026)
					(end 73.000108 -341.250016)
				)
				(arc
					(start 73.000108 -341.250016)
					(mid 78.000098 -346.250006)
					(end 83.000088 -341.250016)
				)
			)
		)
	)
	(zone
		(layer "B.Cu")
		(hatch none 0.5)
		(connect_pads
			(clearance 0)
		)
		(min_thickness 0.25)
		(keepout
			(tracks not_allowed)
			(vias allowed)
			(pads allowed)
			(copperpour not_allowed)
			(footprints allowed)
		)
		(placement
			(enabled no)
			(sheetname "")
		)
		(fill
			(thermal_gap 0.5)
			(thermal_bridge_width 0.5)
			(island_removal_mode 0)
		)
		(polygon
			(pts
				(arc
					(start 86.399878 -197.81012)
					(mid 91.400122 -202.810364)
					(end 96.400112 -197.81012)
				)
				(arc
					(start 96.400112 -197.81012)
					(mid 91.400122 -192.81013)
					(end 86.399878 -197.81012)
				)
			)
		)
	)
	(zone
		(layer "B.Cu")
		(hatch none 0.5)
		(connect_pads
			(clearance 0)
		)
		(min_thickness 0.25)
		(keepout
			(tracks not_allowed)
			(vias allowed)
			(pads allowed)
			(copperpour not_allowed)
			(footprints allowed)
		)
		(placement
			(enabled no)
			(sheetname "")
		)
		(fill
			(thermal_gap 0.5)
			(thermal_bridge_width 0.5)
			(island_removal_mode 0)
		)
		(polygon
			(pts
				(arc
					(start 95.400114 -108.91012)
					(mid 91.400122 -104.910128)
					(end 87.399876 -108.91012)
				)
				(arc
					(start 87.399876 -108.91012)
					(mid 91.400122 -112.910366)
					(end 95.400114 -108.91012)
				)
			)
		)
	)
	(zone
		(layer "B.Cu")
		(hatch none 0.5)
		(connect_pads
			(clearance 0)
		)
		(min_thickness 0.25)
		(keepout
			(tracks allowed)
			(vias allowed)
			(pads allowed)
			(copperpour allowed)
			(footprints not_allowed)
		)
		(placement
			(enabled no)
			(sheetname "")
		)
		(fill
			(thermal_gap 0.5)
			(thermal_bridge_width 0.5)
			(island_removal_mode 0)
		)
		(polygon
			(pts
				(arc
					(start 8.599932 -473.700094)
					(mid 16.599916 -481.700078)
					(end 24.5999 -473.700094)
				)
				(arc
					(start 24.5999 -473.700094)
					(mid 16.599916 -465.70011)
					(end 8.599932 -473.700094)
				)
			)
		)
	)
	(zone
		(layer "B.Cu")
		(hatch none 0.5)
		(connect_pads
			(clearance 0)
		)
		(min_thickness 0.25)
		(keepout
			(tracks allowed)
			(vias allowed)
			(pads allowed)
			(copperpour allowed)
			(footprints not_allowed)
		)
		(placement
			(enabled no)
			(sheetname "")
		)
		(fill
			(thermal_gap 0.5)
			(thermal_bridge_width 0.5)
			(island_removal_mode 0)
		)
		(polygon
			(pts
				(xy 39.180008 -403.035008) (xy 39.180008 -410.884878) (xy 97.16008 -410.884878) (xy 97.16008 -403.035008)
			)
		)
	)
	(zone
		(layer "B.Cu")
		(hatch none 0.5)
		(connect_pads
			(clearance 0)
		)
		(min_thickness 0.25)
		(keepout
			(tracks not_allowed)
			(vias allowed)
			(pads allowed)
			(copperpour not_allowed)
			(footprints allowed)
		)
		(placement
			(enabled no)
			(sheetname "")
		)
		(fill
			(thermal_gap 0.5)
			(thermal_bridge_width 0.5)
			(island_removal_mode 0)
		)
		(polygon
			(pts
				(arc
					(start 80.000094 -341.250016)
					(mid 78.000098 -339.25002)
					(end 76.000102 -341.250016)
				)
				(arc
					(start 76.000102 -341.250016)
					(mid 78.000098 -343.250012)
					(end 80.000094 -341.250016)
				)
			)
		)
	)
	(zone
		(layer "B.Cu")
		(hatch none 0.5)
		(connect_pads
			(clearance 0)
		)
		(min_thickness 0.25)
		(keepout
			(tracks not_allowed)
			(vias allowed)
			(pads allowed)
			(copperpour not_allowed)
			(footprints allowed)
		)
		(placement
			(enabled no)
			(sheetname "")
		)
		(fill
			(thermal_gap 0.5)
			(thermal_bridge_width 0.5)
			(island_removal_mode 0)
		)
		(polygon
			(pts
				(arc
					(start 18.599912 -295.900094)
					(mid 16.599916 -293.900098)
					(end 14.59992 -295.900094)
				)
				(arc
					(start 14.59992 -295.900094)
					(mid 16.599916 -297.90009)
					(end 18.599912 -295.900094)
				)
			)
		)
	)
	(zone
		(layer "B.Cu")
		(hatch none 0.5)
		(connect_pads
			(clearance 0)
		)
		(min_thickness 0.25)
		(keepout
			(tracks not_allowed)
			(vias allowed)
			(pads allowed)
			(copperpour not_allowed)
			(footprints allowed)
		)
		(placement
			(enabled no)
			(sheetname "")
		)
		(fill
			(thermal_gap 0.5)
			(thermal_bridge_width 0.5)
			(island_removal_mode 0)
		)
		(polygon
			(pts
				(arc
					(start 74.399902 -478.799906)
					(mid 78.000098 -482.400102)
					(end 81.60004 -478.799906)
				)
				(arc
					(start 81.60004 -477.799908)
					(mid 78.000098 -474.199966)
					(end 74.399902 -477.799908)
				)
			)
		)
	)
	(zone
		(layer "B.Cu")
		(hatch none 0.5)
		(connect_pads
			(clearance 0)
		)
		(min_thickness 0.25)
		(keepout
			(tracks allowed)
			(vias allowed)
			(pads allowed)
			(copperpour allowed)
			(footprints not_allowed)
		)
		(placement
			(enabled no)
			(sheetname "")
		)
		(fill
			(thermal_gap 0.5)
			(thermal_bridge_width 0.5)
			(island_removal_mode 0)
		)
		(polygon
			(pts
				(arc
					(start 8.599932 -384.800094)
					(mid 16.599916 -392.800078)
					(end 24.5999 -384.800094)
				)
				(arc
					(start 24.5999 -384.800094)
					(mid 16.599916 -376.80011)
					(end 8.599932 -384.800094)
				)
			)
		)
	)
	(zone
		(layer "B.Cu")
		(hatch none 0.5)
		(connect_pads
			(clearance 0)
		)
		(min_thickness 0.25)
		(keepout
			(tracks not_allowed)
			(vias allowed)
			(pads allowed)
			(copperpour not_allowed)
			(footprints allowed)
		)
		(placement
			(enabled no)
			(sheetname "")
		)
		(fill
			(thermal_gap 0.5)
			(thermal_bridge_width 0.5)
			(island_removal_mode 0)
		)
		(polygon
			(pts
				(arc
					(start 80.000094 -519.050016)
					(mid 78.000098 -517.05002)
					(end 76.000102 -519.050016)
				)
				(arc
					(start 76.000102 -519.050016)
					(mid 78.000098 -521.050012)
					(end 80.000094 -519.050016)
				)
			)
		)
	)
	(zone
		(layer "B.Cu")
		(hatch none 0.5)
		(connect_pads
			(clearance 0)
		)
		(min_thickness 0.25)
		(keepout
			(tracks not_allowed)
			(vias allowed)
			(pads allowed)
			(copperpour not_allowed)
			(footprints allowed)
		)
		(placement
			(enabled no)
			(sheetname "")
		)
		(fill
			(thermal_gap 0.5)
			(thermal_bridge_width 0.5)
			(island_removal_mode 0)
		)
		(polygon
			(pts
				(arc
					(start 80.000094 -210.09991)
					(mid 78.000098 -208.099914)
					(end 76.000102 -210.09991)
				)
				(arc
					(start 76.000102 -210.09991)
					(mid 78.000098 -212.099906)
					(end 80.000094 -210.09991)
				)
			)
		)
	)
	(zone
		(layer "B.Cu")
		(hatch none 0.5)
		(connect_pads
			(clearance 0)
		)
		(min_thickness 0.25)
		(keepout
			(tracks not_allowed)
			(vias allowed)
			(pads allowed)
			(copperpour not_allowed)
			(footprints allowed)
		)
		(placement
			(enabled no)
			(sheetname "")
		)
		(fill
			(thermal_gap 0.5)
			(thermal_bridge_width 0.5)
			(island_removal_mode 0)
		)
		(polygon
			(pts
				(arc
					(start 18.599912 -29.200094)
					(mid 16.599916 -27.200098)
					(end 14.59992 -29.200094)
				)
				(arc
					(start 14.59992 -29.200094)
					(mid 16.599916 -31.20009)
					(end 18.599912 -29.200094)
				)
			)
		)
	)
	(zone
		(layer "B.Cu")
		(hatch none 0.5)
		(connect_pads
			(clearance 0)
		)
		(min_thickness 0.25)
		(keepout
			(tracks allowed)
			(vias allowed)
			(pads allowed)
			(copperpour allowed)
			(footprints not_allowed)
		)
		(placement
			(enabled no)
			(sheetname "")
		)
		(fill
			(thermal_gap 0.5)
			(thermal_bridge_width 0.5)
			(island_removal_mode 0)
		)
		(polygon
			(pts
				(arc
					(start 21.599906 -29.200094)
					(mid 16.599916 -24.200104)
					(end 11.599926 -29.200094)
				)
				(arc
					(start 11.599926 -29.200094)
					(mid 16.599916 -34.200084)
					(end 21.599906 -29.200094)
				)
			)
		)
	)
	(zone
		(layer "B.Cu")
		(hatch none 0.5)
		(connect_pads
			(clearance 0)
		)
		(min_thickness 0.25)
		(keepout
			(tracks allowed)
			(vias allowed)
			(pads allowed)
			(copperpour allowed)
			(footprints not_allowed)
		)
		(placement
			(enabled no)
			(sheetname "")
		)
		(fill
			(thermal_gap 0.5)
			(thermal_bridge_width 0.5)
			(island_removal_mode 0)
		)
		(polygon
			(pts
				(xy 39.180008 -491.935008) (xy 39.180008 -499.784878) (xy 97.16008 -499.784878) (xy 97.16008 -491.935008)
			)
		)
	)
	(zone
		(layer "B.Cu")
		(hatch none 0.5)
		(connect_pads
			(clearance 0)
		)
		(min_thickness 0.25)
		(keepout
			(tracks allowed)
			(vias allowed)
			(pads allowed)
			(copperpour allowed)
			(footprints not_allowed)
		)
		(placement
			(enabled no)
			(sheetname "")
		)
		(fill
			(thermal_gap 0.5)
			(thermal_bridge_width 0.5)
			(island_removal_mode 0)
		)
		(polygon
			(pts
				(arc
					(start 70.000114 -341.250016)
					(mid 78.000098 -349.25)
					(end 86.000082 -341.250016)
				)
				(arc
					(start 86.000082 -341.250016)
					(mid 78.000098 -333.250032)
					(end 70.000114 -341.250016)
				)
			)
		)
	)
	(zone
		(layer "B.Cu")
		(hatch none 0.5)
		(connect_pads
			(clearance 0)
		)
		(min_thickness 0.25)
		(keepout
			(tracks allowed)
			(vias allowed)
			(pads allowed)
			(copperpour allowed)
			(footprints not_allowed)
		)
		(placement
			(enabled no)
			(sheetname "")
		)
		(fill
			(thermal_gap 0.5)
			(thermal_bridge_width 0.5)
			(island_removal_mode 0)
		)
		(polygon
			(pts
				(arc
					(start 70.000114 -430.150016)
					(mid 78.000098 -438.15)
					(end 86.000082 -430.150016)
				)
				(arc
					(start 86.000082 -430.150016)
					(mid 78.000098 -422.150032)
					(end 70.000114 -430.150016)
				)
			)
		)
	)
	(zone
		(layer "B.Cu")
		(hatch none 0.5)
		(connect_pads
			(clearance 0)
		)
		(min_thickness 0.25)
		(keepout
			(tracks not_allowed)
			(vias allowed)
			(pads allowed)
			(copperpour not_allowed)
			(footprints allowed)
		)
		(placement
			(enabled no)
			(sheetname "")
		)
		(fill
			(thermal_gap 0.5)
			(thermal_bridge_width 0.5)
			(island_removal_mode 0)
		)
		(polygon
			(pts
				(arc
					(start 86.399878 -375.61012)
					(mid 91.400122 -380.610364)
					(end 96.400112 -375.61012)
				)
				(arc
					(start 96.400112 -375.61012)
					(mid 91.400122 -370.61013)
					(end 86.399878 -375.61012)
				)
			)
		)
	)
	(zone
		(layer "B.Cu")
		(hatch none 0.5)
		(connect_pads
			(clearance 0)
		)
		(min_thickness 0.25)
		(keepout
			(tracks not_allowed)
			(vias allowed)
			(pads allowed)
			(copperpour not_allowed)
			(footprints allowed)
		)
		(placement
			(enabled no)
			(sheetname "")
		)
		(fill
			(thermal_gap 0.5)
			(thermal_bridge_width 0.5)
			(island_removal_mode 0)
		)
		(polygon
			(pts
				(arc
					(start 80.600042 -478.799906)
					(mid 78.000098 -481.39985)
					(end 75.3999 -478.799906)
				)
				(arc
					(start 75.3999 -477.799908)
					(mid 78.000098 -475.19971)
					(end 80.600042 -477.799908)
				)
			)
		)
	)
	(zone
		(layer "B.Cu")
		(hatch none 0.5)
		(connect_pads
			(clearance 0)
		)
		(min_thickness 0.25)
		(keepout
			(tracks not_allowed)
			(vias allowed)
			(pads allowed)
			(copperpour not_allowed)
			(footprints allowed)
		)
		(placement
			(enabled no)
			(sheetname "")
		)
		(fill
			(thermal_gap 0.5)
			(thermal_bridge_width 0.5)
			(island_removal_mode 0)
		)
		(polygon
			(pts
				(arc
					(start 95.400114 -420.06012)
					(mid 91.400122 -416.060128)
					(end 87.399876 -420.06012)
				)
				(arc
					(start 87.399876 -420.06012)
					(mid 91.400122 -424.060366)
					(end 95.400114 -420.06012)
				)
			)
		)
	)
	(zone
		(layer "B.Cu")
		(hatch none 0.5)
		(connect_pads
			(clearance 0)
		)
		(min_thickness 0.25)
		(keepout
			(tracks allowed)
			(vias allowed)
			(pads allowed)
			(copperpour allowed)
			(footprints not_allowed)
		)
		(placement
			(enabled no)
			(sheetname "")
		)
		(fill
			(thermal_gap 0.5)
			(thermal_bridge_width 0.5)
			(island_removal_mode 0)
		)
		(polygon
			(pts
				(xy 39.180008 -358.585008) (xy 39.180008 -366.434878) (xy 97.16008 -366.434878) (xy 97.16008 -358.585008)
			)
		)
	)
	(zone
		(layer "B.Cu")
		(hatch none 0.5)
		(connect_pads
			(clearance 0)
		)
		(min_thickness 0.25)
		(keepout
			(tracks allowed)
			(vias allowed)
			(pads allowed)
			(copperpour allowed)
			(footprints not_allowed)
		)
		(placement
			(enabled no)
			(sheetname "")
		)
		(fill
			(thermal_gap 0.5)
			(thermal_bridge_width 0.5)
			(island_removal_mode 0)
		)
		(polygon
			(pts
				(xy 39.180008 -47.435008) (xy 39.180008 -55.284878) (xy 97.16008 -55.284878) (xy 97.16008 -47.435008)
			)
		)
	)
	(zone
		(layer "B.Cu")
		(hatch none 0.5)
		(connect_pads
			(clearance 0)
		)
		(min_thickness 0.25)
		(keepout
			(tracks not_allowed)
			(vias allowed)
			(pads allowed)
			(copperpour not_allowed)
			(footprints allowed)
		)
		(placement
			(enabled no)
			(sheetname "")
		)
		(fill
			(thermal_gap 0.5)
			(thermal_bridge_width 0.5)
			(island_removal_mode 0)
		)
		(polygon
			(pts
				(arc
					(start 80.000094 -32.29991)
					(mid 78.000098 -30.299914)
					(end 76.000102 -32.29991)
				)
				(arc
					(start 76.000102 -32.29991)
					(mid 78.000098 -34.299906)
					(end 80.000094 -32.29991)
				)
			)
		)
	)
	(zone
		(layer "B.Cu")
		(hatch none 0.5)
		(connect_pads
			(clearance 0)
		)
		(min_thickness 0.25)
		(keepout
			(tracks not_allowed)
			(vias allowed)
			(pads allowed)
			(copperpour not_allowed)
			(footprints allowed)
		)
		(placement
			(enabled no)
			(sheetname "")
		)
		(fill
			(thermal_gap 0.5)
			(thermal_bridge_width 0.5)
			(island_removal_mode 0)
		)
		(polygon
			(pts
				(arc
					(start 95.400114 -375.61012)
					(mid 91.400122 -371.610128)
					(end 87.399876 -375.61012)
				)
				(arc
					(start 87.399876 -375.61012)
					(mid 91.400122 -379.610366)
					(end 95.400114 -375.61012)
				)
			)
		)
	)
	(zone
		(layer "B.Cu")
		(hatch none 0.5)
		(connect_pads
			(clearance 0)
		)
		(min_thickness 0.25)
		(keepout
			(tracks allowed)
			(vias allowed)
			(pads allowed)
			(copperpour allowed)
			(footprints not_allowed)
		)
		(placement
			(enabled no)
			(sheetname "")
		)
		(fill
			(thermal_gap 0.5)
			(thermal_bridge_width 0.5)
			(island_removal_mode 0)
		)
		(polygon
			(pts
				(arc
					(start 21.599906 -118.100094)
					(mid 16.599916 -113.100104)
					(end 11.599926 -118.100094)
				)
				(arc
					(start 11.599926 -118.100094)
					(mid 16.599916 -123.100084)
					(end 21.599906 -118.100094)
				)
			)
		)
	)
	(zone
		(layer "B.Cu")
		(hatch none 0.5)
		(connect_pads
			(clearance 0)
		)
		(min_thickness 0.25)
		(keepout
			(tracks allowed)
			(vias allowed)
			(pads allowed)
			(copperpour allowed)
			(footprints not_allowed)
		)
		(placement
			(enabled no)
			(sheetname "")
		)
		(fill
			(thermal_gap 0.5)
			(thermal_bridge_width 0.5)
			(island_removal_mode 0)
		)
		(polygon
			(pts
				(xy 39.180008 -447.485008) (xy 39.180008 -455.334878) (xy 97.16008 -455.334878) (xy 97.16008 -447.485008)
			)
		)
	)
	(zone
		(layer "B.Cu")
		(hatch none 0.5)
		(connect_pads
			(clearance 0)
		)
		(min_thickness 0.25)
		(keepout
			(tracks not_allowed)
			(vias allowed)
			(pads allowed)
			(copperpour not_allowed)
			(footprints allowed)
		)
		(placement
			(enabled no)
			(sheetname "")
		)
		(fill
			(thermal_gap 0.5)
			(thermal_bridge_width 0.5)
			(island_removal_mode 0)
		)
		(polygon
			(pts
				(arc
					(start 95.400114 -331.16012)
					(mid 91.400122 -327.160128)
					(end 87.399876 -331.16012)
				)
				(arc
					(start 87.399876 -331.16012)
					(mid 91.400122 -335.160366)
					(end 95.400114 -331.16012)
				)
			)
		)
	)
	(zone
		(layer "B.Cu")
		(hatch none 0.5)
		(connect_pads
			(clearance 0)
		)
		(min_thickness 0.25)
		(keepout
			(tracks not_allowed)
			(vias allowed)
			(pads allowed)
			(copperpour not_allowed)
			(footprints allowed)
		)
		(placement
			(enabled no)
			(sheetname "")
		)
		(fill
			(thermal_gap 0.5)
			(thermal_bridge_width 0.5)
			(island_removal_mode 0)
		)
		(polygon
			(pts
				(arc
					(start 86.399878 -108.91012)
					(mid 91.400122 -113.910364)
					(end 96.400112 -108.91012)
				)
				(arc
					(start 96.400112 -108.91012)
					(mid 91.400122 -103.91013)
					(end 86.399878 -108.91012)
				)
			)
		)
	)
	(zone
		(layer "B.Cu")
		(hatch none 0.5)
		(connect_pads
			(clearance 0)
		)
		(min_thickness 0.25)
		(keepout
			(tracks allowed)
			(vias allowed)
			(pads allowed)
			(copperpour allowed)
			(footprints not_allowed)
		)
		(placement
			(enabled no)
			(sheetname "")
		)
		(fill
			(thermal_gap 0.5)
			(thermal_bridge_width 0.5)
			(island_removal_mode 0)
		)
		(polygon
			(pts
				(arc
					(start 83.000088 -519.050016)
					(mid 78.000098 -514.050026)
					(end 73.000108 -519.050016)
				)
				(arc
					(start 73.000108 -519.050016)
					(mid 78.000098 -524.050006)
					(end 83.000088 -519.050016)
				)
			)
		)
	)
	(zone
		(layer "B.Cu")
		(hatch none 0.5)
		(connect_pads
			(clearance 0)
		)
		(min_thickness 0.25)
		(keepout
			(tracks not_allowed)
			(vias allowed)
			(pads allowed)
			(copperpour not_allowed)
			(footprints allowed)
		)
		(placement
			(enabled no)
			(sheetname "")
		)
		(fill
			(thermal_gap 0.5)
			(thermal_bridge_width 0.5)
			(island_removal_mode 0)
		)
		(polygon
			(pts
				(arc
					(start 11.599926 -29.200094)
					(mid 16.599916 -34.200084)
					(end 21.599906 -29.200094)
				)
				(arc
					(start 21.599906 -29.200094)
					(mid 16.599916 -24.200104)
					(end 11.599926 -29.200094)
				)
			)
		)
	)
	(zone
		(layer "B.Cu")
		(hatch none 0.5)
		(connect_pads
			(clearance 0)
		)
		(min_thickness 0.25)
		(keepout
			(tracks not_allowed)
			(vias allowed)
			(pads allowed)
			(copperpour not_allowed)
			(footprints allowed)
		)
		(placement
			(enabled no)
			(sheetname "")
		)
		(fill
			(thermal_gap 0.5)
			(thermal_bridge_width 0.5)
			(island_removal_mode 0)
		)
		(polygon
			(pts
				(arc
					(start 95.400114 -197.81012)
					(mid 91.400122 -193.810128)
					(end 87.399876 -197.81012)
				)
				(arc
					(start 87.399876 -197.81012)
					(mid 91.400122 -201.810366)
					(end 95.400114 -197.81012)
				)
			)
		)
	)
	(zone
		(layers "In2.Cu" "In3.Cu" "In4.Cu" "In5.Cu")
		(hatch none 0.5)
		(connect_pads
			(clearance 0)
		)
		(min_thickness 0.25)
		(keepout
			(tracks not_allowed)
			(vias allowed)
			(pads allowed)
			(copperpour not_allowed)
			(footprints allowed)
		)
		(placement
			(enabled no)
			(sheetname "")
		)
		(fill yes
			(thermal_gap 0.5)
			(thermal_bridge_width 0.5)
			(island_removal_mode 0)
		)
		(polygon
			(pts
				(arc
					(start 16.60017 -290.87445)
					(mid 11.57478 -295.89984)
					(end 16.60017 -300.92523)
				)
				(arc
					(start 16.60017 -301.15383)
					(mid 12.885038 -299.614972)
					(end 11.34618 -295.89984)
				)
				(arc
					(start 11.34618 -295.89984)
					(mid 12.885038 -292.184708)
					(end 16.60017 -290.64585)
				)
			)
		)
	)
	(zone
		(layers "In2.Cu" "In3.Cu" "In4.Cu" "In5.Cu")
		(hatch none 0.5)
		(connect_pads
			(clearance 0)
		)
		(min_thickness 0.25)
		(keepout
			(tracks not_allowed)
			(vias allowed)
			(pads allowed)
			(copperpour not_allowed)
			(footprints allowed)
		)
		(placement
			(enabled no)
			(sheetname "")
		)
		(fill yes
			(thermal_gap 0.5)
			(thermal_bridge_width 0.5)
			(island_removal_mode 0)
		)
		(polygon
			(pts
				(arc
					(start 16.599916 -24.17445)
					(mid 11.574526 -29.19984)
					(end 16.599916 -34.22523)
				)
				(arc
					(start 16.599916 -34.45383)
					(mid 12.884784 -32.914972)
					(end 11.345926 -29.19984)
				)
				(arc
					(start 11.345926 -29.19984)
					(mid 12.884784 -25.484708)
					(end 16.599916 -23.94585)
				)
			)
		)
	)
	(zone
		(layers "In2.Cu" "In3.Cu" "In4.Cu" "In5.Cu")
		(hatch none 0.5)
		(connect_pads
			(clearance 0)
		)
		(min_thickness 0.25)
		(keepout
			(tracks not_allowed)
			(vias allowed)
			(pads allowed)
			(copperpour not_allowed)
			(footprints allowed)
		)
		(placement
			(enabled no)
			(sheetname "")
		)
		(fill yes
			(thermal_gap 0.5)
			(thermal_bridge_width 0.5)
			(island_removal_mode 0)
		)
		(polygon
			(pts
				(arc
					(start 16.60017 -290.87445)
					(mid 21.62556 -295.89984)
					(end 16.60017 -300.92523)
				)
				(arc
					(start 16.60017 -301.15383)
					(mid 20.315302 -299.614972)
					(end 21.85416 -295.89984)
				)
				(arc
					(start 21.85416 -295.89984)
					(mid 20.315302 -292.184708)
					(end 16.60017 -290.64585)
				)
			)
		)
	)
	(zone
		(layers "In2.Cu" "In3.Cu" "In4.Cu" "In5.Cu")
		(hatch none 0.5)
		(connect_pads
			(clearance 0)
		)
		(min_thickness 0.25)
		(keepout
			(tracks not_allowed)
			(vias allowed)
			(pads allowed)
			(copperpour not_allowed)
			(footprints allowed)
		)
		(placement
			(enabled no)
			(sheetname "")
		)
		(fill yes
			(thermal_gap 0.5)
			(thermal_bridge_width 0.5)
			(island_removal_mode 0)
		)
		(polygon
			(pts
				(arc
					(start 78.000098 -346.380562)
					(mid 72.869298 -341.249762)
					(end 78.000098 -336.118962)
				)
				(arc
					(start 78.000098 -336.118962)
					(mid 78.050898 -336.169762)
					(end 78.000098 -336.220562)
				)
				(arc
					(start 78.000098 -336.220562)
					(mid 72.970898 -341.249762)
					(end 78.000098 -346.278962)
				)
				(arc
					(start 78.000098 -346.278962)
					(mid 78.050898 -346.329762)
					(end 78.000098 -346.380562)
				)
			)
		)
	)
	(zone
		(layers "In2.Cu" "In3.Cu" "In4.Cu" "In5.Cu")
		(hatch none 0.5)
		(connect_pads
			(clearance 0)
		)
		(min_thickness 0.25)
		(keepout
			(tracks not_allowed)
			(vias allowed)
			(pads allowed)
			(copperpour not_allowed)
			(footprints allowed)
		)
		(placement
			(enabled no)
			(sheetname "")
		)
		(fill yes
			(thermal_gap 0.5)
			(thermal_bridge_width 0.5)
			(island_removal_mode 0)
		)
		(polygon
			(pts
				(arc
					(start 16.60017 -201.97445)
					(mid 11.57478 -206.99984)
					(end 16.60017 -212.02523)
				)
				(arc
					(start 16.60017 -212.25383)
					(mid 12.885038 -210.714972)
					(end 11.34618 -206.99984)
				)
				(arc
					(start 11.34618 -206.99984)
					(mid 12.885038 -203.284708)
					(end 16.60017 -201.74585)
				)
			)
		)
	)
	(zone
		(layers "In2.Cu" "In3.Cu" "In4.Cu" "In5.Cu")
		(hatch none 0.5)
		(connect_pads
			(clearance 0)
		)
		(min_thickness 0.25)
		(keepout
			(tracks not_allowed)
			(vias allowed)
			(pads allowed)
			(copperpour not_allowed)
			(footprints allowed)
		)
		(placement
			(enabled no)
			(sheetname "")
		)
		(fill yes
			(thermal_gap 0.5)
			(thermal_bridge_width 0.5)
			(island_removal_mode 0)
		)
		(polygon
			(pts
				(arc
					(start 78.000098 -37.430456)
					(mid 83.130898 -32.299656)
					(end 78.000098 -27.168856)
				)
				(arc
					(start 78.000098 -27.168856)
					(mid 77.949298 -27.219656)
					(end 78.000098 -27.270456)
				)
				(arc
					(start 78.000098 -27.270456)
					(mid 83.029298 -32.299656)
					(end 78.000098 -37.328856)
				)
				(arc
					(start 78.000098 -37.328856)
					(mid 77.949298 -37.379656)
					(end 78.000098 -37.430456)
				)
			)
		)
	)
	(zone
		(layers "In2.Cu" "In3.Cu" "In4.Cu" "In5.Cu")
		(hatch none 0.5)
		(connect_pads
			(clearance 0)
		)
		(min_thickness 0.25)
		(keepout
			(tracks not_allowed)
			(vias allowed)
			(pads allowed)
			(copperpour not_allowed)
			(footprints allowed)
		)
		(placement
			(enabled no)
			(sheetname "")
		)
		(fill yes
			(thermal_gap 0.5)
			(thermal_bridge_width 0.5)
			(island_removal_mode 0)
		)
		(polygon
			(pts
				(arc
					(start 78.000098 -215.230456)
					(mid 72.869298 -210.099656)
					(end 78.000098 -204.968856)
				)
				(arc
					(start 78.000098 -204.968856)
					(mid 78.050898 -205.019656)
					(end 78.000098 -205.070456)
				)
				(arc
					(start 78.000098 -205.070456)
					(mid 72.970898 -210.099656)
					(end 78.000098 -215.128856)
				)
				(arc
					(start 78.000098 -215.128856)
					(mid 78.050898 -215.179656)
					(end 78.000098 -215.230456)
				)
			)
		)
	)
	(zone
		(layers "In2.Cu" "In3.Cu" "In4.Cu" "In5.Cu")
		(hatch none 0.5)
		(connect_pads
			(clearance 0)
		)
		(min_thickness 0.25)
		(keepout
			(tracks not_allowed)
			(vias allowed)
			(pads allowed)
			(copperpour not_allowed)
			(footprints allowed)
		)
		(placement
			(enabled no)
			(sheetname "")
		)
		(fill yes
			(thermal_gap 0.5)
			(thermal_bridge_width 0.5)
			(island_removal_mode 0)
		)
		(polygon
			(pts
				(arc
					(start 16.60017 -113.07445)
					(mid 21.62556 -118.09984)
					(end 16.60017 -123.12523)
				)
				(arc
					(start 16.60017 -123.35383)
					(mid 20.315302 -121.814972)
					(end 21.85416 -118.09984)
				)
				(arc
					(start 21.85416 -118.09984)
					(mid 20.315302 -114.384708)
					(end 16.60017 -112.84585)
				)
			)
		)
	)
	(zone
		(layers "In2.Cu" "In3.Cu" "In4.Cu" "In5.Cu")
		(hatch none 0.5)
		(connect_pads
			(clearance 0)
		)
		(min_thickness 0.25)
		(keepout
			(tracks not_allowed)
			(vias allowed)
			(pads allowed)
			(copperpour not_allowed)
			(footprints allowed)
		)
		(placement
			(enabled no)
			(sheetname "")
		)
		(fill yes
			(thermal_gap 0.5)
			(thermal_bridge_width 0.5)
			(island_removal_mode 0)
		)
		(polygon
			(pts
				(arc
					(start 78.000098 -435.280562)
					(mid 83.130898 -430.149762)
					(end 78.000098 -425.018962)
				)
				(arc
					(start 78.000098 -425.018962)
					(mid 77.949298 -425.069762)
					(end 78.000098 -425.120562)
				)
				(arc
					(start 78.000098 -425.120562)
					(mid 83.029298 -430.149762)
					(end 78.000098 -435.178962)
				)
				(arc
					(start 78.000098 -435.178962)
					(mid 77.949298 -435.229762)
					(end 78.000098 -435.280562)
				)
			)
		)
	)
	(zone
		(layers "In2.Cu" "In3.Cu" "In4.Cu" "In5.Cu")
		(hatch none 0.5)
		(connect_pads
			(clearance 0)
		)
		(min_thickness 0.25)
		(keepout
			(tracks not_allowed)
			(vias allowed)
			(pads allowed)
			(copperpour not_allowed)
			(footprints allowed)
		)
		(placement
			(enabled no)
			(sheetname "")
		)
		(fill yes
			(thermal_gap 0.5)
			(thermal_bridge_width 0.5)
			(island_removal_mode 0)
		)
		(polygon
			(pts
				(arc
					(start 78.000098 -524.180562)
					(mid 72.869298 -519.049762)
					(end 78.000098 -513.918962)
				)
				(arc
					(start 78.000098 -513.918962)
					(mid 78.050898 -513.969762)
					(end 78.000098 -514.020562)
				)
				(arc
					(start 78.000098 -514.020562)
					(mid 72.970898 -519.049762)
					(end 78.000098 -524.078962)
				)
				(arc
					(start 78.000098 -524.078962)
					(mid 78.050898 -524.129762)
					(end 78.000098 -524.180562)
				)
			)
		)
	)
	(zone
		(layers "In2.Cu" "In3.Cu" "In4.Cu" "In5.Cu")
		(hatch none 0.5)
		(connect_pads
			(clearance 0)
		)
		(min_thickness 0.25)
		(keepout
			(tracks not_allowed)
			(vias allowed)
			(pads allowed)
			(copperpour not_allowed)
			(footprints allowed)
		)
		(placement
			(enabled no)
			(sheetname "")
		)
		(fill yes
			(thermal_gap 0.5)
			(thermal_bridge_width 0.5)
			(island_removal_mode 0)
		)
		(polygon
			(pts
				(arc
					(start 78.000098 -126.330456)
					(mid 72.869298 -121.199656)
					(end 78.000098 -116.068856)
				)
				(arc
					(start 78.000098 -116.068856)
					(mid 78.050898 -116.119656)
					(end 78.000098 -116.170456)
				)
				(arc
					(start 78.000098 -116.170456)
					(mid 72.970898 -121.199656)
					(end 78.000098 -126.228856)
				)
				(arc
					(start 78.000098 -126.228856)
					(mid 78.050898 -126.279656)
					(end 78.000098 -126.330456)
				)
			)
		)
	)
	(zone
		(layers "In2.Cu" "In3.Cu" "In4.Cu" "In5.Cu")
		(hatch none 0.5)
		(connect_pads
			(clearance 0)
		)
		(min_thickness 0.25)
		(keepout
			(tracks not_allowed)
			(vias allowed)
			(pads allowed)
			(copperpour not_allowed)
			(footprints allowed)
		)
		(placement
			(enabled no)
			(sheetname "")
		)
		(fill yes
			(thermal_gap 0.5)
			(thermal_bridge_width 0.5)
			(island_removal_mode 0)
		)
		(polygon
			(pts
				(arc
					(start 78.000098 -435.280562)
					(mid 72.869298 -430.149762)
					(end 78.000098 -425.018962)
				)
				(arc
					(start 78.000098 -425.018962)
					(mid 78.050898 -425.069762)
					(end 78.000098 -425.120562)
				)
				(arc
					(start 78.000098 -425.120562)
					(mid 72.970898 -430.149762)
					(end 78.000098 -435.178962)
				)
				(arc
					(start 78.000098 -435.178962)
					(mid 78.050898 -435.229762)
					(end 78.000098 -435.280562)
				)
			)
		)
	)
	(zone
		(layers "In2.Cu" "In3.Cu" "In4.Cu" "In5.Cu")
		(hatch none 0.5)
		(connect_pads
			(clearance 0)
		)
		(min_thickness 0.25)
		(keepout
			(tracks not_allowed)
			(vias allowed)
			(pads allowed)
			(copperpour not_allowed)
			(footprints allowed)
		)
		(placement
			(enabled no)
			(sheetname "")
		)
		(fill yes
			(thermal_gap 0.5)
			(thermal_bridge_width 0.5)
			(island_removal_mode 0)
		)
		(polygon
			(pts
				(arc
					(start 16.60017 -379.77445)
					(mid 21.62556 -384.79984)
					(end 16.60017 -389.82523)
				)
				(arc
					(start 16.60017 -390.05383)
					(mid 20.315302 -388.514972)
					(end 21.85416 -384.79984)
				)
				(arc
					(start 21.85416 -384.79984)
					(mid 20.315302 -381.084708)
					(end 16.60017 -379.54585)
				)
			)
		)
	)
	(zone
		(layers "In2.Cu" "In3.Cu" "In4.Cu" "In5.Cu")
		(hatch none 0.5)
		(connect_pads
			(clearance 0)
		)
		(min_thickness 0.25)
		(keepout
			(tracks not_allowed)
			(vias allowed)
			(pads allowed)
			(copperpour not_allowed)
			(footprints allowed)
		)
		(placement
			(enabled no)
			(sheetname "")
		)
		(fill yes
			(thermal_gap 0.5)
			(thermal_bridge_width 0.5)
			(island_removal_mode 0)
		)
		(polygon
			(pts
				(arc
					(start 78.000098 -346.380562)
					(mid 83.130898 -341.249762)
					(end 78.000098 -336.118962)
				)
				(arc
					(start 78.000098 -336.118962)
					(mid 77.949298 -336.169762)
					(end 78.000098 -336.220562)
				)
				(arc
					(start 78.000098 -336.220562)
					(mid 83.029298 -341.249762)
					(end 78.000098 -346.278962)
				)
				(arc
					(start 78.000098 -346.278962)
					(mid 77.949298 -346.329762)
					(end 78.000098 -346.380562)
				)
			)
		)
	)
	(zone
		(layers "In2.Cu" "In3.Cu" "In4.Cu" "In5.Cu")
		(hatch none 0.5)
		(connect_pads
			(clearance 0)
		)
		(min_thickness 0.25)
		(keepout
			(tracks not_allowed)
			(vias allowed)
			(pads allowed)
			(copperpour not_allowed)
			(footprints allowed)
		)
		(placement
			(enabled no)
			(sheetname "")
		)
		(fill yes
			(thermal_gap 0.5)
			(thermal_bridge_width 0.5)
			(island_removal_mode 0)
		)
		(polygon
			(pts
				(arc
					(start 16.60017 -468.67445)
					(mid 11.57478 -473.69984)
					(end 16.60017 -478.72523)
				)
				(arc
					(start 16.60017 -478.95383)
					(mid 12.885038 -477.414972)
					(end 11.34618 -473.69984)
				)
				(arc
					(start 11.34618 -473.69984)
					(mid 12.885038 -469.984708)
					(end 16.60017 -468.44585)
				)
			)
		)
	)
	(zone
		(layers "In2.Cu" "In3.Cu" "In4.Cu" "In5.Cu")
		(hatch none 0.5)
		(connect_pads
			(clearance 0)
		)
		(min_thickness 0.25)
		(keepout
			(tracks not_allowed)
			(vias allowed)
			(pads allowed)
			(copperpour not_allowed)
			(footprints allowed)
		)
		(placement
			(enabled no)
			(sheetname "")
		)
		(fill yes
			(thermal_gap 0.5)
			(thermal_bridge_width 0.5)
			(island_removal_mode 0)
		)
		(polygon
			(pts
				(arc
					(start 16.60017 -113.07445)
					(mid 11.57478 -118.09984)
					(end 16.60017 -123.12523)
				)
				(arc
					(start 16.60017 -123.35383)
					(mid 12.885038 -121.814972)
					(end 11.34618 -118.09984)
				)
				(arc
					(start 11.34618 -118.09984)
					(mid 12.885038 -114.384708)
					(end 16.60017 -112.84585)
				)
			)
		)
	)
	(zone
		(layers "In2.Cu" "In3.Cu" "In4.Cu" "In5.Cu")
		(hatch none 0.5)
		(connect_pads
			(clearance 0)
		)
		(min_thickness 0.25)
		(keepout
			(tracks not_allowed)
			(vias allowed)
			(pads allowed)
			(copperpour not_allowed)
			(footprints allowed)
		)
		(placement
			(enabled no)
			(sheetname "")
		)
		(fill yes
			(thermal_gap 0.5)
			(thermal_bridge_width 0.5)
			(island_removal_mode 0)
		)
		(polygon
			(pts
				(arc
					(start 78.000098 -37.430456)
					(mid 72.869298 -32.299656)
					(end 78.000098 -27.168856)
				)
				(arc
					(start 78.000098 -27.168856)
					(mid 78.050898 -27.219656)
					(end 78.000098 -27.270456)
				)
				(arc
					(start 78.000098 -27.270456)
					(mid 72.970898 -32.299656)
					(end 78.000098 -37.328856)
				)
				(arc
					(start 78.000098 -37.328856)
					(mid 78.050898 -37.379656)
					(end 78.000098 -37.430456)
				)
			)
		)
	)
	(zone
		(layers "In2.Cu" "In3.Cu" "In4.Cu" "In5.Cu")
		(hatch none 0.5)
		(connect_pads
			(clearance 0)
		)
		(min_thickness 0.25)
		(keepout
			(tracks not_allowed)
			(vias allowed)
			(pads allowed)
			(copperpour not_allowed)
			(footprints allowed)
		)
		(placement
			(enabled no)
			(sheetname "")
		)
		(fill yes
			(thermal_gap 0.5)
			(thermal_bridge_width 0.5)
			(island_removal_mode 0)
		)
		(polygon
			(pts
				(arc
					(start 16.60017 -379.77445)
					(mid 11.57478 -384.79984)
					(end 16.60017 -389.82523)
				)
				(arc
					(start 16.60017 -390.05383)
					(mid 12.885038 -388.514972)
					(end 11.34618 -384.79984)
				)
				(arc
					(start 11.34618 -384.79984)
					(mid 12.885038 -381.084708)
					(end 16.60017 -379.54585)
				)
			)
		)
	)
	(zone
		(layers "In2.Cu" "In3.Cu" "In4.Cu" "In5.Cu")
		(hatch none 0.5)
		(connect_pads
			(clearance 0)
		)
		(min_thickness 0.25)
		(keepout
			(tracks not_allowed)
			(vias allowed)
			(pads allowed)
			(copperpour not_allowed)
			(footprints allowed)
		)
		(placement
			(enabled no)
			(sheetname "")
		)
		(fill yes
			(thermal_gap 0.5)
			(thermal_bridge_width 0.5)
			(island_removal_mode 0)
		)
		(polygon
			(pts
				(arc
					(start 16.599916 -24.17445)
					(mid 21.625306 -29.19984)
					(end 16.599916 -34.22523)
				)
				(arc
					(start 16.599916 -34.45383)
					(mid 20.315048 -32.914972)
					(end 21.853906 -29.19984)
				)
				(arc
					(start 21.853906 -29.19984)
					(mid 20.315048 -25.484708)
					(end 16.599916 -23.94585)
				)
			)
		)
	)
	(zone
		(layers "In2.Cu" "In3.Cu" "In4.Cu" "In5.Cu")
		(hatch none 0.5)
		(connect_pads
			(clearance 0)
		)
		(min_thickness 0.25)
		(keepout
			(tracks not_allowed)
			(vias allowed)
			(pads allowed)
			(copperpour not_allowed)
			(footprints allowed)
		)
		(placement
			(enabled no)
			(sheetname "")
		)
		(fill yes
			(thermal_gap 0.5)
			(thermal_bridge_width 0.5)
			(island_removal_mode 0)
		)
		(polygon
			(pts
				(arc
					(start 78.000098 -524.180562)
					(mid 83.130898 -519.049762)
					(end 78.000098 -513.918962)
				)
				(arc
					(start 78.000098 -513.918962)
					(mid 77.949298 -513.969762)
					(end 78.000098 -514.020562)
				)
				(arc
					(start 78.000098 -514.020562)
					(mid 83.029298 -519.049762)
					(end 78.000098 -524.078962)
				)
				(arc
					(start 78.000098 -524.078962)
					(mid 77.949298 -524.129762)
					(end 78.000098 -524.180562)
				)
			)
		)
	)
	(zone
		(layers "In2.Cu" "In3.Cu" "In4.Cu" "In5.Cu")
		(hatch none 0.5)
		(connect_pads
			(clearance 0)
		)
		(min_thickness 0.25)
		(keepout
			(tracks not_allowed)
			(vias allowed)
			(pads allowed)
			(copperpour not_allowed)
			(footprints allowed)
		)
		(placement
			(enabled no)
			(sheetname "")
		)
		(fill yes
			(thermal_gap 0.5)
			(thermal_bridge_width 0.5)
			(island_removal_mode 0)
		)
		(polygon
			(pts
				(arc
					(start 78.000098 -215.230456)
					(mid 83.130898 -210.099656)
					(end 78.000098 -204.968856)
				)
				(arc
					(start 78.000098 -204.968856)
					(mid 77.949298 -205.019656)
					(end 78.000098 -205.070456)
				)
				(arc
					(start 78.000098 -205.070456)
					(mid 83.029298 -210.099656)
					(end 78.000098 -215.128856)
				)
				(arc
					(start 78.000098 -215.128856)
					(mid 77.949298 -215.179656)
					(end 78.000098 -215.230456)
				)
			)
		)
	)
	(zone
		(layers "In2.Cu" "In3.Cu" "In4.Cu" "In5.Cu")
		(hatch none 0.5)
		(connect_pads
			(clearance 0)
		)
		(min_thickness 0.25)
		(keepout
			(tracks not_allowed)
			(vias allowed)
			(pads allowed)
			(copperpour not_allowed)
			(footprints allowed)
		)
		(placement
			(enabled no)
			(sheetname "")
		)
		(fill yes
			(thermal_gap 0.5)
			(thermal_bridge_width 0.5)
			(island_removal_mode 0)
		)
		(polygon
			(pts
				(arc
					(start 16.60017 -201.97445)
					(mid 21.62556 -206.99984)
					(end 16.60017 -212.02523)
				)
				(arc
					(start 16.60017 -212.25383)
					(mid 20.315302 -210.714972)
					(end 21.85416 -206.99984)
				)
				(arc
					(start 21.85416 -206.99984)
					(mid 20.315302 -203.284708)
					(end 16.60017 -201.74585)
				)
			)
		)
	)
	(zone
		(layers "In2.Cu" "In3.Cu" "In4.Cu" "In5.Cu")
		(hatch none 0.5)
		(connect_pads
			(clearance 0)
		)
		(min_thickness 0.25)
		(keepout
			(tracks not_allowed)
			(vias allowed)
			(pads allowed)
			(copperpour not_allowed)
			(footprints allowed)
		)
		(placement
			(enabled no)
			(sheetname "")
		)
		(fill yes
			(thermal_gap 0.5)
			(thermal_bridge_width 0.5)
			(island_removal_mode 0)
		)
		(polygon
			(pts
				(arc
					(start 78.000098 -126.330456)
					(mid 83.130898 -121.199656)
					(end 78.000098 -116.068856)
				)
				(arc
					(start 78.000098 -116.068856)
					(mid 77.949298 -116.119656)
					(end 78.000098 -116.170456)
				)
				(arc
					(start 78.000098 -116.170456)
					(mid 83.029298 -121.199656)
					(end 78.000098 -126.228856)
				)
				(arc
					(start 78.000098 -126.228856)
					(mid 77.949298 -126.279656)
					(end 78.000098 -126.330456)
				)
			)
		)
	)
	(zone
		(layers "In2.Cu" "In3.Cu" "In4.Cu" "In5.Cu")
		(hatch none 0.5)
		(connect_pads
			(clearance 0)
		)
		(min_thickness 0.25)
		(keepout
			(tracks not_allowed)
			(vias allowed)
			(pads allowed)
			(copperpour not_allowed)
			(footprints allowed)
		)
		(placement
			(enabled no)
			(sheetname "")
		)
		(fill yes
			(thermal_gap 0.5)
			(thermal_bridge_width 0.5)
			(island_removal_mode 0)
		)
		(polygon
			(pts
				(arc
					(start 16.60017 -468.67445)
					(mid 21.62556 -473.69984)
					(end 16.60017 -478.72523)
				)
				(arc
					(start 16.60017 -478.95383)
					(mid 20.315302 -477.414972)
					(end 21.85416 -473.69984)
				)
				(arc
					(start 21.85416 -473.69984)
					(mid 20.315302 -469.984708)
					(end 16.60017 -468.44585)
				)
			)
		)
	)
)
